(kicad_pcb
	(version 20260206)
	(generator "pcbnew")
	(generator_version "10.0")
	(general
		(thickness 1.6)
		(legacy_teardrops no)
	)
	(paper "A4")
	(layers
		(0 "F.Cu" signal "TOP")
		(4 "In1.Cu" signal "L2GND")
		(6 "In2.Cu" signal "L3")
		(8 "In3.Cu" signal "L4GND")
		(10 "In4.Cu" signal "L5")
		(12 "In5.Cu" signal "L6GND")
		(14 "In6.Cu" signal "L7VCC")
		(16 "In7.Cu" signal "L8VCC")
		(18 "In8.Cu" signal "L9GND")
		(20 "In9.Cu" signal "L10")
		(22 "In10.Cu" signal "L11GND")
		(24 "In11.Cu" signal "L12")
		(26 "In12.Cu" signal "L13GND")
		(2 "B.Cu" signal "BOTTOM")
		(9 "F.Adhes" user "F.Adhesive")
		(11 "B.Adhes" user "B.Adhesive")
		(13 "F.Paste" user "Package Geometry/Pastemask Top")
		(15 "B.Paste" user "Package Geometry/Pastemask Bottom")
		(5 "F.SilkS" user "Ref Des/Silkscreen Top")
		(7 "B.SilkS" user "Ref Des/Silkscreen Bottom")
		(1 "F.Mask" user "Board Geometry/Soldermask Top")
		(3 "B.Mask" user "Board Geometry/Soldermask Bottom")
		(17 "Dwgs.User" user "User.Drawings")
		(19 "Cmts.User" user "User.Comments")
		(21 "Eco1.User" user "User.Eco1")
		(23 "Eco2.User" user "User.Eco2")
		(25 "Edge.Cuts" user "Board Geometry/Outline")
		(27 "Margin" user)
		(31 "F.CrtYd" user "Package Geometry/Place Bound Top")
		(29 "B.CrtYd" user "Package Geometry/Place Bound Bottom")
		(35 "F.Fab" user "Ref Des/Assembly Top")
		(33 "B.Fab" user "Ref Des/Assembly Bottom")
	)
	(setup
		(pad_to_mask_clearance 0)
		(allow_soldermask_bridges_in_footprints no)
		(tenting
			(front yes)
			(back yes)
		)
		(covering
			(front no)
			(back no)
		)
		(plugging
			(front no)
			(back no)
		)
		(capping no)
		(filling no)
		(pcbplotparams
			(layerselection 0x00000000_00000000_55555555_5755f5ff)
			(plot_on_all_layers_selection 0x00000000_00000000_00000000_00000000)
			(disableapertmacros no)
			(usegerberextensions no)
			(usegerberattributes yes)
			(usegerberadvancedattributes yes)
			(creategerberjobfile yes)
			(dashed_line_dash_ratio 12)
			(dashed_line_gap_ratio 3)
			(svgprecision 4)
			(plotframeref no)
			(mode 1)
			(useauxorigin no)
			(pdf_front_fp_property_popups yes)
			(pdf_back_fp_property_popups yes)
			(pdf_metadata yes)
			(pdf_single_document no)
			(dxfpolygonmode yes)
			(dxfimperialunits yes)
			(dxfusepcbnewfont yes)
			(psnegative no)
			(psa4output no)
			(plot_black_and_white yes)
			(sketchpadsonfab no)
			(plotpadnumbers no)
			(hidednponfab no)
			(sketchdnponfab yes)
			(crossoutdnponfab yes)
			(subtractmaskfromsilk no)
			(outputformat 1)
			(mirror no)
			(drillshape 1)
			(scaleselection 1)
			(outputdirectory "")
		)
	)
	(zone
		(layer "In12.Cu")
		(hatch none 0.5)
		(connect_pads
			(clearance 0)
		)
		(min_thickness 0.25)
		(keepout
			(tracks not_allowed)
			(vias allowed)
			(pads allowed)
			(copperpour not_allowed)
			(footprints allowed)
		)
		(placement
			(enabled no)
			(sheetname "")
		)
		(fill
			(thermal_gap 0.5)
			(thermal_bridge_width 0.5)
			(island_removal_mode 0)
		)
		(polygon
			(pts
				(xy 204.620368 -9.721342) (xy 205.179168 -9.721342) (xy 205.179168 -11.524742) (xy 204.620368 -11.524742)
			)
		)
	)
	(zone
		(layer "In12.Cu")
		(hatch none 0.5)
		(connect_pads
			(clearance 0)
		)
		(min_thickness 0.25)
		(keepout
			(tracks not_allowed)
			(vias allowed)
			(pads allowed)
			(copperpour not_allowed)
			(footprints allowed)
		)
		(placement
			(enabled no)
			(sheetname "")
		)
		(fill
			(thermal_gap 0.5)
			(thermal_bridge_width 0.5)
			(island_removal_mode 0)
		)
		(polygon
			(pts
				(xy 31.969964 -127.374142) (xy 32.528764 -127.374142) (xy 32.528764 -129.177542) (xy 31.969964 -129.177542)
			)
		)
	)
	(zone
		(layer "In12.Cu")
		(hatch none 0.5)
		(connect_pads
			(clearance 0)
		)
		(min_thickness 0.25)
		(keepout
			(tracks not_allowed)
			(vias allowed)
			(pads allowed)
			(copperpour not_allowed)
			(footprints allowed)
		)
		(placement
			(enabled no)
			(sheetname "")
		)
		(fill
			(thermal_gap 0.5)
			(thermal_bridge_width 0.5)
			(island_removal_mode 0)
		)
		(polygon
			(pts
				(xy 116.970048 -136.975342) (xy 117.528848 -136.975342) (xy 117.528848 -138.778742) (xy 116.970048 -138.778742)
			)
		)
	)
	(zone
		(layer "In12.Cu")
		(hatch none 0.5)
		(connect_pads
			(clearance 0)
		)
		(min_thickness 0.25)
		(keepout
			(tracks not_allowed)
			(vias allowed)
			(pads allowed)
			(copperpour not_allowed)
			(footprints allowed)
		)
		(placement
			(enabled no)
			(sheetname "")
		)
		(fill
			(thermal_gap 0.5)
			(thermal_bridge_width 0.5)
			(island_removal_mode 0)
		)
		(polygon
			(pts
				(xy 118.67007 -9.721342) (xy 119.22887 -9.721342) (xy 119.22887 -11.524742) (xy 118.67007 -11.524742)
			)
		)
	)
	(zone
		(layer "In12.Cu")
		(hatch none 0.5)
		(connect_pads
			(clearance 0)
		)
		(min_thickness 0.25)
		(keepout
			(tracks not_allowed)
			(vias allowed)
			(pads allowed)
			(copperpour not_allowed)
			(footprints allowed)
		)
		(placement
			(enabled no)
			(sheetname "")
		)
		(fill
			(thermal_gap 0.5)
			(thermal_bridge_width 0.5)
			(island_removal_mode 0)
		)
		(polygon
			(pts
				(xy 106.77017 -23.922482) (xy 107.32897 -23.922482) (xy 107.32897 -25.725882) (xy 106.77017 -25.725882)
			)
		)
	)
	(zone
		(net "PVDDQ_GHJ")
		(layer "In12.Cu")
		(hatch none 0.5)
		(connect_pads
			(clearance 0.5)
		)
		(min_thickness 0.25)
		(fill yes
			(thermal_gap 0.5)
			(thermal_bridge_width 0.5)
			(island_removal_mode 0)
		)
		(polygon
			(pts
				(xy 100.129594 -11.5189) (xy 99.9871 -11.661394) (xy 99.9871 -12.849606) (xy 100.104194 -12.9667)
				(xy 102.714806 -12.9667) (xy 103.349806 -12.3317) (xy 103.832406 -12.3317) (xy 103.9495 -12.214606)
				(xy 103.9495 -11.712194) (xy 103.756206 -11.5189)
			)
		)
	)
	(zone
		(layer "In12.Cu")
		(hatch none 0.5)
		(connect_pads
			(clearance 0)
		)
		(min_thickness 0.25)
		(keepout
			(tracks not_allowed)
			(vias allowed)
			(pads allowed)
			(copperpour not_allowed)
			(footprints allowed)
		)
		(placement
			(enabled no)
			(sheetname "")
		)
		(fill
			(thermal_gap 0.5)
			(thermal_bridge_width 0.5)
			(island_removal_mode 0)
		)
		(polygon
			(pts
				(xy 307.470302 -23.922482) (xy 308.029102 -23.922482) (xy 308.029102 -25.725882) (xy 307.470302 -25.725882)
			)
		)
	)
	(zone
		(layer "In12.Cu")
		(hatch none 0.5)
		(connect_pads
			(clearance 0)
		)
		(min_thickness 0.25)
		(keepout
			(tracks not_allowed)
			(vias allowed)
			(pads allowed)
			(copperpour not_allowed)
			(footprints allowed)
		)
		(placement
			(enabled no)
			(sheetname "")
		)
		(fill
			(thermal_gap 0.5)
			(thermal_bridge_width 0.5)
			(island_removal_mode 0)
		)
		(polygon
			(pts
				(xy 279.42032 -23.922482) (xy 279.97912 -23.922482) (xy 279.97912 -25.725882) (xy 279.42032 -25.725882)
			)
		)
	)
	(zone
		(layer "In12.Cu")
		(hatch none 0.5)
		(connect_pads
			(clearance 0)
		)
		(min_thickness 0.25)
		(keepout
			(tracks not_allowed)
			(vias allowed)
			(pads allowed)
			(copperpour not_allowed)
			(footprints allowed)
		)
		(placement
			(enabled no)
			(sheetname "")
		)
		(fill
			(thermal_gap 0.5)
			(thermal_bridge_width 0.5)
			(island_removal_mode 0)
		)
		(polygon
			(pts
				(xy 210.570572 -9.721342) (xy 211.129372 -9.721342) (xy 211.129372 -11.524742) (xy 210.570572 -11.524742)
			)
		)
	)
	(zone
		(layer "In12.Cu")
		(hatch none 0.5)
		(connect_pads
			(clearance 0)
		)
		(min_thickness 0.25)
		(keepout
			(tracks not_allowed)
			(vias allowed)
			(pads allowed)
			(copperpour not_allowed)
			(footprints allowed)
		)
		(placement
			(enabled no)
			(sheetname "")
		)
		(fill
			(thermal_gap 0.5)
			(thermal_bridge_width 0.5)
			(island_removal_mode 0)
		)
		(polygon
			(pts
				(xy 310.870346 -131.974082) (xy 311.429146 -131.974082) (xy 311.429146 -133.777482) (xy 310.870346 -133.777482)
			)
		)
	)
	(zone
		(layer "In12.Cu")
		(hatch none 0.5)
		(connect_pads
			(clearance 0)
		)
		(min_thickness 0.25)
		(keepout
			(tracks not_allowed)
			(vias allowed)
			(pads allowed)
			(copperpour not_allowed)
			(footprints allowed)
		)
		(placement
			(enabled no)
			(sheetname "")
		)
		(fill
			(thermal_gap 0.5)
			(thermal_bridge_width 0.5)
			(island_removal_mode 0)
		)
		(polygon
			(pts
				(xy 208.87055 -151.176482) (xy 209.42935 -151.176482) (xy 209.42935 -152.979882) (xy 208.87055 -152.979882)
			)
		)
	)
	(zone
		(layer "In12.Cu")
		(hatch none 0.5)
		(connect_pads
			(clearance 0)
		)
		(min_thickness 0.25)
		(keepout
			(tracks not_allowed)
			(vias allowed)
			(pads allowed)
			(copperpour not_allowed)
			(footprints allowed)
		)
		(placement
			(enabled no)
			(sheetname "")
		)
		(fill
			(thermal_gap 0.5)
			(thermal_bridge_width 0.5)
			(island_removal_mode 0)
		)
		(polygon
			(pts
				(xy 209.720434 -0.120142) (xy 210.279234 -0.120142) (xy 210.279234 -1.923542) (xy 209.720434 -1.923542)
			)
		)
	)
	(zone
		(layer "In12.Cu")
		(hatch none 0.5)
		(connect_pads
			(clearance 0)
		)
		(min_thickness 0.25)
		(keepout
			(tracks not_allowed)
			(vias allowed)
			(pads allowed)
			(copperpour not_allowed)
			(footprints allowed)
		)
		(placement
			(enabled no)
			(sheetname "")
		)
		(fill
			(thermal_gap 0.5)
			(thermal_bridge_width 0.5)
			(island_removal_mode 0)
		)
		(polygon
			(pts
				(xy 197.820534 -131.974082) (xy 198.379334 -131.974082) (xy 198.379334 -133.777482) (xy 197.820534 -133.777482)
			)
		)
	)
	(zone
		(layer "In12.Cu")
		(hatch none 0.5)
		(connect_pads
			(clearance 0)
		)
		(min_thickness 0.25)
		(keepout
			(tracks not_allowed)
			(vias allowed)
			(pads allowed)
			(copperpour not_allowed)
			(footprints allowed)
		)
		(placement
			(enabled no)
			(sheetname "")
		)
		(fill
			(thermal_gap 0.5)
			(thermal_bridge_width 0.5)
			(island_removal_mode 0)
		)
		(polygon
			(pts
				(xy 235.22051 -23.922482) (xy 235.77931 -23.922482) (xy 235.77931 -25.725882) (xy 235.22051 -25.725882)
			)
		)
	)
	(zone
		(layer "In12.Cu")
		(hatch none 0.5)
		(connect_pads
			(clearance 0)
		)
		(min_thickness 0.25)
		(keepout
			(tracks not_allowed)
			(vias allowed)
			(pads allowed)
			(copperpour not_allowed)
			(footprints allowed)
		)
		(placement
			(enabled no)
			(sheetname "")
		)
		(fill
			(thermal_gap 0.5)
			(thermal_bridge_width 0.5)
			(island_removal_mode 0)
		)
		(polygon
			(pts
				(xy 87.220044 -9.721342) (xy 87.778844 -9.721342) (xy 87.778844 -11.524742) (xy 87.220044 -11.524742)
			)
		)
	)
	(zone
		(layer "In12.Cu")
		(hatch none 0.5)
		(connect_pads
			(clearance 0)
		)
		(min_thickness 0.25)
		(keepout
			(tracks not_allowed)
			(vias allowed)
			(pads allowed)
			(copperpour not_allowed)
			(footprints allowed)
		)
		(placement
			(enabled no)
			(sheetname "")
		)
		(fill
			(thermal_gap 0.5)
			(thermal_bridge_width 0.5)
			(island_removal_mode 0)
		)
		(polygon
			(pts
				(xy 41.319958 -19.322542) (xy 41.878758 -19.322542) (xy 41.878758 -21.125942) (xy 41.319958 -21.125942)
			)
		)
	)
	(zone
		(layer "In12.Cu")
		(hatch none 0.5)
		(connect_pads
			(clearance 0)
		)
		(min_thickness 0.25)
		(keepout
			(tracks not_allowed)
			(vias allowed)
			(pads allowed)
			(copperpour not_allowed)
			(footprints allowed)
		)
		(placement
			(enabled no)
			(sheetname "")
		)
		(fill
			(thermal_gap 0.5)
			(thermal_bridge_width 0.5)
			(island_removal_mode 0)
		)
		(polygon
			(pts
				(xy 311.720484 -4.720082) (xy 312.279284 -4.720082) (xy 312.279284 -6.523482) (xy 311.720484 -6.523482)
			)
		)
	)
	(zone
		(layer "In12.Cu")
		(hatch none 0.5)
		(connect_pads
			(clearance 0)
		)
		(min_thickness 0.25)
		(keepout
			(tracks not_allowed)
			(vias allowed)
			(pads allowed)
			(copperpour not_allowed)
			(footprints allowed)
		)
		(placement
			(enabled no)
			(sheetname "")
		)
		(fill
			(thermal_gap 0.5)
			(thermal_bridge_width 0.5)
			(island_removal_mode 0)
		)
		(polygon
			(pts
				(xy 293.020496 -127.374142) (xy 293.579296 -127.374142) (xy 293.579296 -129.177542) (xy 293.020496 -129.177542)
			)
		)
	)
	(zone
		(layer "In12.Cu")
		(hatch none 0.5)
		(connect_pads
			(clearance 0)
		)
		(min_thickness 0.25)
		(keepout
			(tracks not_allowed)
			(vias allowed)
			(pads allowed)
			(copperpour not_allowed)
			(footprints allowed)
		)
		(placement
			(enabled no)
			(sheetname "")
		)
		(fill
			(thermal_gap 0.5)
			(thermal_bridge_width 0.5)
			(island_removal_mode 0)
		)
		(polygon
			(pts
				(xy 350.278192 -76.691236) (xy 350.278192 -78.977236) (xy 349.770192 -78.977236) (xy 349.770192 -76.691236)
			)
		)
	)
	(zone
		(layer "In12.Cu")
		(hatch none 0.5)
		(connect_pads
			(clearance 0)
		)
		(min_thickness 0.25)
		(keepout
			(tracks not_allowed)
			(vias allowed)
			(pads allowed)
			(copperpour not_allowed)
			(footprints allowed)
		)
		(placement
			(enabled no)
			(sheetname "")
		)
		(fill
			(thermal_gap 0.5)
			(thermal_bridge_width 0.5)
			(island_removal_mode 0)
		)
		(polygon
			(pts
				(xy 256.470404 -127.374142) (xy 257.029204 -127.374142) (xy 257.029204 -129.177542) (xy 256.470404 -129.177542)
			)
		)
	)
	(zone
		(layer "In12.Cu")
		(hatch none 0.5)
		(connect_pads
			(clearance 0)
		)
		(min_thickness 0.25)
		(keepout
			(tracks not_allowed)
			(vias allowed)
			(pads allowed)
			(copperpour not_allowed)
			(footprints allowed)
		)
		(placement
			(enabled no)
			(sheetname "")
		)
		(fill
			(thermal_gap 0.5)
			(thermal_bridge_width 0.5)
			(island_removal_mode 0)
		)
		(polygon
			(pts
				(xy 218.220544 -14.321282) (xy 218.779344 -14.321282) (xy 218.779344 -16.124682) (xy 218.220544 -16.124682)
			)
		)
	)
	(zone
		(layer "In12.Cu")
		(hatch none 0.5)
		(connect_pads
			(clearance 0)
		)
		(min_thickness 0.25)
		(keepout
			(tracks not_allowed)
			(vias allowed)
			(pads allowed)
			(copperpour not_allowed)
			(footprints allowed)
		)
		(placement
			(enabled no)
			(sheetname "")
		)
		(fill
			(thermal_gap 0.5)
			(thermal_bridge_width 0.5)
			(island_removal_mode 0)
		)
		(polygon
			(pts
				(xy 298.970446 -9.721342) (xy 299.529246 -9.721342) (xy 299.529246 -11.524742) (xy 298.970446 -11.524742)
			)
		)
	)
	(zone
		(layer "In12.Cu")
		(hatch none 0.5)
		(connect_pads
			(clearance 0)
		)
		(min_thickness 0.25)
		(keepout
			(tracks not_allowed)
			(vias allowed)
			(pads allowed)
			(copperpour not_allowed)
			(footprints allowed)
		)
		(placement
			(enabled no)
			(sheetname "")
		)
		(fill
			(thermal_gap 0.5)
			(thermal_bridge_width 0.5)
			(island_removal_mode 0)
		)
		(polygon
			(pts
				(xy 101.670104 -127.374142) (xy 102.228904 -127.374142) (xy 102.228904 -129.177542) (xy 101.670104 -129.177542)
			)
		)
	)
	(zone
		(layer "In12.Cu")
		(hatch none 0.5)
		(connect_pads
			(clearance 0)
		)
		(min_thickness 0.25)
		(keepout
			(tracks not_allowed)
			(vias allowed)
			(pads allowed)
			(copperpour not_allowed)
			(footprints allowed)
		)
		(placement
			(enabled no)
			(sheetname "")
		)
		(fill
			(thermal_gap 0.5)
			(thermal_bridge_width 0.5)
			(island_removal_mode 0)
		)
		(polygon
			(pts
				(xy 199.520556 -4.720082) (xy 200.079356 -4.720082) (xy 200.079356 -6.523482) (xy 199.520556 -6.523482)
			)
		)
	)
	(zone
		(layer "In12.Cu")
		(hatch none 0.5)
		(connect_pads
			(clearance 0)
		)
		(min_thickness 0.25)
		(keepout
			(tracks not_allowed)
			(vias allowed)
			(pads allowed)
			(copperpour not_allowed)
			(footprints allowed)
		)
		(placement
			(enabled no)
			(sheetname "")
		)
		(fill
			(thermal_gap 0.5)
			(thermal_bridge_width 0.5)
			(island_removal_mode 0)
		)
		(polygon
			(pts
				(xy 246.270526 -131.974082) (xy 246.829326 -131.974082) (xy 246.829326 -133.777482) (xy 246.270526 -133.777482)
			)
		)
	)
	(zone
		(layer "In12.Cu")
		(hatch none 0.5)
		(connect_pads
			(clearance 0)
		)
		(min_thickness 0.25)
		(keepout
			(tracks not_allowed)
			(vias allowed)
			(pads allowed)
			(copperpour not_allowed)
			(footprints allowed)
		)
		(placement
			(enabled no)
			(sheetname "")
		)
		(fill
			(thermal_gap 0.5)
			(thermal_bridge_width 0.5)
			(island_removal_mode 0)
		)
		(polygon
			(pts
				(xy 47.270162 -136.975342) (xy 47.828962 -136.975342) (xy 47.828962 -138.778742) (xy 47.270162 -138.778742)
			)
		)
	)
	(zone
		(layer "In12.Cu")
		(hatch none 0.5)
		(connect_pads
			(clearance 0)
		)
		(min_thickness 0.25)
		(keepout
			(tracks not_allowed)
			(vias allowed)
			(pads allowed)
			(copperpour not_allowed)
			(footprints allowed)
		)
		(placement
			(enabled no)
			(sheetname "")
		)
		(fill
			(thermal_gap 0.5)
			(thermal_bridge_width 0.5)
			(island_removal_mode 0)
		)
		(polygon
			(pts
				(xy 91.469972 -4.720082) (xy 92.028772 -4.720082) (xy 92.028772 -6.523482) (xy 91.469972 -6.523482)
			)
		)
	)
	(zone
		(layer "In12.Cu")
		(hatch none 0.5)
		(connect_pads
			(clearance 0)
		)
		(min_thickness 0.25)
		(keepout
			(tracks not_allowed)
			(vias allowed)
			(pads allowed)
			(copperpour not_allowed)
			(footprints allowed)
		)
		(placement
			(enabled no)
			(sheetname "")
		)
		(fill
			(thermal_gap 0.5)
			(thermal_bridge_width 0.5)
			(island_removal_mode 0)
		)
		(polygon
			(pts
				(xy 53.220112 -141.575282) (xy 53.778912 -141.575282) (xy 53.778912 -143.378682) (xy 53.220112 -143.378682)
			)
		)
	)
	(zone
		(layer "In12.Cu")
		(hatch none 0.5)
		(connect_pads
			(clearance 0)
		)
		(min_thickness 0.25)
		(keepout
			(tracks not_allowed)
			(vias allowed)
			(pads allowed)
			(copperpour not_allowed)
			(footprints allowed)
		)
		(placement
			(enabled no)
			(sheetname "")
		)
		(fill
			(thermal_gap 0.5)
			(thermal_bridge_width 0.5)
			(island_removal_mode 0)
		)
		(polygon
			(pts
				(xy 302.37049 -14.321282) (xy 302.92929 -14.321282) (xy 302.92929 -16.124682) (xy 302.37049 -16.124682)
			)
		)
	)
	(zone
		(layer "In12.Cu")
		(hatch none 0.5)
		(connect_pads
			(clearance 0)
		)
		(min_thickness 0.25)
		(keepout
			(tracks not_allowed)
			(vias allowed)
			(pads allowed)
			(copperpour not_allowed)
			(footprints allowed)
		)
		(placement
			(enabled no)
			(sheetname "")
		)
		(fill
			(thermal_gap 0.5)
			(thermal_bridge_width 0.5)
			(island_removal_mode 0)
		)
		(polygon
			(pts
				(xy 73.620122 -19.322542) (xy 74.178922 -19.322542) (xy 74.178922 -21.125942) (xy 73.620122 -21.125942)
			)
		)
	)
	(zone
		(layer "In12.Cu")
		(hatch none 0.5)
		(connect_pads
			(clearance 0)
		)
		(min_thickness 0.25)
		(keepout
			(tracks not_allowed)
			(vias allowed)
			(pads allowed)
			(copperpour not_allowed)
			(footprints allowed)
		)
		(placement
			(enabled no)
			(sheetname "")
		)
		(fill
			(thermal_gap 0.5)
			(thermal_bridge_width 0.5)
			(island_removal_mode 0)
		)
		(polygon
			(pts
				(xy 271.770602 -4.720082) (xy 272.329402 -4.720082) (xy 272.329402 -6.523482) (xy 271.770602 -6.523482)
			)
		)
	)
	(zone
		(layer "In12.Cu")
		(hatch none 0.5)
		(connect_pads
			(clearance 0)
		)
		(min_thickness 0.25)
		(keepout
			(tracks not_allowed)
			(vias allowed)
			(pads allowed)
			(copperpour not_allowed)
			(footprints allowed)
		)
		(placement
			(enabled no)
			(sheetname "")
		)
		(fill
			(thermal_gap 0.5)
			(thermal_bridge_width 0.5)
			(island_removal_mode 0)
		)
		(polygon
			(pts
				(xy 126.320042 -146.576542) (xy 126.878842 -146.576542) (xy 126.878842 -148.379942) (xy 126.320042 -148.379942)
			)
		)
	)
	(zone
		(layer "In12.Cu")
		(hatch none 0.5)
		(connect_pads
			(clearance 0)
		)
		(min_thickness 0.25)
		(keepout
			(tracks not_allowed)
			(vias allowed)
			(pads allowed)
			(copperpour not_allowed)
			(footprints allowed)
		)
		(placement
			(enabled no)
			(sheetname "")
		)
		(fill
			(thermal_gap 0.5)
			(thermal_bridge_width 0.5)
			(island_removal_mode 0)
		)
		(polygon
			(pts
				(xy 257.320542 -146.576542) (xy 257.879342 -146.576542) (xy 257.879342 -148.379942) (xy 257.320542 -148.379942)
			)
		)
	)
	(zone
		(layer "In12.Cu")
		(hatch none 0.5)
		(connect_pads
			(clearance 0)
		)
		(min_thickness 0.25)
		(keepout
			(tracks not_allowed)
			(vias allowed)
			(pads allowed)
			(copperpour not_allowed)
			(footprints allowed)
		)
		(placement
			(enabled no)
			(sheetname "")
		)
		(fill
			(thermal_gap 0.5)
			(thermal_bridge_width 0.5)
			(island_removal_mode 0)
		)
		(polygon
			(pts
				(xy 79.570072 -4.720082) (xy 80.128872 -4.720082) (xy 80.128872 -6.523482) (xy 79.570072 -6.523482)
			)
		)
	)
	(zone
		(layer "In12.Cu")
		(hatch none 0.5)
		(connect_pads
			(clearance 0)
		)
		(min_thickness 0.25)
		(keepout
			(tracks not_allowed)
			(vias allowed)
			(pads allowed)
			(copperpour not_allowed)
			(footprints allowed)
		)
		(placement
			(enabled no)
			(sheetname "")
		)
		(fill
			(thermal_gap 0.5)
			(thermal_bridge_width 0.5)
			(island_removal_mode 0)
		)
		(polygon
			(pts
				(xy 231.820466 -131.974082) (xy 232.379266 -131.974082) (xy 232.379266 -133.777482) (xy 231.820466 -133.777482)
			)
		)
	)
	(zone
		(layer "In12.Cu")
		(hatch none 0.5)
		(connect_pads
			(clearance 0)
		)
		(min_thickness 0.25)
		(keepout
			(tracks not_allowed)
			(vias allowed)
			(pads allowed)
			(copperpour not_allowed)
			(footprints allowed)
		)
		(placement
			(enabled no)
			(sheetname "")
		)
		(fill
			(thermal_gap 0.5)
			(thermal_bridge_width 0.5)
			(island_removal_mode 0)
		)
		(polygon
			(pts
				(xy 315.970412 -136.975342) (xy 316.529212 -136.975342) (xy 316.529212 -138.778742) (xy 315.970412 -138.778742)
			)
		)
	)
	(zone
		(layer "In12.Cu")
		(hatch none 0.5)
		(connect_pads
			(clearance 0)
		)
		(min_thickness 0.25)
		(keepout
			(tracks not_allowed)
			(vias allowed)
			(pads allowed)
			(copperpour not_allowed)
			(footprints allowed)
		)
		(placement
			(enabled no)
			(sheetname "")
		)
		(fill
			(thermal_gap 0.5)
			(thermal_bridge_width 0.5)
			(island_removal_mode 0)
		)
		(polygon
			(pts
				(xy 72.769984 -136.975342) (xy 73.328784 -136.975342) (xy 73.328784 -138.778742) (xy 72.769984 -138.778742)
			)
		)
	)
	(zone
		(layer "In12.Cu")
		(hatch none 0.5)
		(connect_pads
			(clearance 0)
		)
		(min_thickness 0.25)
		(keepout
			(tracks not_allowed)
			(vias allowed)
			(pads allowed)
			(copperpour not_allowed)
			(footprints allowed)
		)
		(placement
			(enabled no)
			(sheetname "")
		)
		(fill
			(thermal_gap 0.5)
			(thermal_bridge_width 0.5)
			(island_removal_mode 0)
		)
		(polygon
			(pts
				(xy 420.5732 -155.448) (xy 420.5732 -156.21) (xy 421.5638 -156.21) (xy 421.5638 -155.448)
			)
		)
	)
	(zone
		(layer "In12.Cu")
		(hatch none 0.5)
		(connect_pads
			(clearance 0)
		)
		(min_thickness 0.25)
		(keepout
			(tracks not_allowed)
			(vias allowed)
			(pads allowed)
			(copperpour not_allowed)
			(footprints allowed)
		)
		(placement
			(enabled no)
			(sheetname "")
		)
		(fill
			(thermal_gap 0.5)
			(thermal_bridge_width 0.5)
			(island_removal_mode 0)
		)
		(polygon
			(pts
				(xy 270.07058 -23.922482) (xy 270.62938 -23.922482) (xy 270.62938 -25.725882) (xy 270.07058 -25.725882)
			)
		)
	)
	(zone
		(layer "In12.Cu")
		(hatch none 0.5)
		(connect_pads
			(clearance 0)
		)
		(min_thickness 0.25)
		(keepout
			(tracks not_allowed)
			(vias allowed)
			(pads allowed)
			(copperpour not_allowed)
			(footprints allowed)
		)
		(placement
			(enabled no)
			(sheetname "")
		)
		(fill
			(thermal_gap 0.5)
			(thermal_bridge_width 0.5)
			(island_removal_mode 0)
		)
		(polygon
			(pts
				(xy 224.170494 -23.922482) (xy 224.729294 -23.922482) (xy 224.729294 -25.725882) (xy 224.170494 -25.725882)
			)
		)
	)
	(zone
		(layer "In12.Cu")
		(hatch none 0.5)
		(connect_pads
			(clearance 0)
		)
		(min_thickness 0.25)
		(keepout
			(tracks not_allowed)
			(vias allowed)
			(pads allowed)
			(copperpour not_allowed)
			(footprints allowed)
		)
		(placement
			(enabled no)
			(sheetname "")
		)
		(fill
			(thermal_gap 0.5)
			(thermal_bridge_width 0.5)
			(island_removal_mode 0)
		)
		(polygon
			(pts
				(xy 144.169892 -4.720082) (xy 144.728692 -4.720082) (xy 144.728692 -6.523482) (xy 144.169892 -6.523482)
			)
		)
	)
	(zone
		(layer "In12.Cu")
		(hatch none 0.5)
		(connect_pads
			(clearance 0)
		)
		(min_thickness 0.25)
		(keepout
			(tracks not_allowed)
			(vias allowed)
			(pads allowed)
			(copperpour not_allowed)
			(footprints allowed)
		)
		(placement
			(enabled no)
			(sheetname "")
		)
		(fill
			(thermal_gap 0.5)
			(thermal_bridge_width 0.5)
			(island_removal_mode 0)
		)
		(polygon
			(pts
				(xy 58.319924 -146.576542) (xy 58.878724 -146.576542) (xy 58.878724 -148.379942) (xy 58.319924 -148.379942)
			)
		)
	)
	(zone
		(layer "In12.Cu")
		(hatch none 0.5)
		(connect_pads
			(clearance 0)
		)
		(min_thickness 0.25)
		(keepout
			(tracks not_allowed)
			(vias allowed)
			(pads allowed)
			(copperpour not_allowed)
			(footprints allowed)
		)
		(placement
			(enabled no)
			(sheetname "")
		)
		(fill
			(thermal_gap 0.5)
			(thermal_bridge_width 0.5)
			(island_removal_mode 0)
		)
		(polygon
			(pts
				(xy 247.12041 -19.322542) (xy 247.67921 -19.322542) (xy 247.67921 -21.125942) (xy 247.12041 -21.125942)
			)
		)
	)
	(zone
		(layer "In12.Cu")
		(hatch none 0.5)
		(connect_pads
			(clearance 0)
		)
		(min_thickness 0.25)
		(keepout
			(tracks not_allowed)
			(vias allowed)
			(pads allowed)
			(copperpour not_allowed)
			(footprints allowed)
		)
		(placement
			(enabled no)
			(sheetname "")
		)
		(fill
			(thermal_gap 0.5)
			(thermal_bridge_width 0.5)
			(island_removal_mode 0)
		)
		(polygon
			(pts
				(xy 254.770382 -19.322542) (xy 255.329182 -19.322542) (xy 255.329182 -21.125942) (xy 254.770382 -21.125942)
			)
		)
	)
	(zone
		(layer "In12.Cu")
		(hatch none 0.5)
		(connect_pads
			(clearance 0)
		)
		(min_thickness 0.25)
		(keepout
			(tracks not_allowed)
			(vias allowed)
			(pads allowed)
			(copperpour not_allowed)
			(footprints allowed)
		)
		(placement
			(enabled no)
			(sheetname "")
		)
		(fill
			(thermal_gap 0.5)
			(thermal_bridge_width 0.5)
			(island_removal_mode 0)
		)
		(polygon
			(pts
				(xy 354.555806 -59.225434) (xy 354.555806 -61.511434) (xy 354.047806 -61.511434) (xy 354.047806 -59.225434)
			)
		)
	)
	(zone
		(layer "In12.Cu")
		(hatch none 0.5)
		(connect_pads
			(clearance 0)
		)
		(min_thickness 0.25)
		(keepout
			(tracks not_allowed)
			(vias allowed)
			(pads allowed)
			(copperpour not_allowed)
			(footprints allowed)
		)
		(placement
			(enabled no)
			(sheetname "")
		)
		(fill
			(thermal_gap 0.5)
			(thermal_bridge_width 0.5)
			(island_removal_mode 0)
		)
		(polygon
			(pts
				(xy 254.770382 -9.721342) (xy 255.329182 -9.721342) (xy 255.329182 -11.524742) (xy 254.770382 -11.524742)
			)
		)
	)
	(zone
		(layer "In12.Cu")
		(hatch none 0.5)
		(connect_pads
			(clearance 0)
		)
		(min_thickness 0.25)
		(keepout
			(tracks not_allowed)
			(vias allowed)
			(pads allowed)
			(copperpour not_allowed)
			(footprints allowed)
		)
		(placement
			(enabled no)
			(sheetname "")
		)
		(fill
			(thermal_gap 0.5)
			(thermal_bridge_width 0.5)
			(island_removal_mode 0)
		)
		(polygon
			(pts
				(xy 136.51992 -14.321282) (xy 137.07872 -14.321282) (xy 137.07872 -16.124682) (xy 136.51992 -16.124682)
			)
		)
	)
	(zone
		(layer "In12.Cu")
		(hatch none 0.5)
		(connect_pads
			(clearance 0)
		)
		(min_thickness 0.25)
		(keepout
			(tracks not_allowed)
			(vias allowed)
			(pads allowed)
			(copperpour not_allowed)
			(footprints allowed)
		)
		(placement
			(enabled no)
			(sheetname "")
		)
		(fill
			(thermal_gap 0.5)
			(thermal_bridge_width 0.5)
			(island_removal_mode 0)
		)
		(polygon
			(pts
				(xy 309.170324 -141.575282) (xy 309.729124 -141.575282) (xy 309.729124 -143.378682) (xy 309.170324 -143.378682)
			)
		)
	)
	(zone
		(layer "In12.Cu")
		(hatch none 0.5)
		(connect_pads
			(clearance 0)
		)
		(min_thickness 0.25)
		(keepout
			(tracks not_allowed)
			(vias allowed)
			(pads allowed)
			(copperpour not_allowed)
			(footprints allowed)
		)
		(placement
			(enabled no)
			(sheetname "")
		)
		(fill
			(thermal_gap 0.5)
			(thermal_bridge_width 0.5)
			(island_removal_mode 0)
		)
		(polygon
			(pts
				(xy 295.570402 -0.120142) (xy 296.129202 -0.120142) (xy 296.129202 -1.923542) (xy 295.570402 -1.923542)
			)
		)
	)
	(zone
		(layer "In12.Cu")
		(hatch none 0.5)
		(connect_pads
			(clearance 0)
		)
		(min_thickness 0.25)
		(keepout
			(tracks not_allowed)
			(vias allowed)
			(pads allowed)
			(copperpour not_allowed)
			(footprints allowed)
		)
		(placement
			(enabled no)
			(sheetname "")
		)
		(fill
			(thermal_gap 0.5)
			(thermal_bridge_width 0.5)
			(island_removal_mode 0)
		)
		(polygon
			(pts
				(xy 84.670138 -136.975342) (xy 85.228938 -136.975342) (xy 85.228938 -138.778742) (xy 84.670138 -138.778742)
			)
		)
	)
	(zone
		(layer "In12.Cu")
		(hatch none 0.5)
		(connect_pads
			(clearance 0)
		)
		(min_thickness 0.25)
		(keepout
			(tracks not_allowed)
			(vias allowed)
			(pads allowed)
			(copperpour not_allowed)
			(footprints allowed)
		)
		(placement
			(enabled no)
			(sheetname "")
		)
		(fill
			(thermal_gap 0.5)
			(thermal_bridge_width 0.5)
			(island_removal_mode 0)
		)
		(polygon
			(pts
				(xy 91.469972 -23.922482) (xy 92.028772 -23.922482) (xy 92.028772 -25.725882) (xy 91.469972 -25.725882)
			)
		)
	)
	(zone
		(layer "In12.Cu")
		(hatch none 0.5)
		(connect_pads
			(clearance 0)
		)
		(min_thickness 0.25)
		(keepout
			(tracks not_allowed)
			(vias allowed)
			(pads allowed)
			(copperpour not_allowed)
			(footprints allowed)
		)
		(placement
			(enabled no)
			(sheetname "")
		)
		(fill
			(thermal_gap 0.5)
			(thermal_bridge_width 0.5)
			(island_removal_mode 0)
		)
		(polygon
			(pts
				(xy 123.769882 -23.922482) (xy 124.328682 -23.922482) (xy 124.328682 -25.725882) (xy 123.769882 -25.725882)
			)
		)
	)
	(zone
		(layer "In12.Cu")
		(hatch none 0.5)
		(connect_pads
			(clearance 0)
		)
		(min_thickness 0.25)
		(keepout
			(tracks not_allowed)
			(vias allowed)
			(pads allowed)
			(copperpour not_allowed)
			(footprints allowed)
		)
		(placement
			(enabled no)
			(sheetname "")
		)
		(fill
			(thermal_gap 0.5)
			(thermal_bridge_width 0.5)
			(island_removal_mode 0)
		)
		(polygon
			(pts
				(xy 215.670384 -0.120142) (xy 216.229184 -0.120142) (xy 216.229184 -1.923542) (xy 215.670384 -1.923542)
			)
		)
	)
	(zone
		(layer "In12.Cu")
		(hatch none 0.5)
		(connect_pads
			(clearance 0)
		)
		(min_thickness 0.25)
		(keepout
			(tracks not_allowed)
			(vias allowed)
			(pads allowed)
			(copperpour not_allowed)
			(footprints allowed)
		)
		(placement
			(enabled no)
			(sheetname "")
		)
		(fill
			(thermal_gap 0.5)
			(thermal_bridge_width 0.5)
			(island_removal_mode 0)
		)
		(polygon
			(pts
				(xy 208.87055 -14.321282) (xy 209.42935 -14.321282) (xy 209.42935 -16.124682) (xy 208.87055 -16.124682)
			)
		)
	)
	(zone
		(layer "In12.Cu")
		(hatch none 0.5)
		(connect_pads
			(clearance 0)
		)
		(min_thickness 0.25)
		(keepout
			(tracks not_allowed)
			(vias allowed)
			(pads allowed)
			(copperpour not_allowed)
			(footprints allowed)
		)
		(placement
			(enabled no)
			(sheetname "")
		)
		(fill
			(thermal_gap 0.5)
			(thermal_bridge_width 0.5)
			(island_removal_mode 0)
		)
		(polygon
			(pts
				(xy 384.963924 -23.615904) (xy 386.360924 -23.615904) (xy 386.360924 -24.123904) (xy 384.963924 -24.123904)
			)
		)
	)
	(zone
		(layer "In12.Cu")
		(hatch none 0.5)
		(connect_pads
			(clearance 0)
		)
		(min_thickness 0.25)
		(keepout
			(tracks not_allowed)
			(vias allowed)
			(pads allowed)
			(copperpour not_allowed)
			(footprints allowed)
		)
		(placement
			(enabled no)
			(sheetname "")
		)
		(fill
			(thermal_gap 0.5)
			(thermal_bridge_width 0.5)
			(island_removal_mode 0)
		)
		(polygon
			(pts
				(xy 298.120308 -151.176482) (xy 298.679108 -151.176482) (xy 298.679108 -152.979882) (xy 298.120308 -152.979882)
			)
		)
	)
	(zone
		(layer "In12.Cu")
		(hatch none 0.5)
		(connect_pads
			(clearance 0)
		)
		(min_thickness 0.25)
		(keepout
			(tracks not_allowed)
			(vias allowed)
			(pads allowed)
			(copperpour not_allowed)
			(footprints allowed)
		)
		(placement
			(enabled no)
			(sheetname "")
		)
		(fill
			(thermal_gap 0.5)
			(thermal_bridge_width 0.5)
			(island_removal_mode 0)
		)
		(polygon
			(pts
				(xy 385.209034 -26.252932) (xy 386.606034 -26.252932) (xy 386.606034 -26.760932) (xy 385.209034 -26.760932)
			)
		)
	)
	(zone
		(layer "In12.Cu")
		(hatch none 0.5)
		(connect_pads
			(clearance 0)
		)
		(min_thickness 0.25)
		(keepout
			(tracks not_allowed)
			(vias allowed)
			(pads allowed)
			(copperpour not_allowed)
			(footprints allowed)
		)
		(placement
			(enabled no)
			(sheetname "")
		)
		(fill
			(thermal_gap 0.5)
			(thermal_bridge_width 0.5)
			(island_removal_mode 0)
		)
		(polygon
			(pts
				(xy 112.72012 -131.974082) (xy 113.27892 -131.974082) (xy 113.27892 -133.777482) (xy 112.72012 -133.777482)
			)
		)
	)
	(zone
		(layer "In12.Cu")
		(hatch none 0.5)
		(connect_pads
			(clearance 0)
		)
		(min_thickness 0.25)
		(keepout
			(tracks not_allowed)
			(vias allowed)
			(pads allowed)
			(copperpour not_allowed)
			(footprints allowed)
		)
		(placement
			(enabled no)
			(sheetname "")
		)
		(fill
			(thermal_gap 0.5)
			(thermal_bridge_width 0.5)
			(island_removal_mode 0)
		)
		(polygon
			(pts
				(xy 235.22051 -14.321282) (xy 235.77931 -14.321282) (xy 235.77931 -16.124682) (xy 235.22051 -16.124682)
			)
		)
	)
	(zone
		(layer "In12.Cu")
		(hatch none 0.5)
		(connect_pads
			(clearance 0)
		)
		(min_thickness 0.25)
		(keepout
			(tracks not_allowed)
			(vias allowed)
			(pads allowed)
			(copperpour not_allowed)
			(footprints allowed)
		)
		(placement
			(enabled no)
			(sheetname "")
		)
		(fill
			(thermal_gap 0.5)
			(thermal_bridge_width 0.5)
			(island_removal_mode 0)
		)
		(polygon
			(pts
				(xy 89.76995 -146.576542) (xy 90.32875 -146.576542) (xy 90.32875 -148.379942) (xy 89.76995 -148.379942)
			)
		)
	)
	(zone
		(layer "In12.Cu")
		(hatch none 0.5)
		(connect_pads
			(clearance 0)
		)
		(min_thickness 0.25)
		(keepout
			(tracks not_allowed)
			(vias allowed)
			(pads allowed)
			(copperpour not_allowed)
			(footprints allowed)
		)
		(placement
			(enabled no)
			(sheetname "")
		)
		(fill
			(thermal_gap 0.5)
			(thermal_bridge_width 0.5)
			(island_removal_mode 0)
		)
		(polygon
			(pts
				(xy 59.170062 -14.321282) (xy 59.728862 -14.321282) (xy 59.728862 -16.124682) (xy 59.170062 -16.124682)
			)
		)
	)
	(zone
		(layer "In12.Cu")
		(hatch none 0.5)
		(connect_pads
			(clearance 0)
		)
		(min_thickness 0.25)
		(keepout
			(tracks not_allowed)
			(vias allowed)
			(pads allowed)
			(copperpour not_allowed)
			(footprints allowed)
		)
		(placement
			(enabled no)
			(sheetname "")
		)
		(fill
			(thermal_gap 0.5)
			(thermal_bridge_width 0.5)
			(island_removal_mode 0)
		)
		(polygon
			(pts
				(xy 422.6052 -152.654) (xy 422.6052 -153.416) (xy 423.5958 -153.416) (xy 423.5958 -152.654)
			)
		)
	)
	(zone
		(layer "In12.Cu")
		(hatch none 0.5)
		(connect_pads
			(clearance 0)
		)
		(min_thickness 0.25)
		(keepout
			(tracks not_allowed)
			(vias allowed)
			(pads allowed)
			(copperpour not_allowed)
			(footprints allowed)
		)
		(placement
			(enabled no)
			(sheetname "")
		)
		(fill
			(thermal_gap 0.5)
			(thermal_bridge_width 0.5)
			(island_removal_mode 0)
		)
		(polygon
			(pts
				(xy 129.720086 -4.720082) (xy 130.278886 -4.720082) (xy 130.278886 -6.523482) (xy 129.720086 -6.523482)
			)
		)
	)
	(zone
		(layer "In12.Cu")
		(hatch none 0.5)
		(connect_pads
			(clearance 0)
		)
		(min_thickness 0.25)
		(keepout
			(tracks not_allowed)
			(vias allowed)
			(pads allowed)
			(copperpour not_allowed)
			(footprints allowed)
		)
		(placement
			(enabled no)
			(sheetname "")
		)
		(fill
			(thermal_gap 0.5)
			(thermal_bridge_width 0.5)
			(island_removal_mode 0)
		)
		(polygon
			(pts
				(xy 233.520488 -141.575282) (xy 234.079288 -141.575282) (xy 234.079288 -143.378682) (xy 233.520488 -143.378682)
			)
		)
	)
	(zone
		(layer "In12.Cu")
		(hatch none 0.5)
		(connect_pads
			(clearance 0)
		)
		(min_thickness 0.25)
		(keepout
			(tracks not_allowed)
			(vias allowed)
			(pads allowed)
			(copperpour not_allowed)
			(footprints allowed)
		)
		(placement
			(enabled no)
			(sheetname "")
		)
		(fill
			(thermal_gap 0.5)
			(thermal_bridge_width 0.5)
			(island_removal_mode 0)
		)
		(polygon
			(pts
				(xy 354.797614 -122.916442) (xy 352.511614 -122.916442) (xy 352.511614 -122.408442) (xy 354.797614 -122.408442)
			)
		)
	)
	(zone
		(layer "In12.Cu")
		(hatch none 0.5)
		(connect_pads
			(clearance 0)
		)
		(min_thickness 0.25)
		(keepout
			(tracks not_allowed)
			(vias allowed)
			(pads allowed)
			(copperpour not_allowed)
			(footprints allowed)
		)
		(placement
			(enabled no)
			(sheetname "")
		)
		(fill
			(thermal_gap 0.5)
			(thermal_bridge_width 0.5)
			(island_removal_mode 0)
		)
		(polygon
			(pts
				(xy 102.519988 -127.374142) (xy 103.078788 -127.374142) (xy 103.078788 -129.177542) (xy 102.519988 -129.177542)
			)
		)
	)
	(zone
		(layer "In12.Cu")
		(hatch none 0.5)
		(connect_pads
			(clearance 0)
		)
		(min_thickness 0.25)
		(keepout
			(tracks not_allowed)
			(vias allowed)
			(pads allowed)
			(copperpour not_allowed)
			(footprints allowed)
		)
		(placement
			(enabled no)
			(sheetname "")
		)
		(fill
			(thermal_gap 0.5)
			(thermal_bridge_width 0.5)
			(island_removal_mode 0)
		)
		(polygon
			(pts
				(xy 315.120528 -4.720082) (xy 315.679328 -4.720082) (xy 315.679328 -6.523482) (xy 315.120528 -6.523482)
			)
		)
	)
	(zone
		(layer "In12.Cu")
		(hatch none 0.5)
		(connect_pads
			(clearance 0)
		)
		(min_thickness 0.25)
		(keepout
			(tracks not_allowed)
			(vias allowed)
			(pads allowed)
			(copperpour not_allowed)
			(footprints allowed)
		)
		(placement
			(enabled no)
			(sheetname "")
		)
		(fill
			(thermal_gap 0.5)
			(thermal_bridge_width 0.5)
			(island_removal_mode 0)
		)
		(polygon
			(pts
				(xy 106.77017 -4.720082) (xy 107.32897 -4.720082) (xy 107.32897 -6.523482) (xy 106.77017 -6.523482)
			)
		)
	)
	(zone
		(layer "In12.Cu")
		(hatch none 0.5)
		(connect_pads
			(clearance 0)
		)
		(min_thickness 0.25)
		(keepout
			(tracks not_allowed)
			(vias allowed)
			(pads allowed)
			(copperpour not_allowed)
			(footprints allowed)
		)
		(placement
			(enabled no)
			(sheetname "")
		)
		(fill
			(thermal_gap 0.5)
			(thermal_bridge_width 0.5)
			(island_removal_mode 0)
		)
		(polygon
			(pts
				(xy 254.770382 -127.374142) (xy 255.329182 -127.374142) (xy 255.329182 -129.177542) (xy 254.770382 -129.177542)
			)
		)
	)
	(zone
		(layer "In12.Cu")
		(hatch none 0.5)
		(connect_pads
			(clearance 0)
		)
		(min_thickness 0.25)
		(keepout
			(tracks not_allowed)
			(vias allowed)
			(pads allowed)
			(copperpour not_allowed)
			(footprints allowed)
		)
		(placement
			(enabled no)
			(sheetname "")
		)
		(fill
			(thermal_gap 0.5)
			(thermal_bridge_width 0.5)
			(island_removal_mode 0)
		)
		(polygon
			(pts
				(xy 208.87055 -141.575282) (xy 209.42935 -141.575282) (xy 209.42935 -143.378682) (xy 208.87055 -143.378682)
			)
		)
	)
	(zone
		(layer "In12.Cu")
		(hatch none 0.5)
		(connect_pads
			(clearance 0)
		)
		(min_thickness 0.25)
		(keepout
			(tracks not_allowed)
			(vias allowed)
			(pads allowed)
			(copperpour not_allowed)
			(footprints allowed)
		)
		(placement
			(enabled no)
			(sheetname "")
		)
		(fill
			(thermal_gap 0.5)
			(thermal_bridge_width 0.5)
			(island_removal_mode 0)
		)
		(polygon
			(pts
				(xy 68.520056 -141.575282) (xy 69.078856 -141.575282) (xy 69.078856 -143.378682) (xy 68.520056 -143.378682)
			)
		)
	)
	(zone
		(layer "In12.Cu")
		(hatch none 0.5)
		(connect_pads
			(clearance 0)
		)
		(min_thickness 0.25)
		(keepout
			(tracks not_allowed)
			(vias allowed)
			(pads allowed)
			(copperpour not_allowed)
			(footprints allowed)
		)
		(placement
			(enabled no)
			(sheetname "")
		)
		(fill
			(thermal_gap 0.5)
			(thermal_bridge_width 0.5)
			(island_removal_mode 0)
		)
		(polygon
			(pts
				(xy 286.220408 -136.975342) (xy 286.779208 -136.975342) (xy 286.779208 -138.778742) (xy 286.220408 -138.778742)
			)
		)
	)
	(zone
		(layer "In12.Cu")
		(hatch none 0.5)
		(connect_pads
			(clearance 0)
		)
		(min_thickness 0.25)
		(keepout
			(tracks not_allowed)
			(vias allowed)
			(pads allowed)
			(copperpour not_allowed)
			(footprints allowed)
		)
		(placement
			(enabled no)
			(sheetname "")
		)
		(fill
			(thermal_gap 0.5)
			(thermal_bridge_width 0.5)
			(island_removal_mode 0)
		)
		(polygon
			(pts
				(xy 309.170324 -131.974082) (xy 309.729124 -131.974082) (xy 309.729124 -133.777482) (xy 309.170324 -133.777482)
			)
		)
	)
	(zone
		(layer "In12.Cu")
		(hatch none 0.5)
		(connect_pads
			(clearance 0)
		)
		(min_thickness 0.25)
		(keepout
			(tracks not_allowed)
			(vias allowed)
			(pads allowed)
			(copperpour not_allowed)
			(footprints allowed)
		)
		(placement
			(enabled no)
			(sheetname "")
		)
		(fill
			(thermal_gap 0.5)
			(thermal_bridge_width 0.5)
			(island_removal_mode 0)
		)
		(polygon
			(pts
				(xy 256.470404 -9.721342) (xy 257.029204 -9.721342) (xy 257.029204 -11.524742) (xy 256.470404 -11.524742)
			)
		)
	)
	(zone
		(layer "In12.Cu")
		(hatch none 0.5)
		(connect_pads
			(clearance 0)
		)
		(min_thickness 0.25)
		(keepout
			(tracks not_allowed)
			(vias allowed)
			(pads allowed)
			(copperpour not_allowed)
			(footprints allowed)
		)
		(placement
			(enabled no)
			(sheetname "")
		)
		(fill
			(thermal_gap 0.5)
			(thermal_bridge_width 0.5)
			(island_removal_mode 0)
		)
		(polygon
			(pts
				(xy 204.620368 -146.576542) (xy 205.179168 -146.576542) (xy 205.179168 -148.379942) (xy 204.620368 -148.379942)
			)
		)
	)
	(zone
		(layer "In12.Cu")
		(hatch none 0.5)
		(connect_pads
			(clearance 0)
		)
		(min_thickness 0.25)
		(keepout
			(tracks not_allowed)
			(vias allowed)
			(pads allowed)
			(copperpour not_allowed)
			(footprints allowed)
		)
		(placement
			(enabled no)
			(sheetname "")
		)
		(fill
			(thermal_gap 0.5)
			(thermal_bridge_width 0.5)
			(island_removal_mode 0)
		)
		(polygon
			(pts
				(xy 44.720002 -0.120142) (xy 45.278802 -0.120142) (xy 45.278802 -1.923542) (xy 44.720002 -1.923542)
			)
		)
	)
	(zone
		(layer "In12.Cu")
		(hatch none 0.5)
		(connect_pads
			(clearance 0)
		)
		(min_thickness 0.25)
		(keepout
			(tracks not_allowed)
			(vias allowed)
			(pads allowed)
			(copperpour not_allowed)
			(footprints allowed)
		)
		(placement
			(enabled no)
			(sheetname "")
		)
		(fill
			(thermal_gap 0.5)
			(thermal_bridge_width 0.5)
			(island_removal_mode 0)
		)
		(polygon
			(pts
				(xy 82.119978 -0.120142) (xy 82.678778 -0.120142) (xy 82.678778 -1.923542) (xy 82.119978 -1.923542)
			)
		)
	)
	(zone
		(layer "In12.Cu")
		(hatch none 0.5)
		(connect_pads
			(clearance 0)
		)
		(min_thickness 0.25)
		(keepout
			(tracks not_allowed)
			(vias allowed)
			(pads allowed)
			(copperpour not_allowed)
			(footprints allowed)
		)
		(placement
			(enabled no)
			(sheetname "")
		)
		(fill
			(thermal_gap 0.5)
			(thermal_bridge_width 0.5)
			(island_removal_mode 0)
		)
		(polygon
			(pts
				(xy 40.470074 -131.974082) (xy 41.028874 -131.974082) (xy 41.028874 -133.777482) (xy 40.470074 -133.777482)
			)
		)
	)
	(zone
		(layer "In12.Cu")
		(hatch none 0.5)
		(connect_pads
			(clearance 0)
		)
		(min_thickness 0.25)
		(keepout
			(tracks not_allowed)
			(vias allowed)
			(pads allowed)
			(copperpour not_allowed)
			(footprints allowed)
		)
		(placement
			(enabled no)
			(sheetname "")
		)
		(fill
			(thermal_gap 0.5)
			(thermal_bridge_width 0.5)
			(island_removal_mode 0)
		)
		(polygon
			(pts
				(xy 56.620156 -0.120142) (xy 57.178956 -0.120142) (xy 57.178956 -1.923542) (xy 56.620156 -1.923542)
			)
		)
	)
	(zone
		(layer "In12.Cu")
		(hatch none 0.5)
		(connect_pads
			(clearance 0)
		)
		(min_thickness 0.25)
		(keepout
			(tracks not_allowed)
			(vias allowed)
			(pads allowed)
			(copperpour not_allowed)
			(footprints allowed)
		)
		(placement
			(enabled no)
			(sheetname "")
		)
		(fill
			(thermal_gap 0.5)
			(thermal_bridge_width 0.5)
			(island_removal_mode 0)
		)
		(polygon
			(pts
				(xy 207.170528 -14.321282) (xy 207.729328 -14.321282) (xy 207.729328 -16.124682) (xy 207.170528 -16.124682)
			)
		)
	)
	(zone
		(layer "In12.Cu")
		(hatch none 0.5)
		(connect_pads
			(clearance 0)
		)
		(min_thickness 0.25)
		(keepout
			(tracks not_allowed)
			(vias allowed)
			(pads allowed)
			(copperpour not_allowed)
			(footprints allowed)
		)
		(placement
			(enabled no)
			(sheetname "")
		)
		(fill
			(thermal_gap 0.5)
			(thermal_bridge_width 0.5)
			(island_removal_mode 0)
		)
		(polygon
			(pts
				(xy 218.220544 -4.720082) (xy 218.779344 -4.720082) (xy 218.779344 -6.523482) (xy 218.220544 -6.523482)
			)
		)
	)
	(zone
		(layer "In12.Cu")
		(hatch none 0.5)
		(connect_pads
			(clearance 0)
		)
		(min_thickness 0.25)
		(keepout
			(tracks not_allowed)
			(vias allowed)
			(pads allowed)
			(copperpour not_allowed)
			(footprints allowed)
		)
		(placement
			(enabled no)
			(sheetname "")
		)
		(fill
			(thermal_gap 0.5)
			(thermal_bridge_width 0.5)
			(island_removal_mode 0)
		)
		(polygon
			(pts
				(xy 310.020462 -9.721342) (xy 310.579262 -9.721342) (xy 310.579262 -11.524742) (xy 310.020462 -11.524742)
			)
		)
	)
	(zone
		(layer "In12.Cu")
		(hatch none 0.5)
		(connect_pads
			(clearance 0)
		)
		(min_thickness 0.25)
		(keepout
			(tracks not_allowed)
			(vias allowed)
			(pads allowed)
			(copperpour not_allowed)
			(footprints allowed)
		)
		(placement
			(enabled no)
			(sheetname "")
		)
		(fill
			(thermal_gap 0.5)
			(thermal_bridge_width 0.5)
			(island_removal_mode 0)
		)
		(polygon
			(pts
				(xy 210.570572 -19.322542) (xy 211.129372 -19.322542) (xy 211.129372 -21.125942) (xy 210.570572 -21.125942)
			)
		)
	)
	(zone
		(layer "In12.Cu")
		(hatch none 0.5)
		(connect_pads
			(clearance 0)
		)
		(min_thickness 0.25)
		(keepout
			(tracks not_allowed)
			(vias allowed)
			(pads allowed)
			(copperpour not_allowed)
			(footprints allowed)
		)
		(placement
			(enabled no)
			(sheetname "")
		)
		(fill
			(thermal_gap 0.5)
			(thermal_bridge_width 0.5)
			(island_removal_mode 0)
		)
		(polygon
			(pts
				(xy 230.970582 -146.576542) (xy 231.529382 -146.576542) (xy 231.529382 -148.379942) (xy 230.970582 -148.379942)
			)
		)
	)
	(zone
		(layer "In12.Cu")
		(hatch none 0.5)
		(connect_pads
			(clearance 0)
		)
		(min_thickness 0.25)
		(keepout
			(tracks not_allowed)
			(vias allowed)
			(pads allowed)
			(copperpour not_allowed)
			(footprints allowed)
		)
		(placement
			(enabled no)
			(sheetname "")
		)
		(fill
			(thermal_gap 0.5)
			(thermal_bridge_width 0.5)
			(island_removal_mode 0)
		)
		(polygon
			(pts
				(xy 431.794666 -141.475714) (xy 431.794666 -140.713714) (xy 430.804066 -140.713714) (xy 430.804066 -141.475714)
			)
		)
	)
	(zone
		(layer "In12.Cu")
		(hatch none 0.5)
		(connect_pads
			(clearance 0)
		)
		(min_thickness 0.25)
		(keepout
			(tracks not_allowed)
			(vias allowed)
			(pads allowed)
			(copperpour not_allowed)
			(footprints allowed)
		)
		(placement
			(enabled no)
			(sheetname "")
		)
		(fill
			(thermal_gap 0.5)
			(thermal_bridge_width 0.5)
			(island_removal_mode 0)
		)
		(polygon
			(pts
				(xy 270.07058 -136.975342) (xy 270.62938 -136.975342) (xy 270.62938 -138.778742) (xy 270.07058 -138.778742)
			)
		)
	)
	(zone
		(layer "In12.Cu")
		(hatch none 0.5)
		(connect_pads
			(clearance 0)
		)
		(min_thickness 0.25)
		(keepout
			(tracks not_allowed)
			(vias allowed)
			(pads allowed)
			(copperpour not_allowed)
			(footprints allowed)
		)
		(placement
			(enabled no)
			(sheetname "")
		)
		(fill
			(thermal_gap 0.5)
			(thermal_bridge_width 0.5)
			(island_removal_mode 0)
		)
		(polygon
			(pts
				(xy 127.169926 -151.176482) (xy 127.728726 -151.176482) (xy 127.728726 -152.979882) (xy 127.169926 -152.979882)
			)
		)
	)
	(zone
		(layer "In12.Cu")
		(hatch none 0.5)
		(connect_pads
			(clearance 0)
		)
		(min_thickness 0.25)
		(keepout
			(tracks not_allowed)
			(vias allowed)
			(pads allowed)
			(copperpour not_allowed)
			(footprints allowed)
		)
		(placement
			(enabled no)
			(sheetname "")
		)
		(fill
			(thermal_gap 0.5)
			(thermal_bridge_width 0.5)
			(island_removal_mode 0)
		)
		(polygon
			(pts
				(xy 240.320576 -127.374142) (xy 240.879376 -127.374142) (xy 240.879376 -129.177542) (xy 240.320576 -129.177542)
			)
		)
	)
	(zone
		(layer "In12.Cu")
		(hatch none 0.5)
		(connect_pads
			(clearance 0)
		)
		(min_thickness 0.25)
		(keepout
			(tracks not_allowed)
			(vias allowed)
			(pads allowed)
			(copperpour not_allowed)
			(footprints allowed)
		)
		(placement
			(enabled no)
			(sheetname "")
		)
		(fill
			(thermal_gap 0.5)
			(thermal_bridge_width 0.5)
			(island_removal_mode 0)
		)
		(polygon
			(pts
				(xy 228.420422 -141.575282) (xy 228.979222 -141.575282) (xy 228.979222 -143.378682) (xy 228.420422 -143.378682)
			)
		)
	)
	(zone
		(layer "In12.Cu")
		(hatch none 0.5)
		(connect_pads
			(clearance 0)
		)
		(min_thickness 0.25)
		(keepout
			(tracks not_allowed)
			(vias allowed)
			(pads allowed)
			(copperpour not_allowed)
			(footprints allowed)
		)
		(placement
			(enabled no)
			(sheetname "")
		)
		(fill
			(thermal_gap 0.5)
			(thermal_bridge_width 0.5)
			(island_removal_mode 0)
		)
		(polygon
			(pts
				(xy 84.670138 -19.322542) (xy 85.228938 -19.322542) (xy 85.228938 -21.125942) (xy 84.670138 -21.125942)
			)
		)
	)
	(zone
		(layer "In12.Cu")
		(hatch none 0.5)
		(connect_pads
			(clearance 0)
		)
		(min_thickness 0.25)
		(keepout
			(tracks not_allowed)
			(vias allowed)
			(pads allowed)
			(copperpour not_allowed)
			(footprints allowed)
		)
		(placement
			(enabled no)
			(sheetname "")
		)
		(fill
			(thermal_gap 0.5)
			(thermal_bridge_width 0.5)
			(island_removal_mode 0)
		)
		(polygon
			(pts
				(xy 203.770484 -4.720082) (xy 204.329284 -4.720082) (xy 204.329284 -6.523482) (xy 203.770484 -6.523482)
			)
		)
	)
	(zone
		(layer "In12.Cu")
		(hatch none 0.5)
		(connect_pads
			(clearance 0)
		)
		(min_thickness 0.25)
		(keepout
			(tracks not_allowed)
			(vias allowed)
			(pads allowed)
			(copperpour not_allowed)
			(footprints allowed)
		)
		(placement
			(enabled no)
			(sheetname "")
		)
		(fill
			(thermal_gap 0.5)
			(thermal_bridge_width 0.5)
			(island_removal_mode 0)
		)
		(polygon
			(pts
				(xy 272.620486 -131.974082) (xy 273.179286 -131.974082) (xy 273.179286 -133.777482) (xy 272.620486 -133.777482)
			)
		)
	)
	(zone
		(layer "In12.Cu")
		(hatch none 0.5)
		(connect_pads
			(clearance 0)
		)
		(min_thickness 0.25)
		(keepout
			(tracks not_allowed)
			(vias allowed)
			(pads allowed)
			(copperpour not_allowed)
			(footprints allowed)
		)
		(placement
			(enabled no)
			(sheetname "")
		)
		(fill
			(thermal_gap 0.5)
			(thermal_bridge_width 0.5)
			(island_removal_mode 0)
		)
		(polygon
			(pts
				(xy 205.470506 -151.176482) (xy 206.029306 -151.176482) (xy 206.029306 -152.979882) (xy 205.470506 -152.979882)
			)
		)
	)
	(zone
		(layer "In12.Cu")
		(hatch none 0.5)
		(connect_pads
			(clearance 0)
		)
		(min_thickness 0.25)
		(keepout
			(tracks not_allowed)
			(vias allowed)
			(pads allowed)
			(copperpour not_allowed)
			(footprints allowed)
		)
		(placement
			(enabled no)
			(sheetname "")
		)
		(fill
			(thermal_gap 0.5)
			(thermal_bridge_width 0.5)
			(island_removal_mode 0)
		)
		(polygon
			(pts
				(xy 226.7204 -9.721342) (xy 227.2792 -9.721342) (xy 227.2792 -11.524742) (xy 226.7204 -11.524742)
			)
		)
	)
	(zone
		(layer "In12.Cu")
		(hatch none 0.5)
		(connect_pads
			(clearance 0)
		)
		(min_thickness 0.25)
		(keepout
			(tracks not_allowed)
			(vias allowed)
			(pads allowed)
			(copperpour not_allowed)
			(footprints allowed)
		)
		(placement
			(enabled no)
			(sheetname "")
		)
		(fill
			(thermal_gap 0.5)
			(thermal_bridge_width 0.5)
			(island_removal_mode 0)
		)
		(polygon
			(pts
				(xy 150.120096 -14.321282) (xy 150.678896 -14.321282) (xy 150.678896 -16.124682) (xy 150.120096 -16.124682)
			)
		)
	)
	(zone
		(layer "In12.Cu")
		(hatch none 0.5)
		(connect_pads
			(clearance 0)
		)
		(min_thickness 0.25)
		(keepout
			(tracks not_allowed)
			(vias allowed)
			(pads allowed)
			(copperpour not_allowed)
			(footprints allowed)
		)
		(placement
			(enabled no)
			(sheetname "")
		)
		(fill
			(thermal_gap 0.5)
			(thermal_bridge_width 0.5)
			(island_removal_mode 0)
		)
		(polygon
			(pts
				(xy 279.42032 -151.176482) (xy 279.97912 -151.176482) (xy 279.97912 -152.979882) (xy 279.42032 -152.979882)
			)
		)
	)
	(zone
		(layer "In12.Cu")
		(hatch none 0.5)
		(connect_pads
			(clearance 0)
		)
		(min_thickness 0.25)
		(keepout
			(tracks not_allowed)
			(vias allowed)
			(pads allowed)
			(copperpour not_allowed)
			(footprints allowed)
		)
		(placement
			(enabled no)
			(sheetname "")
		)
		(fill
			(thermal_gap 0.5)
			(thermal_bridge_width 0.5)
			(island_removal_mode 0)
		)
		(polygon
			(pts
				(xy 92.32011 -23.922482) (xy 92.87891 -23.922482) (xy 92.87891 -25.725882) (xy 92.32011 -25.725882)
			)
		)
	)
	(zone
		(layer "In12.Cu")
		(hatch none 0.5)
		(connect_pads
			(clearance 0)
		)
		(min_thickness 0.25)
		(keepout
			(tracks not_allowed)
			(vias allowed)
			(pads allowed)
			(copperpour not_allowed)
			(footprints allowed)
		)
		(placement
			(enabled no)
			(sheetname "")
		)
		(fill
			(thermal_gap 0.5)
			(thermal_bridge_width 0.5)
			(island_removal_mode 0)
		)
		(polygon
			(pts
				(xy 136.51992 -151.176482) (xy 137.07872 -151.176482) (xy 137.07872 -152.979882) (xy 136.51992 -152.979882)
			)
		)
	)
	(zone
		(layer "In12.Cu")
		(hatch none 0.5)
		(connect_pads
			(clearance 0)
		)
		(min_thickness 0.25)
		(keepout
			(tracks not_allowed)
			(vias allowed)
			(pads allowed)
			(copperpour not_allowed)
			(footprints allowed)
		)
		(placement
			(enabled no)
			(sheetname "")
		)
		(fill
			(thermal_gap 0.5)
			(thermal_bridge_width 0.5)
			(island_removal_mode 0)
		)
		(polygon
			(pts
				(xy 270.07058 -19.322542) (xy 270.62938 -19.322542) (xy 270.62938 -21.125942) (xy 270.07058 -21.125942)
			)
		)
	)
	(zone
		(layer "In12.Cu")
		(hatch none 0.5)
		(connect_pads
			(clearance 0)
		)
		(min_thickness 0.25)
		(keepout
			(tracks not_allowed)
			(vias allowed)
			(pads allowed)
			(copperpour not_allowed)
			(footprints allowed)
		)
		(placement
			(enabled no)
			(sheetname "")
		)
		(fill
			(thermal_gap 0.5)
			(thermal_bridge_width 0.5)
			(island_removal_mode 0)
		)
		(polygon
			(pts
				(xy 201.220578 -146.576542) (xy 201.779378 -146.576542) (xy 201.779378 -148.379942) (xy 201.220578 -148.379942)
			)
		)
	)
	(zone
		(layer "In12.Cu")
		(hatch none 0.5)
		(connect_pads
			(clearance 0)
		)
		(min_thickness 0.25)
		(keepout
			(tracks not_allowed)
			(vias allowed)
			(pads allowed)
			(copperpour not_allowed)
			(footprints allowed)
		)
		(placement
			(enabled no)
			(sheetname "")
		)
		(fill
			(thermal_gap 0.5)
			(thermal_bridge_width 0.5)
			(island_removal_mode 0)
		)
		(polygon
			(pts
				(xy 291.320474 -9.721342) (xy 291.879274 -9.721342) (xy 291.879274 -11.524742) (xy 291.320474 -11.524742)
			)
		)
	)
	(zone
		(layer "In12.Cu")
		(hatch none 0.5)
		(connect_pads
			(clearance 0)
		)
		(min_thickness 0.25)
		(keepout
			(tracks not_allowed)
			(vias allowed)
			(pads allowed)
			(copperpour not_allowed)
			(footprints allowed)
		)
		(placement
			(enabled no)
			(sheetname "")
		)
		(fill
			(thermal_gap 0.5)
			(thermal_bridge_width 0.5)
			(island_removal_mode 0)
		)
		(polygon
			(pts
				(xy 302.37049 -4.720082) (xy 302.92929 -4.720082) (xy 302.92929 -6.523482) (xy 302.37049 -6.523482)
			)
		)
	)
	(zone
		(layer "In12.Cu")
		(hatch none 0.5)
		(connect_pads
			(clearance 0)
		)
		(min_thickness 0.25)
		(keepout
			(tracks not_allowed)
			(vias allowed)
			(pads allowed)
			(copperpour not_allowed)
			(footprints allowed)
		)
		(placement
			(enabled no)
			(sheetname "")
		)
		(fill
			(thermal_gap 0.5)
			(thermal_bridge_width 0.5)
			(island_removal_mode 0)
		)
		(polygon
			(pts
				(xy 65.97015 -127.374142) (xy 66.52895 -127.374142) (xy 66.52895 -129.177542) (xy 65.97015 -129.177542)
			)
		)
	)
	(zone
		(layer "In12.Cu")
		(hatch none 0.5)
		(connect_pads
			(clearance 0)
		)
		(min_thickness 0.25)
		(keepout
			(tracks not_allowed)
			(vias allowed)
			(pads allowed)
			(copperpour not_allowed)
			(footprints allowed)
		)
		(placement
			(enabled no)
			(sheetname "")
		)
		(fill
			(thermal_gap 0.5)
			(thermal_bridge_width 0.5)
			(island_removal_mode 0)
		)
		(polygon
			(pts
				(xy 249.67057 -0.120142) (xy 250.22937 -0.120142) (xy 250.22937 -1.923542) (xy 249.67057 -1.923542)
			)
		)
	)
	(zone
		(layer "In12.Cu")
		(hatch none 0.5)
		(connect_pads
			(clearance 0)
		)
		(min_thickness 0.25)
		(keepout
			(tracks not_allowed)
			(vias allowed)
			(pads allowed)
			(copperpour not_allowed)
			(footprints allowed)
		)
		(placement
			(enabled no)
			(sheetname "")
		)
		(fill
			(thermal_gap 0.5)
			(thermal_bridge_width 0.5)
			(island_removal_mode 0)
		)
		(polygon
			(pts
				(xy 120.370092 -14.321282) (xy 120.928892 -14.321282) (xy 120.928892 -16.124682) (xy 120.370092 -16.124682)
			)
		)
	)
	(zone
		(layer "In12.Cu")
		(hatch none 0.5)
		(connect_pads
			(clearance 0)
		)
		(min_thickness 0.25)
		(keepout
			(tracks not_allowed)
			(vias allowed)
			(pads allowed)
			(copperpour not_allowed)
			(footprints allowed)
		)
		(placement
			(enabled no)
			(sheetname "")
		)
		(fill
			(thermal_gap 0.5)
			(thermal_bridge_width 0.5)
			(island_removal_mode 0)
		)
		(polygon
			(pts
				(xy 312.570368 -0.120142) (xy 313.129168 -0.120142) (xy 313.129168 -1.923542) (xy 312.570368 -1.923542)
			)
		)
	)
	(zone
		(layer "In12.Cu")
		(hatch none 0.5)
		(connect_pads
			(clearance 0)
		)
		(min_thickness 0.25)
		(keepout
			(tracks not_allowed)
			(vias allowed)
			(pads allowed)
			(copperpour not_allowed)
			(footprints allowed)
		)
		(placement
			(enabled no)
			(sheetname "")
		)
		(fill
			(thermal_gap 0.5)
			(thermal_bridge_width 0.5)
			(island_removal_mode 0)
		)
		(polygon
			(pts
				(xy 44.720002 -14.321282) (xy 45.278802 -14.321282) (xy 45.278802 -16.124682) (xy 44.720002 -16.124682)
			)
		)
	)
	(zone
		(layer "In12.Cu")
		(hatch none 0.5)
		(connect_pads
			(clearance 0)
		)
		(min_thickness 0.25)
		(keepout
			(tracks not_allowed)
			(vias allowed)
			(pads allowed)
			(copperpour not_allowed)
			(footprints allowed)
		)
		(placement
			(enabled no)
			(sheetname "")
		)
		(fill
			(thermal_gap 0.5)
			(thermal_bridge_width 0.5)
			(island_removal_mode 0)
		)
		(polygon
			(pts
				(xy 56.620156 -136.975342) (xy 57.178956 -136.975342) (xy 57.178956 -138.778742) (xy 56.620156 -138.778742)
			)
		)
	)
	(zone
		(layer "In12.Cu")
		(hatch none 0.5)
		(connect_pads
			(clearance 0)
		)
		(min_thickness 0.25)
		(keepout
			(tracks not_allowed)
			(vias allowed)
			(pads allowed)
			(copperpour not_allowed)
			(footprints allowed)
		)
		(placement
			(enabled no)
			(sheetname "")
		)
		(fill
			(thermal_gap 0.5)
			(thermal_bridge_width 0.5)
			(island_removal_mode 0)
		)
		(polygon
			(pts
				(xy 314.27039 -9.721342) (xy 314.82919 -9.721342) (xy 314.82919 -11.524742) (xy 314.27039 -11.524742)
			)
		)
	)
	(zone
		(layer "In12.Cu")
		(hatch none 0.5)
		(connect_pads
			(clearance 0)
		)
		(min_thickness 0.25)
		(keepout
			(tracks not_allowed)
			(vias allowed)
			(pads allowed)
			(copperpour not_allowed)
			(footprints allowed)
		)
		(placement
			(enabled no)
			(sheetname "")
		)
		(fill
			(thermal_gap 0.5)
			(thermal_bridge_width 0.5)
			(island_removal_mode 0)
		)
		(polygon
			(pts
				(xy 132.269992 -127.374142) (xy 132.828792 -127.374142) (xy 132.828792 -129.177542) (xy 132.269992 -129.177542)
			)
		)
	)
	(zone
		(layer "In12.Cu")
		(hatch none 0.5)
		(connect_pads
			(clearance 0)
		)
		(min_thickness 0.25)
		(keepout
			(tracks not_allowed)
			(vias allowed)
			(pads allowed)
			(copperpour not_allowed)
			(footprints allowed)
		)
		(placement
			(enabled no)
			(sheetname "")
		)
		(fill
			(thermal_gap 0.5)
			(thermal_bridge_width 0.5)
			(island_removal_mode 0)
		)
		(polygon
			(pts
				(xy 310.020462 -19.322542) (xy 310.579262 -19.322542) (xy 310.579262 -21.125942) (xy 310.020462 -21.125942)
			)
		)
	)
	(zone
		(layer "In12.Cu")
		(hatch none 0.5)
		(connect_pads
			(clearance 0)
		)
		(min_thickness 0.25)
		(keepout
			(tracks not_allowed)
			(vias allowed)
			(pads allowed)
			(copperpour not_allowed)
			(footprints allowed)
		)
		(placement
			(enabled no)
			(sheetname "")
		)
		(fill
			(thermal_gap 0.5)
			(thermal_bridge_width 0.5)
			(island_removal_mode 0)
		)
		(polygon
			(pts
				(xy 30.269942 -19.322542) (xy 30.828742 -19.322542) (xy 30.828742 -21.125942) (xy 30.269942 -21.125942)
			)
		)
	)
	(zone
		(layer "In12.Cu")
		(hatch none 0.5)
		(connect_pads
			(clearance 0)
		)
		(min_thickness 0.25)
		(keepout
			(tracks not_allowed)
			(vias allowed)
			(pads allowed)
			(copperpour not_allowed)
			(footprints allowed)
		)
		(placement
			(enabled no)
			(sheetname "")
		)
		(fill
			(thermal_gap 0.5)
			(thermal_bridge_width 0.5)
			(island_removal_mode 0)
		)
		(polygon
			(pts
				(xy 77.02042 -0.120142) (xy 77.57922 -0.120142) (xy 77.57922 -1.923542) (xy 77.02042 -1.923542)
			)
		)
	)
	(zone
		(layer "In12.Cu")
		(hatch none 0.5)
		(connect_pads
			(clearance 0)
		)
		(min_thickness 0.25)
		(keepout
			(tracks not_allowed)
			(vias allowed)
			(pads allowed)
			(copperpour not_allowed)
			(footprints allowed)
		)
		(placement
			(enabled no)
			(sheetname "")
		)
		(fill
			(thermal_gap 0.5)
			(thermal_bridge_width 0.5)
			(island_removal_mode 0)
		)
		(polygon
			(pts
				(xy 294.720518 -141.575282) (xy 295.279318 -141.575282) (xy 295.279318 -143.378682) (xy 294.720518 -143.378682)
			)
		)
	)
	(zone
		(layer "In12.Cu")
		(hatch none 0.5)
		(connect_pads
			(clearance 0)
		)
		(min_thickness 0.25)
		(keepout
			(tracks not_allowed)
			(vias allowed)
			(pads allowed)
			(copperpour not_allowed)
			(footprints allowed)
		)
		(placement
			(enabled no)
			(sheetname "")
		)
		(fill
			(thermal_gap 0.5)
			(thermal_bridge_width 0.5)
			(island_removal_mode 0)
		)
		(polygon
			(pts
				(xy 78.719934 -9.721342) (xy 79.278734 -9.721342) (xy 79.278734 -11.524742) (xy 78.719934 -11.524742)
			)
		)
	)
	(zone
		(layer "In12.Cu")
		(hatch none 0.5)
		(connect_pads
			(clearance 0)
		)
		(min_thickness 0.25)
		(keepout
			(tracks not_allowed)
			(vias allowed)
			(pads allowed)
			(copperpour not_allowed)
			(footprints allowed)
		)
		(placement
			(enabled no)
			(sheetname "")
		)
		(fill
			(thermal_gap 0.5)
			(thermal_bridge_width 0.5)
			(island_removal_mode 0)
		)
		(polygon
			(pts
				(xy 230.120444 -141.575282) (xy 230.679244 -141.575282) (xy 230.679244 -143.378682) (xy 230.120444 -143.378682)
			)
		)
	)
	(zone
		(layer "In12.Cu")
		(hatch none 0.5)
		(connect_pads
			(clearance 0)
		)
		(min_thickness 0.25)
		(keepout
			(tracks not_allowed)
			(vias allowed)
			(pads allowed)
			(copperpour not_allowed)
			(footprints allowed)
		)
		(placement
			(enabled no)
			(sheetname "")
		)
		(fill
			(thermal_gap 0.5)
			(thermal_bridge_width 0.5)
			(island_removal_mode 0)
		)
		(polygon
			(pts
				(xy 239.470438 -141.575282) (xy 240.029238 -141.575282) (xy 240.029238 -143.378682) (xy 239.470438 -143.378682)
			)
		)
	)
	(zone
		(layer "In12.Cu")
		(hatch none 0.5)
		(connect_pads
			(clearance 0)
		)
		(min_thickness 0.25)
		(keepout
			(tracks not_allowed)
			(vias allowed)
			(pads allowed)
			(copperpour not_allowed)
			(footprints allowed)
		)
		(placement
			(enabled no)
			(sheetname "")
		)
		(fill
			(thermal_gap 0.5)
			(thermal_bridge_width 0.5)
			(island_removal_mode 0)
		)
		(polygon
			(pts
				(xy 127.169926 -14.321282) (xy 127.728726 -14.321282) (xy 127.728726 -16.124682) (xy 127.169926 -16.124682)
			)
		)
	)
	(zone
		(layer "In12.Cu")
		(hatch none 0.5)
		(connect_pads
			(clearance 0)
		)
		(min_thickness 0.25)
		(keepout
			(tracks not_allowed)
			(vias allowed)
			(pads allowed)
			(copperpour not_allowed)
			(footprints allowed)
		)
		(placement
			(enabled no)
			(sheetname "")
		)
		(fill
			(thermal_gap 0.5)
			(thermal_bridge_width 0.5)
			(island_removal_mode 0)
		)
		(polygon
			(pts
				(xy 315.970412 -9.721342) (xy 316.529212 -9.721342) (xy 316.529212 -11.524742) (xy 315.970412 -11.524742)
			)
		)
	)
	(zone
		(layer "In12.Cu")
		(hatch none 0.5)
		(connect_pads
			(clearance 0)
		)
		(min_thickness 0.25)
		(keepout
			(tracks not_allowed)
			(vias allowed)
			(pads allowed)
			(copperpour not_allowed)
			(footprints allowed)
		)
		(placement
			(enabled no)
			(sheetname "")
		)
		(fill
			(thermal_gap 0.5)
			(thermal_bridge_width 0.5)
			(island_removal_mode 0)
		)
		(polygon
			(pts
				(xy 112.72012 -23.922482) (xy 113.27892 -23.922482) (xy 113.27892 -25.725882) (xy 112.72012 -25.725882)
			)
		)
	)
	(zone
		(layer "In12.Cu")
		(hatch none 0.5)
		(connect_pads
			(clearance 0)
		)
		(min_thickness 0.25)
		(keepout
			(tracks not_allowed)
			(vias allowed)
			(pads allowed)
			(copperpour not_allowed)
			(footprints allowed)
		)
		(placement
			(enabled no)
			(sheetname "")
		)
		(fill
			(thermal_gap 0.5)
			(thermal_bridge_width 0.5)
			(island_removal_mode 0)
		)
		(polygon
			(pts
				(xy 247.970548 -9.721342) (xy 248.529348 -9.721342) (xy 248.529348 -11.524742) (xy 247.970548 -11.524742)
			)
		)
	)
	(zone
		(layer "In12.Cu")
		(hatch none 0.5)
		(connect_pads
			(clearance 0)
		)
		(min_thickness 0.25)
		(keepout
			(tracks not_allowed)
			(vias allowed)
			(pads allowed)
			(copperpour not_allowed)
			(footprints allowed)
		)
		(placement
			(enabled no)
			(sheetname "")
		)
		(fill
			(thermal_gap 0.5)
			(thermal_bridge_width 0.5)
			(island_removal_mode 0)
		)
		(polygon
			(pts
				(xy 287.070546 -151.176482) (xy 287.629346 -151.176482) (xy 287.629346 -152.979882) (xy 287.070546 -152.979882)
			)
		)
	)
	(zone
		(layer "In12.Cu")
		(hatch none 0.5)
		(connect_pads
			(clearance 0)
		)
		(min_thickness 0.25)
		(keepout
			(tracks not_allowed)
			(vias allowed)
			(pads allowed)
			(copperpour not_allowed)
			(footprints allowed)
		)
		(placement
			(enabled no)
			(sheetname "")
		)
		(fill
			(thermal_gap 0.5)
			(thermal_bridge_width 0.5)
			(island_removal_mode 0)
		)
		(polygon
			(pts
				(xy 249.67057 -136.975342) (xy 250.22937 -136.975342) (xy 250.22937 -138.778742) (xy 249.67057 -138.778742)
			)
		)
	)
	(zone
		(layer "In12.Cu")
		(hatch none 0.5)
		(connect_pads
			(clearance 0)
		)
		(min_thickness 0.25)
		(keepout
			(tracks not_allowed)
			(vias allowed)
			(pads allowed)
			(copperpour not_allowed)
			(footprints allowed)
		)
		(placement
			(enabled no)
			(sheetname "")
		)
		(fill
			(thermal_gap 0.5)
			(thermal_bridge_width 0.5)
			(island_removal_mode 0)
		)
		(polygon
			(pts
				(xy 65.97015 -19.322542) (xy 66.52895 -19.322542) (xy 66.52895 -21.125942) (xy 65.97015 -21.125942)
			)
		)
	)
	(zone
		(layer "In12.Cu")
		(hatch none 0.5)
		(connect_pads
			(clearance 0)
		)
		(min_thickness 0.25)
		(keepout
			(tracks not_allowed)
			(vias allowed)
			(pads allowed)
			(copperpour not_allowed)
			(footprints allowed)
		)
		(placement
			(enabled no)
			(sheetname "")
		)
		(fill
			(thermal_gap 0.5)
			(thermal_bridge_width 0.5)
			(island_removal_mode 0)
		)
		(polygon
			(pts
				(xy 134.819898 -4.720082) (xy 135.378698 -4.720082) (xy 135.378698 -6.523482) (xy 134.819898 -6.523482)
			)
		)
	)
	(zone
		(layer "In12.Cu")
		(hatch none 0.5)
		(connect_pads
			(clearance 0)
		)
		(min_thickness 0.25)
		(keepout
			(tracks not_allowed)
			(vias allowed)
			(pads allowed)
			(copperpour not_allowed)
			(footprints allowed)
		)
		(placement
			(enabled no)
			(sheetname "")
		)
		(fill
			(thermal_gap 0.5)
			(thermal_bridge_width 0.5)
			(island_removal_mode 0)
		)
		(polygon
			(pts
				(xy 256.470404 -146.576542) (xy 257.029204 -146.576542) (xy 257.029204 -148.379942) (xy 256.470404 -148.379942)
			)
		)
	)
	(zone
		(layer "In12.Cu")
		(hatch none 0.5)
		(connect_pads
			(clearance 0)
		)
		(min_thickness 0.25)
		(keepout
			(tracks not_allowed)
			(vias allowed)
			(pads allowed)
			(copperpour not_allowed)
			(footprints allowed)
		)
		(placement
			(enabled no)
			(sheetname "")
		)
		(fill
			(thermal_gap 0.5)
			(thermal_bridge_width 0.5)
			(island_removal_mode 0)
		)
		(polygon
			(pts
				(xy 225.020378 -9.721342) (xy 225.579178 -9.721342) (xy 225.579178 -11.524742) (xy 225.020378 -11.524742)
			)
		)
	)
	(zone
		(layer "In12.Cu")
		(hatch none 0.5)
		(connect_pads
			(clearance 0)
		)
		(min_thickness 0.25)
		(keepout
			(tracks not_allowed)
			(vias allowed)
			(pads allowed)
			(copperpour not_allowed)
			(footprints allowed)
		)
		(placement
			(enabled no)
			(sheetname "")
		)
		(fill
			(thermal_gap 0.5)
			(thermal_bridge_width 0.5)
			(island_removal_mode 0)
		)
		(polygon
			(pts
				(xy 274.320508 -131.974082) (xy 274.879308 -131.974082) (xy 274.879308 -133.777482) (xy 274.320508 -133.777482)
			)
		)
	)
	(zone
		(layer "In12.Cu")
		(hatch none 0.5)
		(connect_pads
			(clearance 0)
		)
		(min_thickness 0.25)
		(keepout
			(tracks not_allowed)
			(vias allowed)
			(pads allowed)
			(copperpour not_allowed)
			(footprints allowed)
		)
		(placement
			(enabled no)
			(sheetname "")
		)
		(fill
			(thermal_gap 0.5)
			(thermal_bridge_width 0.5)
			(island_removal_mode 0)
		)
		(polygon
			(pts
				(xy 230.970582 -127.374142) (xy 231.529382 -127.374142) (xy 231.529382 -129.177542) (xy 230.970582 -129.177542)
			)
		)
	)
	(zone
		(layer "In12.Cu")
		(hatch none 0.5)
		(connect_pads
			(clearance 0)
		)
		(min_thickness 0.25)
		(keepout
			(tracks not_allowed)
			(vias allowed)
			(pads allowed)
			(copperpour not_allowed)
			(footprints allowed)
		)
		(placement
			(enabled no)
			(sheetname "")
		)
		(fill
			(thermal_gap 0.5)
			(thermal_bridge_width 0.5)
			(island_removal_mode 0)
		)
		(polygon
			(pts
				(xy 298.120308 -141.575282) (xy 298.679108 -141.575282) (xy 298.679108 -143.378682) (xy 298.120308 -143.378682)
			)
		)
	)
	(zone
		(layer "In12.Cu")
		(hatch none 0.5)
		(connect_pads
			(clearance 0)
		)
		(min_thickness 0.25)
		(keepout
			(tracks not_allowed)
			(vias allowed)
			(pads allowed)
			(copperpour not_allowed)
			(footprints allowed)
		)
		(placement
			(enabled no)
			(sheetname "")
		)
		(fill
			(thermal_gap 0.5)
			(thermal_bridge_width 0.5)
			(island_removal_mode 0)
		)
		(polygon
			(pts
				(xy 121.219976 -146.576542) (xy 121.778776 -146.576542) (xy 121.778776 -148.379942) (xy 121.219976 -148.379942)
			)
		)
	)
	(zone
		(layer "In12.Cu")
		(hatch none 0.5)
		(connect_pads
			(clearance 0)
		)
		(min_thickness 0.25)
		(keepout
			(tracks not_allowed)
			(vias allowed)
			(pads allowed)
			(copperpour not_allowed)
			(footprints allowed)
		)
		(placement
			(enabled no)
			(sheetname "")
		)
		(fill
			(thermal_gap 0.5)
			(thermal_bridge_width 0.5)
			(island_removal_mode 0)
		)
		(polygon
			(pts
				(xy 225.870516 -151.176482) (xy 226.429316 -151.176482) (xy 226.429316 -152.979882) (xy 225.870516 -152.979882)
			)
		)
	)
	(zone
		(layer "In12.Cu")
		(hatch none 0.5)
		(connect_pads
			(clearance 0)
		)
		(min_thickness 0.25)
		(keepout
			(tracks not_allowed)
			(vias allowed)
			(pads allowed)
			(copperpour not_allowed)
			(footprints allowed)
		)
		(placement
			(enabled no)
			(sheetname "")
		)
		(fill
			(thermal_gap 0.5)
			(thermal_bridge_width 0.5)
			(island_removal_mode 0)
		)
		(polygon
			(pts
				(xy 47.270162 -0.120142) (xy 47.828962 -0.120142) (xy 47.828962 -1.923542) (xy 47.270162 -1.923542)
			)
		)
	)
	(zone
		(layer "In12.Cu")
		(hatch none 0.5)
		(connect_pads
			(clearance 0)
		)
		(min_thickness 0.25)
		(keepout
			(tracks not_allowed)
			(vias allowed)
			(pads allowed)
			(copperpour not_allowed)
			(footprints allowed)
		)
		(placement
			(enabled no)
			(sheetname "")
		)
		(fill
			(thermal_gap 0.5)
			(thermal_bridge_width 0.5)
			(island_removal_mode 0)
		)
		(polygon
			(pts
				(xy 141.619986 -19.322542) (xy 142.178786 -19.322542) (xy 142.178786 -21.125942) (xy 141.619986 -21.125942)
			)
		)
	)
	(zone
		(layer "In12.Cu")
		(hatch none 0.5)
		(connect_pads
			(clearance 0)
		)
		(min_thickness 0.25)
		(keepout
			(tracks not_allowed)
			(vias allowed)
			(pads allowed)
			(copperpour not_allowed)
			(footprints allowed)
		)
		(placement
			(enabled no)
			(sheetname "")
		)
		(fill
			(thermal_gap 0.5)
			(thermal_bridge_width 0.5)
			(island_removal_mode 0)
		)
		(polygon
			(pts
				(xy 300.670468 -19.322542) (xy 301.229268 -19.322542) (xy 301.229268 -21.125942) (xy 300.670468 -21.125942)
			)
		)
	)
	(zone
		(layer "In12.Cu")
		(hatch none 0.5)
		(connect_pads
			(clearance 0)
		)
		(min_thickness 0.25)
		(keepout
			(tracks not_allowed)
			(vias allowed)
			(pads allowed)
			(copperpour not_allowed)
			(footprints allowed)
		)
		(placement
			(enabled no)
			(sheetname "")
		)
		(fill
			(thermal_gap 0.5)
			(thermal_bridge_width 0.5)
			(island_removal_mode 0)
		)
		(polygon
			(pts
				(xy 218.220544 -23.922482) (xy 218.779344 -23.922482) (xy 218.779344 -25.725882) (xy 218.220544 -25.725882)
			)
		)
	)
	(zone
		(layer "In12.Cu")
		(hatch none 0.5)
		(connect_pads
			(clearance 0)
		)
		(min_thickness 0.25)
		(keepout
			(tracks not_allowed)
			(vias allowed)
			(pads allowed)
			(copperpour not_allowed)
			(footprints allowed)
		)
		(placement
			(enabled no)
			(sheetname "")
		)
		(fill
			(thermal_gap 0.5)
			(thermal_bridge_width 0.5)
			(island_removal_mode 0)
		)
		(polygon
			(pts
				(xy 288.770314 -151.176482) (xy 289.329114 -151.176482) (xy 289.329114 -152.979882) (xy 288.770314 -152.979882)
			)
		)
	)
	(zone
		(layer "In12.Cu")
		(hatch none 0.5)
		(connect_pads
			(clearance 0)
		)
		(min_thickness 0.25)
		(keepout
			(tracks not_allowed)
			(vias allowed)
			(pads allowed)
			(copperpour not_allowed)
			(footprints allowed)
		)
		(placement
			(enabled no)
			(sheetname "")
		)
		(fill
			(thermal_gap 0.5)
			(thermal_bridge_width 0.5)
			(island_removal_mode 0)
		)
		(polygon
			(pts
				(xy 103.370126 -4.720082) (xy 103.928926 -4.720082) (xy 103.928926 -6.523482) (xy 103.370126 -6.523482)
			)
		)
	)
	(zone
		(layer "In12.Cu")
		(hatch none 0.5)
		(connect_pads
			(clearance 0)
		)
		(min_thickness 0.25)
		(keepout
			(tracks not_allowed)
			(vias allowed)
			(pads allowed)
			(copperpour not_allowed)
			(footprints allowed)
		)
		(placement
			(enabled no)
			(sheetname "")
		)
		(fill
			(thermal_gap 0.5)
			(thermal_bridge_width 0.5)
			(island_removal_mode 0)
		)
		(polygon
			(pts
				(xy 219.070428 -14.321282) (xy 219.629228 -14.321282) (xy 219.629228 -16.124682) (xy 219.070428 -16.124682)
			)
		)
	)
	(zone
		(layer "In12.Cu")
		(hatch none 0.5)
		(connect_pads
			(clearance 0)
		)
		(min_thickness 0.25)
		(keepout
			(tracks not_allowed)
			(vias allowed)
			(pads allowed)
			(copperpour not_allowed)
			(footprints allowed)
		)
		(placement
			(enabled no)
			(sheetname "")
		)
		(fill
			(thermal_gap 0.5)
			(thermal_bridge_width 0.5)
			(island_removal_mode 0)
		)
		(polygon
			(pts
				(xy 63.41999 -136.975342) (xy 63.97879 -136.975342) (xy 63.97879 -138.778742) (xy 63.41999 -138.778742)
			)
		)
	)
	(zone
		(layer "In12.Cu")
		(hatch none 0.5)
		(connect_pads
			(clearance 0)
		)
		(min_thickness 0.25)
		(keepout
			(tracks not_allowed)
			(vias allowed)
			(pads allowed)
			(copperpour not_allowed)
			(footprints allowed)
		)
		(placement
			(enabled no)
			(sheetname "")
		)
		(fill
			(thermal_gap 0.5)
			(thermal_bridge_width 0.5)
			(island_removal_mode 0)
		)
		(polygon
			(pts
				(xy 57.47004 -23.922482) (xy 58.02884 -23.922482) (xy 58.02884 -25.725882) (xy 57.47004 -25.725882)
			)
		)
	)
	(zone
		(layer "In12.Cu")
		(hatch none 0.5)
		(connect_pads
			(clearance 0)
		)
		(min_thickness 0.25)
		(keepout
			(tracks not_allowed)
			(vias allowed)
			(pads allowed)
			(copperpour not_allowed)
			(footprints allowed)
		)
		(placement
			(enabled no)
			(sheetname "")
		)
		(fill
			(thermal_gap 0.5)
			(thermal_bridge_width 0.5)
			(island_removal_mode 0)
		)
		(polygon
			(pts
				(xy 52.369974 -9.721342) (xy 52.928774 -9.721342) (xy 52.928774 -11.524742) (xy 52.369974 -11.524742)
			)
		)
	)
	(zone
		(layer "In12.Cu")
		(hatch none 0.5)
		(connect_pads
			(clearance 0)
		)
		(min_thickness 0.25)
		(keepout
			(tracks not_allowed)
			(vias allowed)
			(pads allowed)
			(copperpour not_allowed)
			(footprints allowed)
		)
		(placement
			(enabled no)
			(sheetname "")
		)
		(fill
			(thermal_gap 0.5)
			(thermal_bridge_width 0.5)
			(island_removal_mode 0)
		)
		(polygon
			(pts
				(xy 37.07003 -4.720082) (xy 37.62883 -4.720082) (xy 37.62883 -6.523482) (xy 37.07003 -6.523482)
			)
		)
	)
	(zone
		(layer "In12.Cu")
		(hatch none 0.5)
		(connect_pads
			(clearance 0)
		)
		(min_thickness 0.25)
		(keepout
			(tracks not_allowed)
			(vias allowed)
			(pads allowed)
			(copperpour not_allowed)
			(footprints allowed)
		)
		(placement
			(enabled no)
			(sheetname "")
		)
		(fill
			(thermal_gap 0.5)
			(thermal_bridge_width 0.5)
			(island_removal_mode 0)
		)
		(polygon
			(pts
				(xy 223.320356 -19.322542) (xy 223.879156 -19.322542) (xy 223.879156 -21.125942) (xy 223.320356 -21.125942)
			)
		)
	)
	(zone
		(layer "In12.Cu")
		(hatch none 0.5)
		(connect_pads
			(clearance 0)
		)
		(min_thickness 0.25)
		(keepout
			(tracks not_allowed)
			(vias allowed)
			(pads allowed)
			(copperpour not_allowed)
			(footprints allowed)
		)
		(placement
			(enabled no)
			(sheetname "")
		)
		(fill
			(thermal_gap 0.5)
			(thermal_bridge_width 0.5)
			(island_removal_mode 0)
		)
		(polygon
			(pts
				(xy 145.869914 -151.176482) (xy 146.428714 -151.176482) (xy 146.428714 -152.979882) (xy 145.869914 -152.979882)
			)
		)
	)
	(zone
		(layer "In12.Cu")
		(hatch none 0.5)
		(connect_pads
			(clearance 0)
		)
		(min_thickness 0.25)
		(keepout
			(tracks not_allowed)
			(vias allowed)
			(pads allowed)
			(copperpour not_allowed)
			(footprints allowed)
		)
		(placement
			(enabled no)
			(sheetname "")
		)
		(fill
			(thermal_gap 0.5)
			(thermal_bridge_width 0.5)
			(island_removal_mode 0)
		)
		(polygon
			(pts
				(xy 81.270094 -4.720082) (xy 81.828894 -4.720082) (xy 81.828894 -6.523482) (xy 81.270094 -6.523482)
			)
		)
	)
	(zone
		(layer "In12.Cu")
		(hatch none 0.5)
		(connect_pads
			(clearance 0)
		)
		(min_thickness 0.25)
		(keepout
			(tracks not_allowed)
			(vias allowed)
			(pads allowed)
			(copperpour not_allowed)
			(footprints allowed)
		)
		(placement
			(enabled no)
			(sheetname "")
		)
		(fill
			(thermal_gap 0.5)
			(thermal_bridge_width 0.5)
			(island_removal_mode 0)
		)
		(polygon
			(pts
				(xy 249.67057 -127.374142) (xy 250.22937 -127.374142) (xy 250.22937 -129.177542) (xy 249.67057 -129.177542)
			)
		)
	)
	(zone
		(layer "In12.Cu")
		(hatch none 0.5)
		(connect_pads
			(clearance 0)
		)
		(min_thickness 0.25)
		(keepout
			(tracks not_allowed)
			(vias allowed)
			(pads allowed)
			(copperpour not_allowed)
			(footprints allowed)
		)
		(placement
			(enabled no)
			(sheetname "")
		)
		(fill
			(thermal_gap 0.5)
			(thermal_bridge_width 0.5)
			(island_removal_mode 0)
		)
		(polygon
			(pts
				(xy 236.070394 -127.374142) (xy 236.629194 -127.374142) (xy 236.629194 -129.177542) (xy 236.070394 -129.177542)
			)
		)
	)
	(zone
		(layer "In12.Cu")
		(hatch none 0.5)
		(connect_pads
			(clearance 0)
		)
		(min_thickness 0.25)
		(keepout
			(tracks not_allowed)
			(vias allowed)
			(pads allowed)
			(copperpour not_allowed)
			(footprints allowed)
		)
		(placement
			(enabled no)
			(sheetname "")
		)
		(fill
			(thermal_gap 0.5)
			(thermal_bridge_width 0.5)
			(island_removal_mode 0)
		)
		(polygon
			(pts
				(xy 126.320042 -136.975342) (xy 126.878842 -136.975342) (xy 126.878842 -138.778742) (xy 126.320042 -138.778742)
			)
		)
	)
	(zone
		(layer "In12.Cu")
		(hatch none 0.5)
		(connect_pads
			(clearance 0)
		)
		(min_thickness 0.25)
		(keepout
			(tracks not_allowed)
			(vias allowed)
			(pads allowed)
			(copperpour not_allowed)
			(footprints allowed)
		)
		(placement
			(enabled no)
			(sheetname "")
		)
		(fill
			(thermal_gap 0.5)
			(thermal_bridge_width 0.5)
			(island_removal_mode 0)
		)
		(polygon
			(pts
				(xy 111.020098 -0.120142) (xy 111.578898 -0.120142) (xy 111.578898 -1.923542) (xy 111.020098 -1.923542)
			)
		)
	)
	(zone
		(layer "In12.Cu")
		(hatch none 0.5)
		(connect_pads
			(clearance 0)
		)
		(min_thickness 0.25)
		(keepout
			(tracks not_allowed)
			(vias allowed)
			(pads allowed)
			(copperpour not_allowed)
			(footprints allowed)
		)
		(placement
			(enabled no)
			(sheetname "")
		)
		(fill
			(thermal_gap 0.5)
			(thermal_bridge_width 0.5)
			(island_removal_mode 0)
		)
		(polygon
			(pts
				(xy 253.070614 -9.721342) (xy 253.629414 -9.721342) (xy 253.629414 -11.524742) (xy 253.070614 -11.524742)
			)
		)
	)
	(zone
		(layer "In12.Cu")
		(hatch none 0.5)
		(connect_pads
			(clearance 0)
		)
		(min_thickness 0.25)
		(keepout
			(tracks not_allowed)
			(vias allowed)
			(pads allowed)
			(copperpour not_allowed)
			(footprints allowed)
		)
		(placement
			(enabled no)
			(sheetname "")
		)
		(fill
			(thermal_gap 0.5)
			(thermal_bridge_width 0.5)
			(island_removal_mode 0)
		)
		(polygon
			(pts
				(xy 242.870482 -14.321282) (xy 243.429282 -14.321282) (xy 243.429282 -16.124682) (xy 242.870482 -16.124682)
			)
		)
	)
	(zone
		(layer "In12.Cu")
		(hatch none 0.5)
		(connect_pads
			(clearance 0)
		)
		(min_thickness 0.25)
		(keepout
			(tracks not_allowed)
			(vias allowed)
			(pads allowed)
			(copperpour not_allowed)
			(footprints allowed)
		)
		(placement
			(enabled no)
			(sheetname "")
		)
		(fill
			(thermal_gap 0.5)
			(thermal_bridge_width 0.5)
			(island_removal_mode 0)
		)
		(polygon
			(pts
				(xy 216.520522 -141.575282) (xy 217.079322 -141.575282) (xy 217.079322 -143.378682) (xy 216.520522 -143.378682)
			)
		)
	)
	(zone
		(layer "In12.Cu")
		(hatch none 0.5)
		(connect_pads
			(clearance 0)
		)
		(min_thickness 0.25)
		(keepout
			(tracks not_allowed)
			(vias allowed)
			(pads allowed)
			(copperpour not_allowed)
			(footprints allowed)
		)
		(placement
			(enabled no)
			(sheetname "")
		)
		(fill
			(thermal_gap 0.5)
			(thermal_bridge_width 0.5)
			(island_removal_mode 0)
		)
		(polygon
			(pts
				(xy 283.670502 -19.322542) (xy 284.229302 -19.322542) (xy 284.229302 -21.125942) (xy 283.670502 -21.125942)
			)
		)
	)
	(zone
		(layer "In12.Cu")
		(hatch none 0.5)
		(connect_pads
			(clearance 0)
		)
		(min_thickness 0.25)
		(keepout
			(tracks not_allowed)
			(vias allowed)
			(pads allowed)
			(copperpour not_allowed)
			(footprints allowed)
		)
		(placement
			(enabled no)
			(sheetname "")
		)
		(fill
			(thermal_gap 0.5)
			(thermal_bridge_width 0.5)
			(island_removal_mode 0)
		)
		(polygon
			(pts
				(xy 64.270128 -146.576542) (xy 64.828928 -146.576542) (xy 64.828928 -148.379942) (xy 64.270128 -148.379942)
			)
		)
	)
	(zone
		(layer "In12.Cu")
		(hatch none 0.5)
		(connect_pads
			(clearance 0)
		)
		(min_thickness 0.25)
		(keepout
			(tracks not_allowed)
			(vias allowed)
			(pads allowed)
			(copperpour not_allowed)
			(footprints allowed)
		)
		(placement
			(enabled no)
			(sheetname "")
		)
		(fill
			(thermal_gap 0.5)
			(thermal_bridge_width 0.5)
			(island_removal_mode 0)
		)
		(polygon
			(pts
				(xy 292.170358 -141.575282) (xy 292.729158 -141.575282) (xy 292.729158 -143.378682) (xy 292.170358 -143.378682)
			)
		)
	)
	(zone
		(layer "In12.Cu")
		(hatch none 0.5)
		(connect_pads
			(clearance 0)
		)
		(min_thickness 0.25)
		(keepout
			(tracks not_allowed)
			(vias allowed)
			(pads allowed)
			(copperpour not_allowed)
			(footprints allowed)
		)
		(placement
			(enabled no)
			(sheetname "")
		)
		(fill
			(thermal_gap 0.5)
			(thermal_bridge_width 0.5)
			(island_removal_mode 0)
		)
		(polygon
			(pts
				(xy 248.820432 -131.974082) (xy 249.379232 -131.974082) (xy 249.379232 -133.777482) (xy 248.820432 -133.777482)
			)
		)
	)
	(zone
		(layer "In12.Cu")
		(hatch none 0.5)
		(connect_pads
			(clearance 0)
		)
		(min_thickness 0.25)
		(keepout
			(tracks not_allowed)
			(vias allowed)
			(pads allowed)
			(copperpour not_allowed)
			(footprints allowed)
		)
		(placement
			(enabled no)
			(sheetname "")
		)
		(fill
			(thermal_gap 0.5)
			(thermal_bridge_width 0.5)
			(island_removal_mode 0)
		)
		(polygon
			(pts
				(xy 71.9201 -151.176482) (xy 72.4789 -151.176482) (xy 72.4789 -152.979882) (xy 71.9201 -152.979882)
			)
		)
	)
	(zone
		(layer "In12.Cu")
		(hatch none 0.5)
		(connect_pads
			(clearance 0)
		)
		(min_thickness 0.25)
		(keepout
			(tracks not_allowed)
			(vias allowed)
			(pads allowed)
			(copperpour not_allowed)
			(footprints allowed)
		)
		(placement
			(enabled no)
			(sheetname "")
		)
		(fill
			(thermal_gap 0.5)
			(thermal_bridge_width 0.5)
			(island_removal_mode 0)
		)
		(polygon
			(pts
				(xy 61.719968 -136.975342) (xy 62.278768 -136.975342) (xy 62.278768 -138.778742) (xy 61.719968 -138.778742)
			)
		)
	)
	(zone
		(layer "In12.Cu")
		(hatch none 0.5)
		(connect_pads
			(clearance 0)
		)
		(min_thickness 0.25)
		(keepout
			(tracks not_allowed)
			(vias allowed)
			(pads allowed)
			(copperpour not_allowed)
			(footprints allowed)
		)
		(placement
			(enabled no)
			(sheetname "")
		)
		(fill
			(thermal_gap 0.5)
			(thermal_bridge_width 0.5)
			(island_removal_mode 0)
		)
		(polygon
			(pts
				(xy 110.16996 -0.120142) (xy 110.72876 -0.120142) (xy 110.72876 -1.923542) (xy 110.16996 -1.923542)
			)
		)
	)
	(zone
		(layer "In12.Cu")
		(hatch none 0.5)
		(connect_pads
			(clearance 0)
		)
		(min_thickness 0.25)
		(keepout
			(tracks not_allowed)
			(vias allowed)
			(pads allowed)
			(copperpour not_allowed)
			(footprints allowed)
		)
		(placement
			(enabled no)
			(sheetname "")
		)
		(fill
			(thermal_gap 0.5)
			(thermal_bridge_width 0.5)
			(island_removal_mode 0)
		)
		(polygon
			(pts
				(xy 304.070512 -141.575282) (xy 304.629312 -141.575282) (xy 304.629312 -143.378682) (xy 304.070512 -143.378682)
			)
		)
	)
	(zone
		(layer "In12.Cu")
		(hatch none 0.5)
		(connect_pads
			(clearance 0)
		)
		(min_thickness 0.25)
		(keepout
			(tracks not_allowed)
			(vias allowed)
			(pads allowed)
			(copperpour not_allowed)
			(footprints allowed)
		)
		(placement
			(enabled no)
			(sheetname "")
		)
		(fill
			(thermal_gap 0.5)
			(thermal_bridge_width 0.5)
			(island_removal_mode 0)
		)
		(polygon
			(pts
				(xy 287.92043 -136.975342) (xy 288.47923 -136.975342) (xy 288.47923 -138.778742) (xy 287.92043 -138.778742)
			)
		)
	)
	(zone
		(layer "In12.Cu")
		(hatch none 0.5)
		(connect_pads
			(clearance 0)
		)
		(min_thickness 0.25)
		(keepout
			(tracks not_allowed)
			(vias allowed)
			(pads allowed)
			(copperpour not_allowed)
			(footprints allowed)
		)
		(placement
			(enabled no)
			(sheetname "")
		)
		(fill
			(thermal_gap 0.5)
			(thermal_bridge_width 0.5)
			(island_removal_mode 0)
		)
		(polygon
			(pts
				(xy 280.270458 -9.721342) (xy 280.829258 -9.721342) (xy 280.829258 -11.524742) (xy 280.270458 -11.524742)
			)
		)
	)
	(zone
		(layer "In12.Cu")
		(hatch none 0.5)
		(connect_pads
			(clearance 0)
		)
		(min_thickness 0.25)
		(keepout
			(tracks not_allowed)
			(vias allowed)
			(pads allowed)
			(copperpour not_allowed)
			(footprints allowed)
		)
		(placement
			(enabled no)
			(sheetname "")
		)
		(fill
			(thermal_gap 0.5)
			(thermal_bridge_width 0.5)
			(island_removal_mode 0)
		)
		(polygon
			(pts
				(xy 12.85494 -96.86036) (xy 14.25194 -96.86036) (xy 14.25194 -97.36836) (xy 12.85494 -97.36836)
			)
		)
	)
	(zone
		(layer "In12.Cu")
		(hatch none 0.5)
		(connect_pads
			(clearance 0)
		)
		(min_thickness 0.25)
		(keepout
			(tracks not_allowed)
			(vias allowed)
			(pads allowed)
			(copperpour not_allowed)
			(footprints allowed)
		)
		(placement
			(enabled no)
			(sheetname "")
		)
		(fill
			(thermal_gap 0.5)
			(thermal_bridge_width 0.5)
			(island_removal_mode 0)
		)
		(polygon
			(pts
				(xy 289.620452 -146.576542) (xy 290.179252 -146.576542) (xy 290.179252 -148.379942) (xy 289.620452 -148.379942)
			)
		)
	)
	(zone
		(layer "In12.Cu")
		(hatch none 0.5)
		(connect_pads
			(clearance 0)
		)
		(min_thickness 0.25)
		(keepout
			(tracks not_allowed)
			(vias allowed)
			(pads allowed)
			(copperpour not_allowed)
			(footprints allowed)
		)
		(placement
			(enabled no)
			(sheetname "")
		)
		(fill
			(thermal_gap 0.5)
			(thermal_bridge_width 0.5)
			(island_removal_mode 0)
		)
		(polygon
			(pts
				(xy 208.87055 -23.922482) (xy 209.42935 -23.922482) (xy 209.42935 -25.725882) (xy 208.87055 -25.725882)
			)
		)
	)
	(zone
		(layer "In12.Cu")
		(hatch none 0.5)
		(connect_pads
			(clearance 0)
		)
		(min_thickness 0.25)
		(keepout
			(tracks not_allowed)
			(vias allowed)
			(pads allowed)
			(copperpour not_allowed)
			(footprints allowed)
		)
		(placement
			(enabled no)
			(sheetname "")
		)
		(fill
			(thermal_gap 0.5)
			(thermal_bridge_width 0.5)
			(island_removal_mode 0)
		)
		(polygon
			(pts
				(xy 266.670536 -19.322542) (xy 267.229336 -19.322542) (xy 267.229336 -21.125942) (xy 266.670536 -21.125942)
			)
		)
	)
	(zone
		(layer "In12.Cu")
		(hatch none 0.5)
		(connect_pads
			(clearance 0)
		)
		(min_thickness 0.25)
		(keepout
			(tracks not_allowed)
			(vias allowed)
			(pads allowed)
			(copperpour not_allowed)
			(footprints allowed)
		)
		(placement
			(enabled no)
			(sheetname "")
		)
		(fill
			(thermal_gap 0.5)
			(thermal_bridge_width 0.5)
			(island_removal_mode 0)
		)
		(polygon
			(pts
				(xy 408.6606 -146.58848) (xy 408.6606 -147.35048) (xy 409.6512 -147.35048) (xy 409.6512 -146.58848)
			)
		)
	)
	(zone
		(layer "In12.Cu")
		(hatch none 0.5)
		(connect_pads
			(clearance 0)
		)
		(min_thickness 0.25)
		(keepout
			(tracks not_allowed)
			(vias allowed)
			(pads allowed)
			(copperpour not_allowed)
			(footprints allowed)
		)
		(placement
			(enabled no)
			(sheetname "")
		)
		(fill
			(thermal_gap 0.5)
			(thermal_bridge_width 0.5)
			(island_removal_mode 0)
		)
		(polygon
			(pts
				(xy 107.620054 -14.321282) (xy 108.178854 -14.321282) (xy 108.178854 -16.124682) (xy 107.620054 -16.124682)
			)
		)
	)
	(zone
		(layer "In12.Cu")
		(hatch none 0.5)
		(connect_pads
			(clearance 0)
		)
		(min_thickness 0.25)
		(keepout
			(tracks not_allowed)
			(vias allowed)
			(pads allowed)
			(copperpour not_allowed)
			(footprints allowed)
		)
		(placement
			(enabled no)
			(sheetname "")
		)
		(fill
			(thermal_gap 0.5)
			(thermal_bridge_width 0.5)
			(island_removal_mode 0)
		)
		(polygon
			(pts
				(xy 76.170282 -4.720082) (xy 76.729082 -4.720082) (xy 76.729082 -6.523482) (xy 76.170282 -6.523482)
			)
		)
	)
	(zone
		(layer "In12.Cu")
		(hatch none 0.5)
		(connect_pads
			(clearance 0)
		)
		(min_thickness 0.25)
		(keepout
			(tracks not_allowed)
			(vias allowed)
			(pads allowed)
			(copperpour not_allowed)
			(footprints allowed)
		)
		(placement
			(enabled no)
			(sheetname "")
		)
		(fill
			(thermal_gap 0.5)
			(thermal_bridge_width 0.5)
			(island_removal_mode 0)
		)
		(polygon
			(pts
				(xy 126.320042 -19.322542) (xy 126.878842 -19.322542) (xy 126.878842 -21.125942) (xy 126.320042 -21.125942)
			)
		)
	)
	(zone
		(layer "In12.Cu")
		(hatch none 0.5)
		(connect_pads
			(clearance 0)
		)
		(min_thickness 0.25)
		(keepout
			(tracks not_allowed)
			(vias allowed)
			(pads allowed)
			(copperpour not_allowed)
			(footprints allowed)
		)
		(placement
			(enabled no)
			(sheetname "")
		)
		(fill
			(thermal_gap 0.5)
			(thermal_bridge_width 0.5)
			(island_removal_mode 0)
		)
		(polygon
			(pts
				(xy 62.570106 -131.974082) (xy 63.128906 -131.974082) (xy 63.128906 -133.777482) (xy 62.570106 -133.777482)
			)
		)
	)
	(zone
		(layer "In12.Cu")
		(hatch none 0.5)
		(connect_pads
			(clearance 0)
		)
		(min_thickness 0.25)
		(keepout
			(tracks not_allowed)
			(vias allowed)
			(pads allowed)
			(copperpour not_allowed)
			(footprints allowed)
		)
		(placement
			(enabled no)
			(sheetname "")
		)
		(fill
			(thermal_gap 0.5)
			(thermal_bridge_width 0.5)
			(island_removal_mode 0)
		)
		(polygon
			(pts
				(xy 109.320076 -14.321282) (xy 109.878876 -14.321282) (xy 109.878876 -16.124682) (xy 109.320076 -16.124682)
			)
		)
	)
	(zone
		(layer "In12.Cu")
		(hatch none 0.5)
		(connect_pads
			(clearance 0)
		)
		(min_thickness 0.25)
		(keepout
			(tracks not_allowed)
			(vias allowed)
			(pads allowed)
			(copperpour not_allowed)
			(footprints allowed)
		)
		(placement
			(enabled no)
			(sheetname "")
		)
		(fill
			(thermal_gap 0.5)
			(thermal_bridge_width 0.5)
			(island_removal_mode 0)
		)
		(polygon
			(pts
				(xy 91.469972 -127.374142) (xy 92.028772 -127.374142) (xy 92.028772 -129.177542) (xy 91.469972 -129.177542)
			)
		)
	)
	(zone
		(layer "In12.Cu")
		(hatch none 0.5)
		(connect_pads
			(clearance 0)
		)
		(min_thickness 0.25)
		(keepout
			(tracks not_allowed)
			(vias allowed)
			(pads allowed)
			(copperpour not_allowed)
			(footprints allowed)
		)
		(placement
			(enabled no)
			(sheetname "")
		)
		(fill
			(thermal_gap 0.5)
			(thermal_bridge_width 0.5)
			(island_removal_mode 0)
		)
		(polygon
			(pts
				(xy 87.220044 -151.176482) (xy 87.778844 -151.176482) (xy 87.778844 -152.979882) (xy 87.220044 -152.979882)
			)
		)
	)
	(zone
		(layer "In12.Cu")
		(hatch none 0.5)
		(connect_pads
			(clearance 0)
		)
		(min_thickness 0.25)
		(keepout
			(tracks not_allowed)
			(vias allowed)
			(pads allowed)
			(copperpour not_allowed)
			(footprints allowed)
		)
		(placement
			(enabled no)
			(sheetname "")
		)
		(fill
			(thermal_gap 0.5)
			(thermal_bridge_width 0.5)
			(island_removal_mode 0)
		)
		(polygon
			(pts
				(xy 225.020378 -146.576542) (xy 225.579178 -146.576542) (xy 225.579178 -148.379942) (xy 225.020378 -148.379942)
			)
		)
	)
	(zone
		(layer "In12.Cu")
		(hatch none 0.5)
		(connect_pads
			(clearance 0)
		)
		(min_thickness 0.25)
		(keepout
			(tracks not_allowed)
			(vias allowed)
			(pads allowed)
			(copperpour not_allowed)
			(footprints allowed)
		)
		(placement
			(enabled no)
			(sheetname "")
		)
		(fill
			(thermal_gap 0.5)
			(thermal_bridge_width 0.5)
			(island_removal_mode 0)
		)
		(polygon
			(pts
				(xy 118.67007 -141.575282) (xy 119.22887 -141.575282) (xy 119.22887 -143.378682) (xy 118.67007 -143.378682)
			)
		)
	)
	(zone
		(layer "In12.Cu")
		(hatch none 0.5)
		(connect_pads
			(clearance 0)
		)
		(min_thickness 0.25)
		(keepout
			(tracks not_allowed)
			(vias allowed)
			(pads allowed)
			(copperpour not_allowed)
			(footprints allowed)
		)
		(placement
			(enabled no)
			(sheetname "")
		)
		(fill
			(thermal_gap 0.5)
			(thermal_bridge_width 0.5)
			(island_removal_mode 0)
		)
		(polygon
			(pts
				(xy 293.020496 -9.721342) (xy 293.579296 -9.721342) (xy 293.579296 -11.524742) (xy 293.020496 -11.524742)
			)
		)
	)
	(zone
		(layer "In12.Cu")
		(hatch none 0.5)
		(connect_pads
			(clearance 0)
		)
		(min_thickness 0.25)
		(keepout
			(tracks not_allowed)
			(vias allowed)
			(pads allowed)
			(copperpour not_allowed)
			(footprints allowed)
		)
		(placement
			(enabled no)
			(sheetname "")
		)
		(fill
			(thermal_gap 0.5)
			(thermal_bridge_width 0.5)
			(island_removal_mode 0)
		)
		(polygon
			(pts
				(xy 287.070546 -131.974082) (xy 287.629346 -131.974082) (xy 287.629346 -133.777482) (xy 287.070546 -133.777482)
			)
		)
	)
	(zone
		(layer "In12.Cu")
		(hatch none 0.5)
		(connect_pads
			(clearance 0)
		)
		(min_thickness 0.25)
		(keepout
			(tracks not_allowed)
			(vias allowed)
			(pads allowed)
			(copperpour not_allowed)
			(footprints allowed)
		)
		(placement
			(enabled no)
			(sheetname "")
		)
		(fill
			(thermal_gap 0.5)
			(thermal_bridge_width 0.5)
			(island_removal_mode 0)
		)
		(polygon
			(pts
				(xy 313.420506 -151.176482) (xy 313.979306 -151.176482) (xy 313.979306 -152.979882) (xy 313.420506 -152.979882)
			)
		)
	)
	(zone
		(layer "In12.Cu")
		(hatch none 0.5)
		(connect_pads
			(clearance 0)
		)
		(min_thickness 0.25)
		(keepout
			(tracks not_allowed)
			(vias allowed)
			(pads allowed)
			(copperpour not_allowed)
			(footprints allowed)
		)
		(placement
			(enabled no)
			(sheetname "")
		)
		(fill
			(thermal_gap 0.5)
			(thermal_bridge_width 0.5)
			(island_removal_mode 0)
		)
		(polygon
			(pts
				(xy 274.320508 -4.720082) (xy 274.879308 -4.720082) (xy 274.879308 -6.523482) (xy 274.320508 -6.523482)
			)
		)
	)
	(zone
		(layer "In12.Cu")
		(hatch none 0.5)
		(connect_pads
			(clearance 0)
		)
		(min_thickness 0.25)
		(keepout
			(tracks not_allowed)
			(vias allowed)
			(pads allowed)
			(copperpour not_allowed)
			(footprints allowed)
		)
		(placement
			(enabled no)
			(sheetname "")
		)
		(fill
			(thermal_gap 0.5)
			(thermal_bridge_width 0.5)
			(island_removal_mode 0)
		)
		(polygon
			(pts
				(xy 208.020412 -19.322542) (xy 208.579212 -19.322542) (xy 208.579212 -21.125942) (xy 208.020412 -21.125942)
			)
		)
	)
	(zone
		(layer "In12.Cu")
		(hatch none 0.5)
		(connect_pads
			(clearance 0)
		)
		(min_thickness 0.25)
		(keepout
			(tracks not_allowed)
			(vias allowed)
			(pads allowed)
			(copperpour not_allowed)
			(footprints allowed)
		)
		(placement
			(enabled no)
			(sheetname "")
		)
		(fill
			(thermal_gap 0.5)
			(thermal_bridge_width 0.5)
			(island_removal_mode 0)
		)
		(polygon
			(pts
				(xy 63.41999 -127.374142) (xy 63.97879 -127.374142) (xy 63.97879 -129.177542) (xy 63.41999 -129.177542)
			)
		)
	)
	(zone
		(layer "In12.Cu")
		(hatch none 0.5)
		(connect_pads
			(clearance 0)
		)
		(min_thickness 0.25)
		(keepout
			(tracks not_allowed)
			(vias allowed)
			(pads allowed)
			(copperpour not_allowed)
			(footprints allowed)
		)
		(placement
			(enabled no)
			(sheetname "")
		)
		(fill
			(thermal_gap 0.5)
			(thermal_bridge_width 0.5)
			(island_removal_mode 0)
		)
		(polygon
			(pts
				(xy 267.52042 -136.975342) (xy 268.07922 -136.975342) (xy 268.07922 -138.778742) (xy 267.52042 -138.778742)
			)
		)
	)
	(zone
		(layer "In12.Cu")
		(hatch none 0.5)
		(connect_pads
			(clearance 0)
		)
		(min_thickness 0.25)
		(keepout
			(tracks not_allowed)
			(vias allowed)
			(pads allowed)
			(copperpour not_allowed)
			(footprints allowed)
		)
		(placement
			(enabled no)
			(sheetname "")
		)
		(fill
			(thermal_gap 0.5)
			(thermal_bridge_width 0.5)
			(island_removal_mode 0)
		)
		(polygon
			(pts
				(xy 135.670036 -19.322542) (xy 136.228836 -19.322542) (xy 136.228836 -21.125942) (xy 135.670036 -21.125942)
			)
		)
	)
	(zone
		(layer "In12.Cu")
		(hatch none 0.5)
		(connect_pads
			(clearance 0)
		)
		(min_thickness 0.25)
		(keepout
			(tracks not_allowed)
			(vias allowed)
			(pads allowed)
			(copperpour not_allowed)
			(footprints allowed)
		)
		(placement
			(enabled no)
			(sheetname "")
		)
		(fill
			(thermal_gap 0.5)
			(thermal_bridge_width 0.5)
			(island_removal_mode 0)
		)
		(polygon
			(pts
				(xy 12.86002 -97.74428) (xy 14.25702 -97.74428) (xy 14.25702 -98.25228) (xy 12.86002 -98.25228)
			)
		)
	)
	(zone
		(layer "In12.Cu")
		(hatch none 0.5)
		(connect_pads
			(clearance 0)
		)
		(min_thickness 0.25)
		(keepout
			(tracks not_allowed)
			(vias allowed)
			(pads allowed)
			(copperpour not_allowed)
			(footprints allowed)
		)
		(placement
			(enabled no)
			(sheetname "")
		)
		(fill
			(thermal_gap 0.5)
			(thermal_bridge_width 0.5)
			(island_removal_mode 0)
		)
		(polygon
			(pts
				(xy 307.470302 -141.575282) (xy 308.029102 -141.575282) (xy 308.029102 -143.378682) (xy 307.470302 -143.378682)
			)
		)
	)
	(zone
		(layer "In12.Cu")
		(hatch none 0.5)
		(connect_pads
			(clearance 0)
		)
		(min_thickness 0.25)
		(keepout
			(tracks not_allowed)
			(vias allowed)
			(pads allowed)
			(copperpour not_allowed)
			(footprints allowed)
		)
		(placement
			(enabled no)
			(sheetname "")
		)
		(fill
			(thermal_gap 0.5)
			(thermal_bridge_width 0.5)
			(island_removal_mode 0)
		)
		(polygon
			(pts
				(xy 34.520124 -141.575282) (xy 35.078924 -141.575282) (xy 35.078924 -143.378682) (xy 34.520124 -143.378682)
			)
		)
	)
	(zone
		(layer "In12.Cu")
		(hatch none 0.5)
		(connect_pads
			(clearance 0)
		)
		(min_thickness 0.25)
		(keepout
			(tracks not_allowed)
			(vias allowed)
			(pads allowed)
			(copperpour not_allowed)
			(footprints allowed)
		)
		(placement
			(enabled no)
			(sheetname "")
		)
		(fill
			(thermal_gap 0.5)
			(thermal_bridge_width 0.5)
			(island_removal_mode 0)
		)
		(polygon
			(pts
				(xy 63.41999 -146.576542) (xy 63.97879 -146.576542) (xy 63.97879 -148.379942) (xy 63.41999 -148.379942)
			)
		)
	)
	(zone
		(layer "In12.Cu")
		(hatch none 0.5)
		(connect_pads
			(clearance 0)
		)
		(min_thickness 0.25)
		(keepout
			(tracks not_allowed)
			(vias allowed)
			(pads allowed)
			(copperpour not_allowed)
			(footprints allowed)
		)
		(placement
			(enabled no)
			(sheetname "")
		)
		(fill
			(thermal_gap 0.5)
			(thermal_bridge_width 0.5)
			(island_removal_mode 0)
		)
		(polygon
			(pts
				(xy 197.820534 -14.321282) (xy 198.379334 -14.321282) (xy 198.379334 -16.124682) (xy 197.820534 -16.124682)
			)
		)
	)
	(zone
		(layer "In12.Cu")
		(hatch none 0.5)
		(connect_pads
			(clearance 0)
		)
		(min_thickness 0.25)
		(keepout
			(tracks not_allowed)
			(vias allowed)
			(pads allowed)
			(copperpour not_allowed)
			(footprints allowed)
		)
		(placement
			(enabled no)
			(sheetname "")
		)
		(fill
			(thermal_gap 0.5)
			(thermal_bridge_width 0.5)
			(island_removal_mode 0)
		)
		(polygon
			(pts
				(xy 308.32044 -146.576542) (xy 308.87924 -146.576542) (xy 308.87924 -148.379942) (xy 308.32044 -148.379942)
			)
		)
	)
	(zone
		(layer "In12.Cu")
		(hatch none 0.5)
		(connect_pads
			(clearance 0)
		)
		(min_thickness 0.25)
		(keepout
			(tracks not_allowed)
			(vias allowed)
			(pads allowed)
			(copperpour not_allowed)
			(footprints allowed)
		)
		(placement
			(enabled no)
			(sheetname "")
		)
		(fill
			(thermal_gap 0.5)
			(thermal_bridge_width 0.5)
			(island_removal_mode 0)
		)
		(polygon
			(pts
				(xy 219.070428 -4.720082) (xy 219.629228 -4.720082) (xy 219.629228 -6.523482) (xy 219.070428 -6.523482)
			)
		)
	)
	(zone
		(layer "In12.Cu")
		(hatch none 0.5)
		(connect_pads
			(clearance 0)
		)
		(min_thickness 0.25)
		(keepout
			(tracks not_allowed)
			(vias allowed)
			(pads allowed)
			(copperpour not_allowed)
			(footprints allowed)
		)
		(placement
			(enabled no)
			(sheetname "")
		)
		(fill
			(thermal_gap 0.5)
			(thermal_bridge_width 0.5)
			(island_removal_mode 0)
		)
		(polygon
			(pts
				(xy 304.920396 -9.721342) (xy 305.479196 -9.721342) (xy 305.479196 -11.524742) (xy 304.920396 -11.524742)
			)
		)
	)
	(zone
		(layer "In12.Cu")
		(hatch none 0.5)
		(connect_pads
			(clearance 0)
		)
		(min_thickness 0.25)
		(keepout
			(tracks not_allowed)
			(vias allowed)
			(pads allowed)
			(copperpour not_allowed)
			(footprints allowed)
		)
		(placement
			(enabled no)
			(sheetname "")
		)
		(fill
			(thermal_gap 0.5)
			(thermal_bridge_width 0.5)
			(island_removal_mode 0)
		)
		(polygon
			(pts
				(xy 297.270424 -19.322542) (xy 297.829224 -19.322542) (xy 297.829224 -21.125942) (xy 297.270424 -21.125942)
			)
		)
	)
	(zone
		(layer "In12.Cu")
		(hatch none 0.5)
		(connect_pads
			(clearance 0)
		)
		(min_thickness 0.25)
		(keepout
			(tracks not_allowed)
			(vias allowed)
			(pads allowed)
			(copperpour not_allowed)
			(footprints allowed)
		)
		(placement
			(enabled no)
			(sheetname "")
		)
		(fill
			(thermal_gap 0.5)
			(thermal_bridge_width 0.5)
			(island_removal_mode 0)
		)
		(polygon
			(pts
				(xy 50.669952 -146.576542) (xy 51.228752 -146.576542) (xy 51.228752 -148.379942) (xy 50.669952 -148.379942)
			)
		)
	)
	(zone
		(layer "In12.Cu")
		(hatch none 0.5)
		(connect_pads
			(clearance 0)
		)
		(min_thickness 0.25)
		(keepout
			(tracks not_allowed)
			(vias allowed)
			(pads allowed)
			(copperpour not_allowed)
			(footprints allowed)
		)
		(placement
			(enabled no)
			(sheetname "")
		)
		(fill
			(thermal_gap 0.5)
			(thermal_bridge_width 0.5)
			(island_removal_mode 0)
		)
		(polygon
			(pts
				(xy 293.020496 -141.575282) (xy 293.579296 -141.575282) (xy 293.579296 -143.378682) (xy 293.020496 -143.378682)
			)
		)
	)
	(zone
		(layer "In12.Cu")
		(hatch none 0.5)
		(connect_pads
			(clearance 0)
		)
		(min_thickness 0.25)
		(keepout
			(tracks not_allowed)
			(vias allowed)
			(pads allowed)
			(copperpour not_allowed)
			(footprints allowed)
		)
		(placement
			(enabled no)
			(sheetname "")
		)
		(fill
			(thermal_gap 0.5)
			(thermal_bridge_width 0.5)
			(island_removal_mode 0)
		)
		(polygon
			(pts
				(xy 219.920566 -9.721342) (xy 220.479366 -9.721342) (xy 220.479366 -11.524742) (xy 219.920566 -11.524742)
			)
		)
	)
	(zone
		(layer "In12.Cu")
		(hatch none 0.5)
		(connect_pads
			(clearance 0)
		)
		(min_thickness 0.25)
		(keepout
			(tracks not_allowed)
			(vias allowed)
			(pads allowed)
			(copperpour not_allowed)
			(footprints allowed)
		)
		(placement
			(enabled no)
			(sheetname "")
		)
		(fill
			(thermal_gap 0.5)
			(thermal_bridge_width 0.5)
			(island_removal_mode 0)
		)
		(polygon
			(pts
				(xy 145.869914 -131.974082) (xy 146.428714 -131.974082) (xy 146.428714 -133.777482) (xy 145.869914 -133.777482)
			)
		)
	)
	(zone
		(layer "In12.Cu")
		(hatch none 0.5)
		(connect_pads
			(clearance 0)
		)
		(min_thickness 0.25)
		(keepout
			(tracks not_allowed)
			(vias allowed)
			(pads allowed)
			(copperpour not_allowed)
			(footprints allowed)
		)
		(placement
			(enabled no)
			(sheetname "")
		)
		(fill
			(thermal_gap 0.5)
			(thermal_bridge_width 0.5)
			(island_removal_mode 0)
		)
		(polygon
			(pts
				(xy 67.669918 -146.576542) (xy 68.228718 -146.576542) (xy 68.228718 -148.379942) (xy 67.669918 -148.379942)
			)
		)
	)
	(zone
		(layer "In12.Cu")
		(hatch none 0.5)
		(connect_pads
			(clearance 0)
		)
		(min_thickness 0.25)
		(keepout
			(tracks not_allowed)
			(vias allowed)
			(pads allowed)
			(copperpour not_allowed)
			(footprints allowed)
		)
		(placement
			(enabled no)
			(sheetname "")
		)
		(fill
			(thermal_gap 0.5)
			(thermal_bridge_width 0.5)
			(island_removal_mode 0)
		)
		(polygon
			(pts
				(xy 242.020852 -9.721342) (xy 242.579652 -9.721342) (xy 242.579652 -11.524742) (xy 242.020852 -11.524742)
			)
		)
	)
	(zone
		(layer "In12.Cu")
		(hatch none 0.5)
		(connect_pads
			(clearance 0)
		)
		(min_thickness 0.25)
		(keepout
			(tracks not_allowed)
			(vias allowed)
			(pads allowed)
			(copperpour not_allowed)
			(footprints allowed)
		)
		(placement
			(enabled no)
			(sheetname "")
		)
		(fill
			(thermal_gap 0.5)
			(thermal_bridge_width 0.5)
			(island_removal_mode 0)
		)
		(polygon
			(pts
				(xy 200.37044 -131.974082) (xy 200.92924 -131.974082) (xy 200.92924 -133.777482) (xy 200.37044 -133.777482)
			)
		)
	)
	(zone
		(layer "In12.Cu")
		(hatch none 0.5)
		(connect_pads
			(clearance 0)
		)
		(min_thickness 0.25)
		(keepout
			(tracks not_allowed)
			(vias allowed)
			(pads allowed)
			(copperpour not_allowed)
			(footprints allowed)
		)
		(placement
			(enabled no)
			(sheetname "")
		)
		(fill
			(thermal_gap 0.5)
			(thermal_bridge_width 0.5)
			(island_removal_mode 0)
		)
		(polygon
			(pts
				(xy 311.720484 -0.120142) (xy 312.279284 -0.120142) (xy 312.279284 -1.923542) (xy 311.720484 -1.923542)
			)
		)
	)
	(zone
		(layer "In12.Cu")
		(hatch none 0.5)
		(connect_pads
			(clearance 0)
		)
		(min_thickness 0.25)
		(keepout
			(tracks not_allowed)
			(vias allowed)
			(pads allowed)
			(copperpour not_allowed)
			(footprints allowed)
		)
		(placement
			(enabled no)
			(sheetname "")
		)
		(fill
			(thermal_gap 0.5)
			(thermal_bridge_width 0.5)
			(island_removal_mode 0)
		)
		(polygon
			(pts
				(xy 110.16996 -9.721342) (xy 110.72876 -9.721342) (xy 110.72876 -11.524742) (xy 110.16996 -11.524742)
			)
		)
	)
	(zone
		(layer "In12.Cu")
		(hatch none 0.5)
		(connect_pads
			(clearance 0)
		)
		(min_thickness 0.25)
		(keepout
			(tracks not_allowed)
			(vias allowed)
			(pads allowed)
			(copperpour not_allowed)
			(footprints allowed)
		)
		(placement
			(enabled no)
			(sheetname "")
		)
		(fill
			(thermal_gap 0.5)
			(thermal_bridge_width 0.5)
			(island_removal_mode 0)
		)
		(polygon
			(pts
				(xy 344.776806 -59.225434) (xy 344.776806 -61.511434) (xy 344.268806 -61.511434) (xy 344.268806 -59.225434)
			)
		)
	)
	(zone
		(layer "In12.Cu")
		(hatch none 0.5)
		(connect_pads
			(clearance 0)
		)
		(min_thickness 0.25)
		(keepout
			(tracks not_allowed)
			(vias allowed)
			(pads allowed)
			(copperpour not_allowed)
			(footprints allowed)
		)
		(placement
			(enabled no)
			(sheetname "")
		)
		(fill
			(thermal_gap 0.5)
			(thermal_bridge_width 0.5)
			(island_removal_mode 0)
		)
		(polygon
			(pts
				(xy 311.720484 -19.322542) (xy 312.279284 -19.322542) (xy 312.279284 -21.125942) (xy 311.720484 -21.125942)
			)
		)
	)
	(zone
		(layer "In12.Cu")
		(hatch none 0.5)
		(connect_pads
			(clearance 0)
		)
		(min_thickness 0.25)
		(keepout
			(tracks not_allowed)
			(vias allowed)
			(pads allowed)
			(copperpour not_allowed)
			(footprints allowed)
		)
		(placement
			(enabled no)
			(sheetname "")
		)
		(fill
			(thermal_gap 0.5)
			(thermal_bridge_width 0.5)
			(island_removal_mode 0)
		)
		(polygon
			(pts
				(xy 141.619986 -146.576542) (xy 142.178786 -146.576542) (xy 142.178786 -148.379942) (xy 141.619986 -148.379942)
			)
		)
	)
	(zone
		(layer "In12.Cu")
		(hatch none 0.5)
		(connect_pads
			(clearance 0)
		)
		(min_thickness 0.25)
		(keepout
			(tracks not_allowed)
			(vias allowed)
			(pads allowed)
			(copperpour not_allowed)
			(footprints allowed)
		)
		(placement
			(enabled no)
			(sheetname "")
		)
		(fill
			(thermal_gap 0.5)
			(thermal_bridge_width 0.5)
			(island_removal_mode 0)
		)
		(polygon
			(pts
				(xy 281.97048 -136.975342) (xy 282.52928 -136.975342) (xy 282.52928 -138.778742) (xy 281.97048 -138.778742)
			)
		)
	)
	(zone
		(layer "In12.Cu")
		(hatch none 0.5)
		(connect_pads
			(clearance 0)
		)
		(min_thickness 0.25)
		(keepout
			(tracks not_allowed)
			(vias allowed)
			(pads allowed)
			(copperpour not_allowed)
			(footprints allowed)
		)
		(placement
			(enabled no)
			(sheetname "")
		)
		(fill
			(thermal_gap 0.5)
			(thermal_bridge_width 0.5)
			(island_removal_mode 0)
		)
		(polygon
			(pts
				(xy 107.620054 -23.922482) (xy 108.178854 -23.922482) (xy 108.178854 -25.725882) (xy 107.620054 -25.725882)
			)
		)
	)
	(zone
		(layer "In12.Cu")
		(hatch none 0.5)
		(connect_pads
			(clearance 0)
		)
		(min_thickness 0.25)
		(keepout
			(tracks not_allowed)
			(vias allowed)
			(pads allowed)
			(copperpour not_allowed)
			(footprints allowed)
		)
		(placement
			(enabled no)
			(sheetname "")
		)
		(fill
			(thermal_gap 0.5)
			(thermal_bridge_width 0.5)
			(island_removal_mode 0)
		)
		(polygon
			(pts
				(xy 315.120528 -141.575282) (xy 315.679328 -141.575282) (xy 315.679328 -143.378682) (xy 315.120528 -143.378682)
			)
		)
	)
	(zone
		(layer "In12.Cu")
		(hatch none 0.5)
		(connect_pads
			(clearance 0)
		)
		(min_thickness 0.25)
		(keepout
			(tracks not_allowed)
			(vias allowed)
			(pads allowed)
			(copperpour not_allowed)
			(footprints allowed)
		)
		(placement
			(enabled no)
			(sheetname "")
		)
		(fill
			(thermal_gap 0.5)
			(thermal_bridge_width 0.5)
			(island_removal_mode 0)
		)
		(polygon
			(pts
				(xy 237.770416 -19.322542) (xy 238.329216 -19.322542) (xy 238.329216 -21.125942) (xy 237.770416 -21.125942)
			)
		)
	)
	(zone
		(layer "In12.Cu")
		(hatch none 0.5)
		(connect_pads
			(clearance 0)
		)
		(min_thickness 0.25)
		(keepout
			(tracks not_allowed)
			(vias allowed)
			(pads allowed)
			(copperpour not_allowed)
			(footprints allowed)
		)
		(placement
			(enabled no)
			(sheetname "")
		)
		(fill
			(thermal_gap 0.5)
			(thermal_bridge_width 0.5)
			(island_removal_mode 0)
		)
		(polygon
			(pts
				(xy 410.9212 -145.034) (xy 410.9212 -145.796) (xy 411.9118 -145.796) (xy 411.9118 -145.034)
			)
		)
	)
	(zone
		(layer "In12.Cu")
		(hatch none 0.5)
		(connect_pads
			(clearance 0)
		)
		(min_thickness 0.25)
		(keepout
			(tracks not_allowed)
			(vias allowed)
			(pads allowed)
			(copperpour not_allowed)
			(footprints allowed)
		)
		(placement
			(enabled no)
			(sheetname "")
		)
		(fill
			(thermal_gap 0.5)
			(thermal_bridge_width 0.5)
			(island_removal_mode 0)
		)
		(polygon
			(pts
				(xy 37.920168 -136.975342) (xy 38.478968 -136.975342) (xy 38.478968 -138.778742) (xy 37.920168 -138.778742)
			)
		)
	)
	(zone
		(layer "In12.Cu")
		(hatch none 0.5)
		(connect_pads
			(clearance 0)
		)
		(min_thickness 0.25)
		(keepout
			(tracks not_allowed)
			(vias allowed)
			(pads allowed)
			(copperpour not_allowed)
			(footprints allowed)
		)
		(placement
			(enabled no)
			(sheetname "")
		)
		(fill
			(thermal_gap 0.5)
			(thermal_bridge_width 0.5)
			(island_removal_mode 0)
		)
		(polygon
			(pts
				(xy 306.620418 -9.721342) (xy 307.179218 -9.721342) (xy 307.179218 -11.524742) (xy 306.620418 -11.524742)
			)
		)
	)
	(zone
		(layer "In12.Cu")
		(hatch none 0.5)
		(connect_pads
			(clearance 0)
		)
		(min_thickness 0.25)
		(keepout
			(tracks not_allowed)
			(vias allowed)
			(pads allowed)
			(copperpour not_allowed)
			(footprints allowed)
		)
		(placement
			(enabled no)
			(sheetname "")
		)
		(fill
			(thermal_gap 0.5)
			(thermal_bridge_width 0.5)
			(island_removal_mode 0)
		)
		(polygon
			(pts
				(xy 306.620418 -127.374142) (xy 307.179218 -127.374142) (xy 307.179218 -129.177542) (xy 306.620418 -129.177542)
			)
		)
	)
	(zone
		(net "PVDDQ_ABC")
		(layer "In12.Cu")
		(hatch none 0.5)
		(connect_pads
			(clearance 0.5)
		)
		(min_thickness 0.25)
		(fill yes
			(thermal_gap 0.5)
			(thermal_bridge_width 0.5)
			(island_removal_mode 0)
		)
		(polygon
			(pts
				(xy 265.127994 -1.9939) (xy 264.9601 -2.161794) (xy 264.9601 -3.299206) (xy 265.077194 -3.4163)
				(xy 267.687806 -3.4163) (xy 268.373606 -2.7305) (xy 268.805406 -2.7305) (xy 268.9479 -2.588006)
				(xy 268.9479 -2.110994) (xy 268.830806 -1.9939)
			)
		)
	)
	(zone
		(layer "In12.Cu")
		(hatch none 0.5)
		(connect_pads
			(clearance 0)
		)
		(min_thickness 0.25)
		(keepout
			(tracks not_allowed)
			(vias allowed)
			(pads allowed)
			(copperpour not_allowed)
			(footprints allowed)
		)
		(placement
			(enabled no)
			(sheetname "")
		)
		(fill
			(thermal_gap 0.5)
			(thermal_bridge_width 0.5)
			(island_removal_mode 0)
		)
		(polygon
			(pts
				(xy 133.119876 -151.176482) (xy 133.678676 -151.176482) (xy 133.678676 -152.979882) (xy 133.119876 -152.979882)
			)
		)
	)
	(zone
		(layer "In12.Cu")
		(hatch none 0.5)
		(connect_pads
			(clearance 0)
		)
		(min_thickness 0.25)
		(keepout
			(tracks not_allowed)
			(vias allowed)
			(pads allowed)
			(copperpour not_allowed)
			(footprints allowed)
		)
		(placement
			(enabled no)
			(sheetname "")
		)
		(fill
			(thermal_gap 0.5)
			(thermal_bridge_width 0.5)
			(island_removal_mode 0)
		)
		(polygon
			(pts
				(xy 305.770534 -4.720082) (xy 306.329334 -4.720082) (xy 306.329334 -6.523482) (xy 305.770534 -6.523482)
			)
		)
	)
	(zone
		(layer "In12.Cu")
		(hatch none 0.5)
		(connect_pads
			(clearance 0)
		)
		(min_thickness 0.25)
		(keepout
			(tracks not_allowed)
			(vias allowed)
			(pads allowed)
			(copperpour not_allowed)
			(footprints allowed)
		)
		(placement
			(enabled no)
			(sheetname "")
		)
		(fill
			(thermal_gap 0.5)
			(thermal_bridge_width 0.5)
			(island_removal_mode 0)
		)
		(polygon
			(pts
				(xy 265.820398 -151.176482) (xy 266.379198 -151.176482) (xy 266.379198 -152.979882) (xy 265.820398 -152.979882)
			)
		)
	)
	(zone
		(layer "In12.Cu")
		(hatch none 0.5)
		(connect_pads
			(clearance 0)
		)
		(min_thickness 0.25)
		(keepout
			(tracks not_allowed)
			(vias allowed)
			(pads allowed)
			(copperpour not_allowed)
			(footprints allowed)
		)
		(placement
			(enabled no)
			(sheetname "")
		)
		(fill
			(thermal_gap 0.5)
			(thermal_bridge_width 0.5)
			(island_removal_mode 0)
		)
		(polygon
			(pts
				(xy 133.970014 -127.374142) (xy 134.528814 -127.374142) (xy 134.528814 -129.177542) (xy 133.970014 -129.177542)
			)
		)
	)
	(zone
		(layer "In12.Cu")
		(hatch none 0.5)
		(connect_pads
			(clearance 0)
		)
		(min_thickness 0.25)
		(keepout
			(tracks not_allowed)
			(vias allowed)
			(pads allowed)
			(copperpour not_allowed)
			(footprints allowed)
		)
		(placement
			(enabled no)
			(sheetname "")
		)
		(fill
			(thermal_gap 0.5)
			(thermal_bridge_width 0.5)
			(island_removal_mode 0)
		)
		(polygon
			(pts
				(xy 267.52042 -127.374142) (xy 268.07922 -127.374142) (xy 268.07922 -129.177542) (xy 267.52042 -129.177542)
			)
		)
	)
	(zone
		(layer "In12.Cu")
		(hatch none 0.5)
		(connect_pads
			(clearance 0)
		)
		(min_thickness 0.25)
		(keepout
			(tracks not_allowed)
			(vias allowed)
			(pads allowed)
			(copperpour not_allowed)
			(footprints allowed)
		)
		(placement
			(enabled no)
			(sheetname "")
		)
		(fill
			(thermal_gap 0.5)
			(thermal_bridge_width 0.5)
			(island_removal_mode 0)
		)
		(polygon
			(pts
				(xy 350.276414 -126.599442) (xy 347.990414 -126.599442) (xy 347.990414 -126.091442) (xy 350.276414 -126.091442)
			)
		)
	)
	(zone
		(layer "In12.Cu")
		(hatch none 0.5)
		(connect_pads
			(clearance 0)
		)
		(min_thickness 0.25)
		(keepout
			(tracks not_allowed)
			(vias allowed)
			(pads allowed)
			(copperpour not_allowed)
			(footprints allowed)
		)
		(placement
			(enabled no)
			(sheetname "")
		)
		(fill
			(thermal_gap 0.5)
			(thermal_bridge_width 0.5)
			(island_removal_mode 0)
		)
		(polygon
			(pts
				(xy 213.120478 -141.575282) (xy 213.679278 -141.575282) (xy 213.679278 -143.378682) (xy 213.120478 -143.378682)
			)
		)
	)
	(zone
		(layer "In12.Cu")
		(hatch none 0.5)
		(connect_pads
			(clearance 0)
		)
		(min_thickness 0.25)
		(keepout
			(tracks not_allowed)
			(vias allowed)
			(pads allowed)
			(copperpour not_allowed)
			(footprints allowed)
		)
		(placement
			(enabled no)
			(sheetname "")
		)
		(fill
			(thermal_gap 0.5)
			(thermal_bridge_width 0.5)
			(island_removal_mode 0)
		)
		(polygon
			(pts
				(xy 86.37016 -141.575282) (xy 86.92896 -141.575282) (xy 86.92896 -143.378682) (xy 86.37016 -143.378682)
			)
		)
	)
	(zone
		(layer "In12.Cu")
		(hatch none 0.5)
		(connect_pads
			(clearance 0)
		)
		(min_thickness 0.25)
		(keepout
			(tracks not_allowed)
			(vias allowed)
			(pads allowed)
			(copperpour not_allowed)
			(footprints allowed)
		)
		(placement
			(enabled no)
			(sheetname "")
		)
		(fill
			(thermal_gap 0.5)
			(thermal_bridge_width 0.5)
			(island_removal_mode 0)
		)
		(polygon
			(pts
				(xy 148.420074 -14.321282) (xy 148.978874 -14.321282) (xy 148.978874 -16.124682) (xy 148.420074 -16.124682)
			)
		)
	)
	(zone
		(layer "In12.Cu")
		(hatch none 0.5)
		(connect_pads
			(clearance 0)
		)
		(min_thickness 0.25)
		(keepout
			(tracks not_allowed)
			(vias allowed)
			(pads allowed)
			(copperpour not_allowed)
			(footprints allowed)
		)
		(placement
			(enabled no)
			(sheetname "")
		)
		(fill
			(thermal_gap 0.5)
			(thermal_bridge_width 0.5)
			(island_removal_mode 0)
		)
		(polygon
			(pts
				(xy 223.320356 -127.374142) (xy 223.879156 -127.374142) (xy 223.879156 -129.177542) (xy 223.320356 -129.177542)
			)
		)
	)
	(zone
		(layer "In12.Cu")
		(hatch none 0.5)
		(connect_pads
			(clearance 0)
		)
		(min_thickness 0.25)
		(keepout
			(tracks not_allowed)
			(vias allowed)
			(pads allowed)
			(copperpour not_allowed)
			(footprints allowed)
		)
		(placement
			(enabled no)
			(sheetname "")
		)
		(fill
			(thermal_gap 0.5)
			(thermal_bridge_width 0.5)
			(island_removal_mode 0)
		)
		(polygon
			(pts
				(xy 58.319924 -19.322542) (xy 58.878724 -19.322542) (xy 58.878724 -21.125942) (xy 58.319924 -21.125942)
			)
		)
	)
	(zone
		(layer "In12.Cu")
		(hatch none 0.5)
		(connect_pads
			(clearance 0)
		)
		(min_thickness 0.25)
		(keepout
			(tracks not_allowed)
			(vias allowed)
			(pads allowed)
			(copperpour not_allowed)
			(footprints allowed)
		)
		(placement
			(enabled no)
			(sheetname "")
		)
		(fill
			(thermal_gap 0.5)
			(thermal_bridge_width 0.5)
			(island_removal_mode 0)
		)
		(polygon
			(pts
				(xy 201.220578 -136.975342) (xy 201.779378 -136.975342) (xy 201.779378 -138.778742) (xy 201.220578 -138.778742)
			)
		)
	)
	(zone
		(layer "In12.Cu")
		(hatch none 0.5)
		(connect_pads
			(clearance 0)
		)
		(min_thickness 0.25)
		(keepout
			(tracks not_allowed)
			(vias allowed)
			(pads allowed)
			(copperpour not_allowed)
			(footprints allowed)
		)
		(placement
			(enabled no)
			(sheetname "")
		)
		(fill
			(thermal_gap 0.5)
			(thermal_bridge_width 0.5)
			(island_removal_mode 0)
		)
		(polygon
			(pts
				(xy 265.820398 -14.321282) (xy 266.379198 -14.321282) (xy 266.379198 -16.124682) (xy 265.820398 -16.124682)
			)
		)
	)
	(zone
		(layer "In12.Cu")
		(hatch none 0.5)
		(connect_pads
			(clearance 0)
		)
		(min_thickness 0.25)
		(keepout
			(tracks not_allowed)
			(vias allowed)
			(pads allowed)
			(copperpour not_allowed)
			(footprints allowed)
		)
		(placement
			(enabled no)
			(sheetname "")
		)
		(fill
			(thermal_gap 0.5)
			(thermal_bridge_width 0.5)
			(island_removal_mode 0)
		)
		(polygon
			(pts
				(xy 251.370592 -4.720082) (xy 251.929392 -4.720082) (xy 251.929392 -6.523482) (xy 251.370592 -6.523482)
			)
		)
	)
	(zone
		(layer "In12.Cu")
		(hatch none 0.5)
		(connect_pads
			(clearance 0)
		)
		(min_thickness 0.25)
		(keepout
			(tracks not_allowed)
			(vias allowed)
			(pads allowed)
			(copperpour not_allowed)
			(footprints allowed)
		)
		(placement
			(enabled no)
			(sheetname "")
		)
		(fill
			(thermal_gap 0.5)
			(thermal_bridge_width 0.5)
			(island_removal_mode 0)
		)
		(polygon
			(pts
				(xy 431.794666 -142.313914) (xy 431.794666 -141.551914) (xy 430.804066 -141.551914) (xy 430.804066 -142.313914)
			)
		)
	)
	(zone
		(layer "In12.Cu")
		(hatch none 0.5)
		(connect_pads
			(clearance 0)
		)
		(min_thickness 0.25)
		(keepout
			(tracks not_allowed)
			(vias allowed)
			(pads allowed)
			(copperpour not_allowed)
			(footprints allowed)
		)
		(placement
			(enabled no)
			(sheetname "")
		)
		(fill
			(thermal_gap 0.5)
			(thermal_bridge_width 0.5)
			(island_removal_mode 0)
		)
		(polygon
			(pts
				(xy 448.945 -115.34902) (xy 449.453 -115.34902) (xy 449.453 -116.74602) (xy 448.945 -116.74602)
			)
		)
	)
	(zone
		(layer "In12.Cu")
		(hatch none 0.5)
		(connect_pads
			(clearance 0)
		)
		(min_thickness 0.25)
		(keepout
			(tracks not_allowed)
			(vias allowed)
			(pads allowed)
			(copperpour not_allowed)
			(footprints allowed)
		)
		(placement
			(enabled no)
			(sheetname "")
		)
		(fill
			(thermal_gap 0.5)
			(thermal_bridge_width 0.5)
			(island_removal_mode 0)
		)
		(polygon
			(pts
				(xy 264.970514 -0.120142) (xy 265.529314 -0.120142) (xy 265.529314 -1.923542) (xy 264.970514 -1.923542)
			)
		)
	)
	(zone
		(layer "In12.Cu")
		(hatch none 0.5)
		(connect_pads
			(clearance 0)
		)
		(min_thickness 0.25)
		(keepout
			(tracks not_allowed)
			(vias allowed)
			(pads allowed)
			(copperpour not_allowed)
			(footprints allowed)
		)
		(placement
			(enabled no)
			(sheetname "")
		)
		(fill
			(thermal_gap 0.5)
			(thermal_bridge_width 0.5)
			(island_removal_mode 0)
		)
		(polygon
			(pts
				(xy 299.82033 -141.575282) (xy 300.37913 -141.575282) (xy 300.37913 -143.378682) (xy 299.82033 -143.378682)
			)
		)
	)
	(zone
		(layer "In12.Cu")
		(hatch none 0.5)
		(connect_pads
			(clearance 0)
		)
		(min_thickness 0.25)
		(keepout
			(tracks not_allowed)
			(vias allowed)
			(pads allowed)
			(copperpour not_allowed)
			(footprints allowed)
		)
		(placement
			(enabled no)
			(sheetname "")
		)
		(fill
			(thermal_gap 0.5)
			(thermal_bridge_width 0.5)
			(island_removal_mode 0)
		)
		(polygon
			(pts
				(xy 148.420074 -141.575282) (xy 148.978874 -141.575282) (xy 148.978874 -143.378682) (xy 148.420074 -143.378682)
			)
		)
	)
	(zone
		(layer "In12.Cu")
		(hatch none 0.5)
		(connect_pads
			(clearance 0)
		)
		(min_thickness 0.25)
		(keepout
			(tracks not_allowed)
			(vias allowed)
			(pads allowed)
			(copperpour not_allowed)
			(footprints allowed)
		)
		(placement
			(enabled no)
			(sheetname "")
		)
		(fill
			(thermal_gap 0.5)
			(thermal_bridge_width 0.5)
			(island_removal_mode 0)
		)
		(polygon
			(pts
				(xy 290.470336 -23.922482) (xy 291.029136 -23.922482) (xy 291.029136 -25.725882) (xy 290.470336 -25.725882)
			)
		)
	)
	(zone
		(layer "In12.Cu")
		(hatch none 0.5)
		(connect_pads
			(clearance 0)
		)
		(min_thickness 0.25)
		(keepout
			(tracks not_allowed)
			(vias allowed)
			(pads allowed)
			(copperpour not_allowed)
			(footprints allowed)
		)
		(placement
			(enabled no)
			(sheetname "")
		)
		(fill
			(thermal_gap 0.5)
			(thermal_bridge_width 0.5)
			(island_removal_mode 0)
		)
		(polygon
			(pts
				(xy 238.620554 -9.721342) (xy 239.179354 -9.721342) (xy 239.179354 -11.524742) (xy 238.620554 -11.524742)
			)
		)
	)
	(zone
		(layer "In12.Cu")
		(hatch none 0.5)
		(connect_pads
			(clearance 0)
		)
		(min_thickness 0.25)
		(keepout
			(tracks not_allowed)
			(vias allowed)
			(pads allowed)
			(copperpour not_allowed)
			(footprints allowed)
		)
		(placement
			(enabled no)
			(sheetname "")
		)
		(fill
			(thermal_gap 0.5)
			(thermal_bridge_width 0.5)
			(island_removal_mode 0)
		)
		(polygon
			(pts
				(xy 284.520386 -136.975342) (xy 285.079186 -136.975342) (xy 285.079186 -138.778742) (xy 284.520386 -138.778742)
			)
		)
	)
	(zone
		(layer "In12.Cu")
		(hatch none 0.5)
		(connect_pads
			(clearance 0)
		)
		(min_thickness 0.25)
		(keepout
			(tracks not_allowed)
			(vias allowed)
			(pads allowed)
			(copperpour not_allowed)
			(footprints allowed)
		)
		(placement
			(enabled no)
			(sheetname "")
		)
		(fill
			(thermal_gap 0.5)
			(thermal_bridge_width 0.5)
			(island_removal_mode 0)
		)
		(polygon
			(pts
				(xy 35.370008 -4.720082) (xy 35.928808 -4.720082) (xy 35.928808 -6.523482) (xy 35.370008 -6.523482)
			)
		)
	)
	(zone
		(layer "In12.Cu")
		(hatch none 0.5)
		(connect_pads
			(clearance 0)
		)
		(min_thickness 0.25)
		(keepout
			(tracks not_allowed)
			(vias allowed)
			(pads allowed)
			(copperpour not_allowed)
			(footprints allowed)
		)
		(placement
			(enabled no)
			(sheetname "")
		)
		(fill
			(thermal_gap 0.5)
			(thermal_bridge_width 0.5)
			(island_removal_mode 0)
		)
		(polygon
			(pts
				(xy 243.720366 -146.576542) (xy 244.279166 -146.576542) (xy 244.279166 -148.379942) (xy 243.720366 -148.379942)
			)
		)
	)
	(zone
		(layer "In12.Cu")
		(hatch none 0.5)
		(connect_pads
			(clearance 0)
		)
		(min_thickness 0.25)
		(keepout
			(tracks not_allowed)
			(vias allowed)
			(pads allowed)
			(copperpour not_allowed)
			(footprints allowed)
		)
		(placement
			(enabled no)
			(sheetname "")
		)
		(fill
			(thermal_gap 0.5)
			(thermal_bridge_width 0.5)
			(island_removal_mode 0)
		)
		(polygon
			(pts
				(xy 222.470472 -4.720082) (xy 223.029272 -4.720082) (xy 223.029272 -6.523482) (xy 222.470472 -6.523482)
			)
		)
	)
	(zone
		(layer "In12.Cu")
		(hatch none 0.5)
		(connect_pads
			(clearance 0)
		)
		(min_thickness 0.25)
		(keepout
			(tracks not_allowed)
			(vias allowed)
			(pads allowed)
			(copperpour not_allowed)
			(footprints allowed)
		)
		(placement
			(enabled no)
			(sheetname "")
		)
		(fill
			(thermal_gap 0.5)
			(thermal_bridge_width 0.5)
			(island_removal_mode 0)
		)
		(polygon
			(pts
				(xy 277.720552 -0.120142) (xy 278.279352 -0.120142) (xy 278.279352 -1.923542) (xy 277.720552 -1.923542)
			)
		)
	)
	(zone
		(layer "In12.Cu")
		(hatch none 0.5)
		(connect_pads
			(clearance 0)
		)
		(min_thickness 0.25)
		(keepout
			(tracks not_allowed)
			(vias allowed)
			(pads allowed)
			(copperpour not_allowed)
			(footprints allowed)
		)
		(placement
			(enabled no)
			(sheetname "")
		)
		(fill
			(thermal_gap 0.5)
			(thermal_bridge_width 0.5)
			(island_removal_mode 0)
		)
		(polygon
			(pts
				(xy 237.770416 -136.975342) (xy 238.329216 -136.975342) (xy 238.329216 -138.778742) (xy 237.770416 -138.778742)
			)
		)
	)
	(zone
		(layer "In12.Cu")
		(hatch none 0.5)
		(connect_pads
			(clearance 0)
		)
		(min_thickness 0.25)
		(keepout
			(tracks not_allowed)
			(vias allowed)
			(pads allowed)
			(copperpour not_allowed)
			(footprints allowed)
		)
		(placement
			(enabled no)
			(sheetname "")
		)
		(fill
			(thermal_gap 0.5)
			(thermal_bridge_width 0.5)
			(island_removal_mode 0)
		)
		(polygon
			(pts
				(xy 253.920498 -141.575282) (xy 254.479298 -141.575282) (xy 254.479298 -143.378682) (xy 253.920498 -143.378682)
			)
		)
	)
	(zone
		(layer "In12.Cu")
		(hatch none 0.5)
		(connect_pads
			(clearance 0)
		)
		(min_thickness 0.25)
		(keepout
			(tracks not_allowed)
			(vias allowed)
			(pads allowed)
			(copperpour not_allowed)
			(footprints allowed)
		)
		(placement
			(enabled no)
			(sheetname "")
		)
		(fill
			(thermal_gap 0.5)
			(thermal_bridge_width 0.5)
			(island_removal_mode 0)
		)
		(polygon
			(pts
				(xy 43.870118 -151.176482) (xy 44.428918 -151.176482) (xy 44.428918 -152.979882) (xy 43.870118 -152.979882)
			)
		)
	)
	(zone
		(layer "In12.Cu")
		(hatch none 0.5)
		(connect_pads
			(clearance 0)
		)
		(min_thickness 0.25)
		(keepout
			(tracks not_allowed)
			(vias allowed)
			(pads allowed)
			(copperpour not_allowed)
			(footprints allowed)
		)
		(placement
			(enabled no)
			(sheetname "")
		)
		(fill
			(thermal_gap 0.5)
			(thermal_bridge_width 0.5)
			(island_removal_mode 0)
		)
		(polygon
			(pts
				(xy 253.070614 -136.975342) (xy 253.629414 -136.975342) (xy 253.629414 -138.778742) (xy 253.070614 -138.778742)
			)
		)
	)
	(zone
		(layer "In12.Cu")
		(hatch none 0.5)
		(connect_pads
			(clearance 0)
		)
		(min_thickness 0.25)
		(keepout
			(tracks not_allowed)
			(vias allowed)
			(pads allowed)
			(copperpour not_allowed)
			(footprints allowed)
		)
		(placement
			(enabled no)
			(sheetname "")
		)
		(fill
			(thermal_gap 0.5)
			(thermal_bridge_width 0.5)
			(island_removal_mode 0)
		)
		(polygon
			(pts
				(xy 56.620156 -19.322542) (xy 57.178956 -19.322542) (xy 57.178956 -21.125942) (xy 56.620156 -21.125942)
			)
		)
	)
	(zone
		(layer "In12.Cu")
		(hatch none 0.5)
		(connect_pads
			(clearance 0)
		)
		(min_thickness 0.25)
		(keepout
			(tracks not_allowed)
			(vias allowed)
			(pads allowed)
			(copperpour not_allowed)
			(footprints allowed)
		)
		(placement
			(enabled no)
			(sheetname "")
		)
		(fill
			(thermal_gap 0.5)
			(thermal_bridge_width 0.5)
			(island_removal_mode 0)
		)
		(polygon
			(pts
				(xy 31.12008 -141.575282) (xy 31.67888 -141.575282) (xy 31.67888 -143.378682) (xy 31.12008 -143.378682)
			)
		)
	)
	(zone
		(layer "In12.Cu")
		(hatch none 0.5)
		(connect_pads
			(clearance 0)
		)
		(min_thickness 0.25)
		(keepout
			(tracks not_allowed)
			(vias allowed)
			(pads allowed)
			(copperpour not_allowed)
			(footprints allowed)
		)
		(placement
			(enabled no)
			(sheetname "")
		)
		(fill
			(thermal_gap 0.5)
			(thermal_bridge_width 0.5)
			(island_removal_mode 0)
		)
		(polygon
			(pts
				(xy 92.32011 -19.322542) (xy 92.87891 -19.322542) (xy 92.87891 -21.125942) (xy 92.32011 -21.125942)
			)
		)
	)
	(zone
		(layer "In12.Cu")
		(hatch none 0.5)
		(connect_pads
			(clearance 0)
		)
		(min_thickness 0.25)
		(keepout
			(tracks not_allowed)
			(vias allowed)
			(pads allowed)
			(copperpour not_allowed)
			(footprints allowed)
		)
		(placement
			(enabled no)
			(sheetname "")
		)
		(fill
			(thermal_gap 0.5)
			(thermal_bridge_width 0.5)
			(island_removal_mode 0)
		)
		(polygon
			(pts
				(xy 248.820432 -4.720082) (xy 249.379232 -4.720082) (xy 249.379232 -6.523482) (xy 248.820432 -6.523482)
			)
		)
	)
	(zone
		(layer "In12.Cu")
		(hatch none 0.5)
		(connect_pads
			(clearance 0)
		)
		(min_thickness 0.25)
		(keepout
			(tracks not_allowed)
			(vias allowed)
			(pads allowed)
			(copperpour not_allowed)
			(footprints allowed)
		)
		(placement
			(enabled no)
			(sheetname "")
		)
		(fill
			(thermal_gap 0.5)
			(thermal_bridge_width 0.5)
			(island_removal_mode 0)
		)
		(polygon
			(pts
				(xy 111.020098 -141.575282) (xy 111.578898 -141.575282) (xy 111.578898 -143.378682) (xy 111.020098 -143.378682)
			)
		)
	)
	(zone
		(layer "In12.Cu")
		(hatch none 0.5)
		(connect_pads
			(clearance 0)
		)
		(min_thickness 0.25)
		(keepout
			(tracks not_allowed)
			(vias allowed)
			(pads allowed)
			(copperpour not_allowed)
			(footprints allowed)
		)
		(placement
			(enabled no)
			(sheetname "")
		)
		(fill
			(thermal_gap 0.5)
			(thermal_bridge_width 0.5)
			(island_removal_mode 0)
		)
		(polygon
			(pts
				(xy 236.070394 -146.576542) (xy 236.629194 -146.576542) (xy 236.629194 -148.379942) (xy 236.070394 -148.379942)
			)
		)
	)
	(zone
		(layer "In12.Cu")
		(hatch none 0.5)
		(connect_pads
			(clearance 0)
		)
		(min_thickness 0.25)
		(keepout
			(tracks not_allowed)
			(vias allowed)
			(pads allowed)
			(copperpour not_allowed)
			(footprints allowed)
		)
		(placement
			(enabled no)
			(sheetname "")
		)
		(fill
			(thermal_gap 0.5)
			(thermal_bridge_width 0.5)
			(island_removal_mode 0)
		)
		(polygon
			(pts
				(xy 63.41999 -131.974082) (xy 63.97879 -131.974082) (xy 63.97879 -133.777482) (xy 63.41999 -133.777482)
			)
		)
	)
	(zone
		(layer "In12.Cu")
		(hatch none 0.5)
		(connect_pads
			(clearance 0)
		)
		(min_thickness 0.25)
		(keepout
			(tracks not_allowed)
			(vias allowed)
			(pads allowed)
			(copperpour not_allowed)
			(footprints allowed)
		)
		(placement
			(enabled no)
			(sheetname "")
		)
		(fill
			(thermal_gap 0.5)
			(thermal_bridge_width 0.5)
			(island_removal_mode 0)
		)
		(polygon
			(pts
				(xy 252.220476 -151.176482) (xy 252.779276 -151.176482) (xy 252.779276 -152.979882) (xy 252.220476 -152.979882)
			)
		)
	)
	(zone
		(layer "In12.Cu")
		(hatch none 0.5)
		(connect_pads
			(clearance 0)
		)
		(min_thickness 0.25)
		(keepout
			(tracks not_allowed)
			(vias allowed)
			(pads allowed)
			(copperpour not_allowed)
			(footprints allowed)
		)
		(placement
			(enabled no)
			(sheetname "")
		)
		(fill
			(thermal_gap 0.5)
			(thermal_bridge_width 0.5)
			(island_removal_mode 0)
		)
		(polygon
			(pts
				(xy 225.020378 -0.120142) (xy 225.579178 -0.120142) (xy 225.579178 -1.923542) (xy 225.020378 -1.923542)
			)
		)
	)
	(zone
		(layer "In12.Cu")
		(hatch none 0.5)
		(connect_pads
			(clearance 0)
		)
		(min_thickness 0.25)
		(keepout
			(tracks not_allowed)
			(vias allowed)
			(pads allowed)
			(copperpour not_allowed)
			(footprints allowed)
		)
		(placement
			(enabled no)
			(sheetname "")
		)
		(fill
			(thermal_gap 0.5)
			(thermal_bridge_width 0.5)
			(island_removal_mode 0)
		)
		(polygon
			(pts
				(xy 422.65092 -148.717) (xy 422.65092 -149.479) (xy 423.64152 -149.479) (xy 423.64152 -148.717)
			)
		)
	)
	(zone
		(layer "In12.Cu")
		(hatch none 0.5)
		(connect_pads
			(clearance 0)
		)
		(min_thickness 0.25)
		(keepout
			(tracks not_allowed)
			(vias allowed)
			(pads allowed)
			(copperpour not_allowed)
			(footprints allowed)
		)
		(placement
			(enabled no)
			(sheetname "")
		)
		(fill
			(thermal_gap 0.5)
			(thermal_bridge_width 0.5)
			(island_removal_mode 0)
		)
		(polygon
			(pts
				(xy 37.07003 -141.575282) (xy 37.62883 -141.575282) (xy 37.62883 -143.378682) (xy 37.07003 -143.378682)
			)
		)
	)
	(zone
		(layer "In12.Cu")
		(hatch none 0.5)
		(connect_pads
			(clearance 0)
		)
		(min_thickness 0.25)
		(keepout
			(tracks not_allowed)
			(vias allowed)
			(pads allowed)
			(copperpour not_allowed)
			(footprints allowed)
		)
		(placement
			(enabled no)
			(sheetname "")
		)
		(fill
			(thermal_gap 0.5)
			(thermal_bridge_width 0.5)
			(island_removal_mode 0)
		)
		(polygon
			(pts
				(xy 63.41999 -19.322542) (xy 63.97879 -19.322542) (xy 63.97879 -21.125942) (xy 63.41999 -21.125942)
			)
		)
	)
	(zone
		(layer "In12.Cu")
		(hatch none 0.5)
		(connect_pads
			(clearance 0)
		)
		(min_thickness 0.25)
		(keepout
			(tracks not_allowed)
			(vias allowed)
			(pads allowed)
			(copperpour not_allowed)
			(footprints allowed)
		)
		(placement
			(enabled no)
			(sheetname "")
		)
		(fill
			(thermal_gap 0.5)
			(thermal_bridge_width 0.5)
			(island_removal_mode 0)
		)
		(polygon
			(pts
				(xy 31.969964 -136.975342) (xy 32.528764 -136.975342) (xy 32.528764 -138.778742) (xy 31.969964 -138.778742)
			)
		)
	)
	(zone
		(layer "In12.Cu")
		(hatch none 0.5)
		(connect_pads
			(clearance 0)
		)
		(min_thickness 0.25)
		(keepout
			(tracks not_allowed)
			(vias allowed)
			(pads allowed)
			(copperpour not_allowed)
			(footprints allowed)
		)
		(placement
			(enabled no)
			(sheetname "")
		)
		(fill
			(thermal_gap 0.5)
			(thermal_bridge_width 0.5)
			(island_removal_mode 0)
		)
		(polygon
			(pts
				(xy 35.370008 -151.176482) (xy 35.928808 -151.176482) (xy 35.928808 -152.979882) (xy 35.370008 -152.979882)
			)
		)
	)
	(zone
		(layer "In12.Cu")
		(hatch none 0.5)
		(connect_pads
			(clearance 0)
		)
		(min_thickness 0.25)
		(keepout
			(tracks not_allowed)
			(vias allowed)
			(pads allowed)
			(copperpour not_allowed)
			(footprints allowed)
		)
		(placement
			(enabled no)
			(sheetname "")
		)
		(fill
			(thermal_gap 0.5)
			(thermal_bridge_width 0.5)
			(island_removal_mode 0)
		)
		(polygon
			(pts
				(xy 284.520386 -127.374142) (xy 285.079186 -127.374142) (xy 285.079186 -129.177542) (xy 284.520386 -129.177542)
			)
		)
	)
	(zone
		(layer "In12.Cu")
		(hatch none 0.5)
		(connect_pads
			(clearance 0)
		)
		(min_thickness 0.25)
		(keepout
			(tracks not_allowed)
			(vias allowed)
			(pads allowed)
			(copperpour not_allowed)
			(footprints allowed)
		)
		(placement
			(enabled no)
			(sheetname "")
		)
		(fill
			(thermal_gap 0.5)
			(thermal_bridge_width 0.5)
			(island_removal_mode 0)
		)
		(polygon
			(pts
				(xy 77.02042 -127.374142) (xy 77.57922 -127.374142) (xy 77.57922 -129.177542) (xy 77.02042 -129.177542)
			)
		)
	)
	(zone
		(layer "In12.Cu")
		(hatch none 0.5)
		(connect_pads
			(clearance 0)
		)
		(min_thickness 0.25)
		(keepout
			(tracks not_allowed)
			(vias allowed)
			(pads allowed)
			(copperpour not_allowed)
			(footprints allowed)
		)
		(placement
			(enabled no)
			(sheetname "")
		)
		(fill
			(thermal_gap 0.5)
			(thermal_bridge_width 0.5)
			(island_removal_mode 0)
		)
		(polygon
			(pts
				(xy 122.919998 -146.576542) (xy 123.478798 -146.576542) (xy 123.478798 -148.379942) (xy 122.919998 -148.379942)
			)
		)
	)
	(zone
		(layer "In12.Cu")
		(hatch none 0.5)
		(connect_pads
			(clearance 0)
		)
		(min_thickness 0.25)
		(keepout
			(tracks not_allowed)
			(vias allowed)
			(pads allowed)
			(copperpour not_allowed)
			(footprints allowed)
		)
		(placement
			(enabled no)
			(sheetname "")
		)
		(fill
			(thermal_gap 0.5)
			(thermal_bridge_width 0.5)
			(island_removal_mode 0)
		)
		(polygon
			(pts
				(xy 42.170096 -131.974082) (xy 42.728896 -131.974082) (xy 42.728896 -133.777482) (xy 42.170096 -133.777482)
			)
		)
	)
	(zone
		(layer "In12.Cu")
		(hatch none 0.5)
		(connect_pads
			(clearance 0)
		)
		(min_thickness 0.25)
		(keepout
			(tracks not_allowed)
			(vias allowed)
			(pads allowed)
			(copperpour not_allowed)
			(footprints allowed)
		)
		(placement
			(enabled no)
			(sheetname "")
		)
		(fill
			(thermal_gap 0.5)
			(thermal_bridge_width 0.5)
			(island_removal_mode 0)
		)
		(polygon
			(pts
				(xy 273.47037 -127.374142) (xy 274.02917 -127.374142) (xy 274.02917 -129.177542) (xy 273.47037 -129.177542)
			)
		)
	)
	(zone
		(layer "In12.Cu")
		(hatch none 0.5)
		(connect_pads
			(clearance 0)
		)
		(min_thickness 0.25)
		(keepout
			(tracks not_allowed)
			(vias allowed)
			(pads allowed)
			(copperpour not_allowed)
			(footprints allowed)
		)
		(placement
			(enabled no)
			(sheetname "")
		)
		(fill
			(thermal_gap 0.5)
			(thermal_bridge_width 0.5)
			(island_removal_mode 0)
		)
		(polygon
			(pts
				(xy 315.120528 -14.321282) (xy 315.679328 -14.321282) (xy 315.679328 -16.124682) (xy 315.120528 -16.124682)
			)
		)
	)
	(zone
		(layer "In12.Cu")
		(hatch none 0.5)
		(connect_pads
			(clearance 0)
		)
		(min_thickness 0.25)
		(keepout
			(tracks not_allowed)
			(vias allowed)
			(pads allowed)
			(copperpour not_allowed)
			(footprints allowed)
		)
		(placement
			(enabled no)
			(sheetname "")
		)
		(fill
			(thermal_gap 0.5)
			(thermal_bridge_width 0.5)
			(island_removal_mode 0)
		)
		(polygon
			(pts
				(xy 57.47004 -14.321282) (xy 58.02884 -14.321282) (xy 58.02884 -16.124682) (xy 57.47004 -16.124682)
			)
		)
	)
	(zone
		(layer "In12.Cu")
		(hatch none 0.5)
		(connect_pads
			(clearance 0)
		)
		(min_thickness 0.25)
		(keepout
			(tracks not_allowed)
			(vias allowed)
			(pads allowed)
			(copperpour not_allowed)
			(footprints allowed)
		)
		(placement
			(enabled no)
			(sheetname "")
		)
		(fill
			(thermal_gap 0.5)
			(thermal_bridge_width 0.5)
			(island_removal_mode 0)
		)
		(polygon
			(pts
				(xy 71.069962 -127.374142) (xy 71.628762 -127.374142) (xy 71.628762 -129.177542) (xy 71.069962 -129.177542)
			)
		)
	)
	(zone
		(layer "In12.Cu")
		(hatch none 0.5)
		(connect_pads
			(clearance 0)
		)
		(min_thickness 0.25)
		(keepout
			(tracks not_allowed)
			(vias allowed)
			(pads allowed)
			(copperpour not_allowed)
			(footprints allowed)
		)
		(placement
			(enabled no)
			(sheetname "")
		)
		(fill
			(thermal_gap 0.5)
			(thermal_bridge_width 0.5)
			(island_removal_mode 0)
		)
		(polygon
			(pts
				(xy 58.319924 -0.120142) (xy 58.878724 -0.120142) (xy 58.878724 -1.923542) (xy 58.319924 -1.923542)
			)
		)
	)
	(zone
		(layer "In12.Cu")
		(hatch none 0.5)
		(connect_pads
			(clearance 0)
		)
		(min_thickness 0.25)
		(keepout
			(tracks not_allowed)
			(vias allowed)
			(pads allowed)
			(copperpour not_allowed)
			(footprints allowed)
		)
		(placement
			(enabled no)
			(sheetname "")
		)
		(fill
			(thermal_gap 0.5)
			(thermal_bridge_width 0.5)
			(island_removal_mode 0)
		)
		(polygon
			(pts
				(xy 213.970362 -127.374142) (xy 214.529162 -127.374142) (xy 214.529162 -129.177542) (xy 213.970362 -129.177542)
			)
		)
	)
	(zone
		(layer "In12.Cu")
		(hatch none 0.5)
		(connect_pads
			(clearance 0)
		)
		(min_thickness 0.25)
		(keepout
			(tracks not_allowed)
			(vias allowed)
			(pads allowed)
			(copperpour not_allowed)
			(footprints allowed)
		)
		(placement
			(enabled no)
			(sheetname "")
		)
		(fill
			(thermal_gap 0.5)
			(thermal_bridge_width 0.5)
			(island_removal_mode 0)
		)
		(polygon
			(pts
				(xy 60.019946 -127.374142) (xy 60.578746 -127.374142) (xy 60.578746 -129.177542) (xy 60.019946 -129.177542)
			)
		)
	)
	(zone
		(layer "In12.Cu")
		(hatch none 0.5)
		(connect_pads
			(clearance 0)
		)
		(min_thickness 0.25)
		(keepout
			(tracks not_allowed)
			(vias allowed)
			(pads allowed)
			(copperpour not_allowed)
			(footprints allowed)
		)
		(placement
			(enabled no)
			(sheetname "")
		)
		(fill
			(thermal_gap 0.5)
			(thermal_bridge_width 0.5)
			(island_removal_mode 0)
		)
		(polygon
			(pts
				(xy 100.819966 -151.176482) (xy 101.378766 -151.176482) (xy 101.378766 -152.979882) (xy 100.819966 -152.979882)
			)
		)
	)
	(zone
		(layer "In12.Cu")
		(hatch none 0.5)
		(connect_pads
			(clearance 0)
		)
		(min_thickness 0.25)
		(keepout
			(tracks not_allowed)
			(vias allowed)
			(pads allowed)
			(copperpour not_allowed)
			(footprints allowed)
		)
		(placement
			(enabled no)
			(sheetname "")
		)
		(fill
			(thermal_gap 0.5)
			(thermal_bridge_width 0.5)
			(island_removal_mode 0)
		)
		(polygon
			(pts
				(xy 148.420074 -4.720082) (xy 148.978874 -4.720082) (xy 148.978874 -6.523482) (xy 148.420074 -6.523482)
			)
		)
	)
	(zone
		(layer "In12.Cu")
		(hatch none 0.5)
		(connect_pads
			(clearance 0)
		)
		(min_thickness 0.25)
		(keepout
			(tracks not_allowed)
			(vias allowed)
			(pads allowed)
			(copperpour not_allowed)
			(footprints allowed)
		)
		(placement
			(enabled no)
			(sheetname "")
		)
		(fill
			(thermal_gap 0.5)
			(thermal_bridge_width 0.5)
			(island_removal_mode 0)
		)
		(polygon
			(pts
				(xy 55.770018 -4.720082) (xy 56.328818 -4.720082) (xy 56.328818 -6.523482) (xy 55.770018 -6.523482)
			)
		)
	)
	(zone
		(layer "In12.Cu")
		(hatch none 0.5)
		(connect_pads
			(clearance 0)
		)
		(min_thickness 0.25)
		(keepout
			(tracks not_allowed)
			(vias allowed)
			(pads allowed)
			(copperpour not_allowed)
			(footprints allowed)
		)
		(placement
			(enabled no)
			(sheetname "")
		)
		(fill
			(thermal_gap 0.5)
			(thermal_bridge_width 0.5)
			(island_removal_mode 0)
		)
		(polygon
			(pts
				(xy 150.120096 -23.922482) (xy 150.678896 -23.922482) (xy 150.678896 -25.725882) (xy 150.120096 -25.725882)
			)
		)
	)
	(zone
		(layer "In12.Cu")
		(hatch none 0.5)
		(connect_pads
			(clearance 0)
		)
		(min_thickness 0.25)
		(keepout
			(tracks not_allowed)
			(vias allowed)
			(pads allowed)
			(copperpour not_allowed)
			(footprints allowed)
		)
		(placement
			(enabled no)
			(sheetname "")
		)
		(fill
			(thermal_gap 0.5)
			(thermal_bridge_width 0.5)
			(island_removal_mode 0)
		)
		(polygon
			(pts
				(xy 31.969964 -146.576542) (xy 32.528764 -146.576542) (xy 32.528764 -148.379942) (xy 31.969964 -148.379942)
			)
		)
	)
	(zone
		(layer "In12.Cu")
		(hatch none 0.5)
		(connect_pads
			(clearance 0)
		)
		(min_thickness 0.25)
		(keepout
			(tracks not_allowed)
			(vias allowed)
			(pads allowed)
			(copperpour not_allowed)
			(footprints allowed)
		)
		(placement
			(enabled no)
			(sheetname "")
		)
		(fill
			(thermal_gap 0.5)
			(thermal_bridge_width 0.5)
			(island_removal_mode 0)
		)
		(polygon
			(pts
				(xy 257.320542 -151.176482) (xy 257.879342 -151.176482) (xy 257.879342 -152.979882) (xy 257.320542 -152.979882)
			)
		)
	)
	(zone
		(layer "In12.Cu")
		(hatch none 0.5)
		(connect_pads
			(clearance 0)
		)
		(min_thickness 0.25)
		(keepout
			(tracks not_allowed)
			(vias allowed)
			(pads allowed)
			(copperpour not_allowed)
			(footprints allowed)
		)
		(placement
			(enabled no)
			(sheetname "")
		)
		(fill
			(thermal_gap 0.5)
			(thermal_bridge_width 0.5)
			(island_removal_mode 0)
		)
		(polygon
			(pts
				(xy 276.02053 -141.575282) (xy 276.57933 -141.575282) (xy 276.57933 -143.378682) (xy 276.02053 -143.378682)
			)
		)
	)
	(zone
		(layer "In12.Cu")
		(hatch none 0.5)
		(connect_pads
			(clearance 0)
		)
		(min_thickness 0.25)
		(keepout
			(tracks not_allowed)
			(vias allowed)
			(pads allowed)
			(copperpour not_allowed)
			(footprints allowed)
		)
		(placement
			(enabled no)
			(sheetname "")
		)
		(fill
			(thermal_gap 0.5)
			(thermal_bridge_width 0.5)
			(island_removal_mode 0)
		)
		(polygon
			(pts
				(xy 214.8205 -14.321282) (xy 215.3793 -14.321282) (xy 215.3793 -16.124682) (xy 214.8205 -16.124682)
			)
		)
	)
	(zone
		(layer "In12.Cu")
		(hatch none 0.5)
		(connect_pads
			(clearance 0)
		)
		(min_thickness 0.25)
		(keepout
			(tracks not_allowed)
			(vias allowed)
			(pads allowed)
			(copperpour not_allowed)
			(footprints allowed)
		)
		(placement
			(enabled no)
			(sheetname "")
		)
		(fill
			(thermal_gap 0.5)
			(thermal_bridge_width 0.5)
			(island_removal_mode 0)
		)
		(polygon
			(pts
				(xy 101.670104 -0.120142) (xy 102.228904 -0.120142) (xy 102.228904 -1.923542) (xy 101.670104 -1.923542)
			)
		)
	)
	(zone
		(layer "In12.Cu")
		(hatch none 0.5)
		(connect_pads
			(clearance 0)
		)
		(min_thickness 0.25)
		(keepout
			(tracks not_allowed)
			(vias allowed)
			(pads allowed)
			(copperpour not_allowed)
			(footprints allowed)
		)
		(placement
			(enabled no)
			(sheetname "")
		)
		(fill
			(thermal_gap 0.5)
			(thermal_bridge_width 0.5)
			(island_removal_mode 0)
		)
		(polygon
			(pts
				(xy 139.919964 -146.576542) (xy 140.478764 -146.576542) (xy 140.478764 -148.379942) (xy 139.919964 -148.379942)
			)
		)
	)
	(zone
		(layer "In12.Cu")
		(hatch none 0.5)
		(connect_pads
			(clearance 0)
		)
		(min_thickness 0.25)
		(keepout
			(tracks not_allowed)
			(vias allowed)
			(pads allowed)
			(copperpour not_allowed)
			(footprints allowed)
		)
		(placement
			(enabled no)
			(sheetname "")
		)
		(fill
			(thermal_gap 0.5)
			(thermal_bridge_width 0.5)
			(island_removal_mode 0)
		)
		(polygon
			(pts
				(xy 276.02053 -0.120142) (xy 276.57933 -0.120142) (xy 276.57933 -1.923542) (xy 276.02053 -1.923542)
			)
		)
	)
	(zone
		(layer "In12.Cu")
		(hatch none 0.5)
		(connect_pads
			(clearance 0)
		)
		(min_thickness 0.25)
		(keepout
			(tracks not_allowed)
			(vias allowed)
			(pads allowed)
			(copperpour not_allowed)
			(footprints allowed)
		)
		(placement
			(enabled no)
			(sheetname "")
		)
		(fill
			(thermal_gap 0.5)
			(thermal_bridge_width 0.5)
			(island_removal_mode 0)
		)
		(polygon
			(pts
				(xy 137.370058 -4.720082) (xy 137.928858 -4.720082) (xy 137.928858 -6.523482) (xy 137.370058 -6.523482)
			)
		)
	)
	(zone
		(layer "In12.Cu")
		(hatch none 0.5)
		(connect_pads
			(clearance 0)
		)
		(min_thickness 0.25)
		(keepout
			(tracks not_allowed)
			(vias allowed)
			(pads allowed)
			(copperpour not_allowed)
			(footprints allowed)
		)
		(placement
			(enabled no)
			(sheetname "")
		)
		(fill
			(thermal_gap 0.5)
			(thermal_bridge_width 0.5)
			(island_removal_mode 0)
		)
		(polygon
			(pts
				(xy 203.770484 -131.974082) (xy 204.329284 -131.974082) (xy 204.329284 -133.777482) (xy 203.770484 -133.777482)
			)
		)
	)
	(zone
		(layer "In12.Cu")
		(hatch none 0.5)
		(connect_pads
			(clearance 0)
		)
		(min_thickness 0.25)
		(keepout
			(tracks not_allowed)
			(vias allowed)
			(pads allowed)
			(copperpour not_allowed)
			(footprints allowed)
		)
		(placement
			(enabled no)
			(sheetname "")
		)
		(fill
			(thermal_gap 0.5)
			(thermal_bridge_width 0.5)
			(island_removal_mode 0)
		)
		(polygon
			(pts
				(xy 13.58646 -107.23118) (xy 14.98346 -107.23118) (xy 14.98346 -107.73918) (xy 13.58646 -107.73918)
			)
		)
	)
	(zone
		(layer "In12.Cu")
		(hatch none 0.5)
		(connect_pads
			(clearance 0)
		)
		(min_thickness 0.25)
		(keepout
			(tracks not_allowed)
			(vias allowed)
			(pads allowed)
			(copperpour not_allowed)
			(footprints allowed)
		)
		(placement
			(enabled no)
			(sheetname "")
		)
		(fill
			(thermal_gap 0.5)
			(thermal_bridge_width 0.5)
			(island_removal_mode 0)
		)
		(polygon
			(pts
				(xy 200.37044 -23.922482) (xy 200.92924 -23.922482) (xy 200.92924 -25.725882) (xy 200.37044 -25.725882)
			)
		)
	)
	(zone
		(layer "In12.Cu")
		(hatch none 0.5)
		(connect_pads
			(clearance 0)
		)
		(min_thickness 0.25)
		(keepout
			(tracks not_allowed)
			(vias allowed)
			(pads allowed)
			(copperpour not_allowed)
			(footprints allowed)
		)
		(placement
			(enabled no)
			(sheetname "")
		)
		(fill
			(thermal_gap 0.5)
			(thermal_bridge_width 0.5)
			(island_removal_mode 0)
		)
		(polygon
			(pts
				(xy 73.620122 -136.975342) (xy 74.178922 -136.975342) (xy 74.178922 -138.778742) (xy 73.620122 -138.778742)
			)
		)
	)
	(zone
		(layer "In12.Cu")
		(hatch none 0.5)
		(connect_pads
			(clearance 0)
		)
		(min_thickness 0.25)
		(keepout
			(tracks not_allowed)
			(vias allowed)
			(pads allowed)
			(copperpour not_allowed)
			(footprints allowed)
		)
		(placement
			(enabled no)
			(sheetname "")
		)
		(fill
			(thermal_gap 0.5)
			(thermal_bridge_width 0.5)
			(island_removal_mode 0)
		)
		(polygon
			(pts
				(xy 71.069962 -9.721342) (xy 71.628762 -9.721342) (xy 71.628762 -11.524742) (xy 71.069962 -11.524742)
			)
		)
	)
	(zone
		(layer "In12.Cu")
		(hatch none 0.5)
		(connect_pads
			(clearance 0)
		)
		(min_thickness 0.25)
		(keepout
			(tracks not_allowed)
			(vias allowed)
			(pads allowed)
			(copperpour not_allowed)
			(footprints allowed)
		)
		(placement
			(enabled no)
			(sheetname "")
		)
		(fill
			(thermal_gap 0.5)
			(thermal_bridge_width 0.5)
			(island_removal_mode 0)
		)
		(polygon
			(pts
				(xy 254.770382 -14.321282) (xy 255.329182 -14.321282) (xy 255.329182 -16.124682) (xy 254.770382 -16.124682)
			)
		)
	)
	(zone
		(layer "In12.Cu")
		(hatch none 0.5)
		(connect_pads
			(clearance 0)
		)
		(min_thickness 0.25)
		(keepout
			(tracks not_allowed)
			(vias allowed)
			(pads allowed)
			(copperpour not_allowed)
			(footprints allowed)
		)
		(placement
			(enabled no)
			(sheetname "")
		)
		(fill
			(thermal_gap 0.5)
			(thermal_bridge_width 0.5)
			(island_removal_mode 0)
		)
		(polygon
			(pts
				(xy 242.870482 -141.575282) (xy 243.429282 -141.575282) (xy 243.429282 -143.378682) (xy 242.870482 -143.378682)
			)
		)
	)
	(zone
		(layer "In12.Cu")
		(hatch none 0.5)
		(connect_pads
			(clearance 0)
		)
		(min_thickness 0.25)
		(keepout
			(tracks not_allowed)
			(vias allowed)
			(pads allowed)
			(copperpour not_allowed)
			(footprints allowed)
		)
		(placement
			(enabled no)
			(sheetname "")
		)
		(fill
			(thermal_gap 0.5)
			(thermal_bridge_width 0.5)
			(island_removal_mode 0)
		)
		(polygon
			(pts
				(xy 139.919964 -136.975342) (xy 140.478764 -136.975342) (xy 140.478764 -138.778742) (xy 139.919964 -138.778742)
			)
		)
	)
	(zone
		(layer "In12.Cu")
		(hatch none 0.5)
		(connect_pads
			(clearance 0)
		)
		(min_thickness 0.25)
		(keepout
			(tracks not_allowed)
			(vias allowed)
			(pads allowed)
			(copperpour not_allowed)
			(footprints allowed)
		)
		(placement
			(enabled no)
			(sheetname "")
		)
		(fill
			(thermal_gap 0.5)
			(thermal_bridge_width 0.5)
			(island_removal_mode 0)
		)
		(polygon
			(pts
				(xy 84.670138 -131.974082) (xy 85.228938 -131.974082) (xy 85.228938 -133.777482) (xy 84.670138 -133.777482)
			)
		)
	)
	(zone
		(net "PVDDQ_GHJ")
		(layer "In12.Cu")
		(hatch none 0.5)
		(connect_pads
			(clearance 0.5)
		)
		(min_thickness 0.25)
		(fill yes
			(thermal_gap 0.5)
			(thermal_bridge_width 0.5)
			(island_removal_mode 0)
		)
		(polygon
			(pts
				(xy 100.205794 -1.9177) (xy 99.9617 -2.161794) (xy 99.9617 -3.223006) (xy 100.129594 -3.3909) (xy 102.689406 -3.3909)
				(xy 103.349806 -2.7305) (xy 103.807006 -2.7305) (xy 103.9241 -2.613406) (xy 103.9241 -2.136394)
				(xy 103.705406 -1.9177)
			)
		)
	)
	(zone
		(layer "In12.Cu")
		(hatch none 0.5)
		(connect_pads
			(clearance 0)
		)
		(min_thickness 0.25)
		(keepout
			(tracks not_allowed)
			(vias allowed)
			(pads allowed)
			(copperpour not_allowed)
			(footprints allowed)
		)
		(placement
			(enabled no)
			(sheetname "")
		)
		(fill
			(thermal_gap 0.5)
			(thermal_bridge_width 0.5)
			(island_removal_mode 0)
		)
		(polygon
			(pts
				(xy 281.97048 -146.576542) (xy 282.52928 -146.576542) (xy 282.52928 -148.379942) (xy 281.97048 -148.379942)
			)
		)
	)
	(zone
		(layer "In12.Cu")
		(hatch none 0.5)
		(connect_pads
			(clearance 0)
		)
		(min_thickness 0.25)
		(keepout
			(tracks not_allowed)
			(vias allowed)
			(pads allowed)
			(copperpour not_allowed)
			(footprints allowed)
		)
		(placement
			(enabled no)
			(sheetname "")
		)
		(fill
			(thermal_gap 0.5)
			(thermal_bridge_width 0.5)
			(island_removal_mode 0)
		)
		(polygon
			(pts
				(xy 315.120528 -151.176482) (xy 315.679328 -151.176482) (xy 315.679328 -152.979882) (xy 315.120528 -152.979882)
			)
		)
	)
	(zone
		(layer "In12.Cu")
		(hatch none 0.5)
		(connect_pads
			(clearance 0)
		)
		(min_thickness 0.25)
		(keepout
			(tracks not_allowed)
			(vias allowed)
			(pads allowed)
			(copperpour not_allowed)
			(footprints allowed)
		)
		(placement
			(enabled no)
			(sheetname "")
		)
		(fill
			(thermal_gap 0.5)
			(thermal_bridge_width 0.5)
			(island_removal_mode 0)
		)
		(polygon
			(pts
				(xy 133.970014 -136.975342) (xy 134.528814 -136.975342) (xy 134.528814 -138.778742) (xy 133.970014 -138.778742)
			)
		)
	)
	(zone
		(layer "In12.Cu")
		(hatch none 0.5)
		(connect_pads
			(clearance 0)
		)
		(min_thickness 0.25)
		(keepout
			(tracks not_allowed)
			(vias allowed)
			(pads allowed)
			(copperpour not_allowed)
			(footprints allowed)
		)
		(placement
			(enabled no)
			(sheetname "")
		)
		(fill
			(thermal_gap 0.5)
			(thermal_bridge_width 0.5)
			(island_removal_mode 0)
		)
		(polygon
			(pts
				(xy 53.220112 -23.922482) (xy 53.778912 -23.922482) (xy 53.778912 -25.725882) (xy 53.220112 -25.725882)
			)
		)
	)
	(zone
		(layer "In12.Cu")
		(hatch none 0.5)
		(connect_pads
			(clearance 0)
		)
		(min_thickness 0.25)
		(keepout
			(tracks not_allowed)
			(vias allowed)
			(pads allowed)
			(copperpour not_allowed)
			(footprints allowed)
		)
		(placement
			(enabled no)
			(sheetname "")
		)
		(fill
			(thermal_gap 0.5)
			(thermal_bridge_width 0.5)
			(island_removal_mode 0)
		)
		(polygon
			(pts
				(xy 295.570402 -136.975342) (xy 296.129202 -136.975342) (xy 296.129202 -138.778742) (xy 295.570402 -138.778742)
			)
		)
	)
	(zone
		(layer "In12.Cu")
		(hatch none 0.5)
		(connect_pads
			(clearance 0)
		)
		(min_thickness 0.25)
		(keepout
			(tracks not_allowed)
			(vias allowed)
			(pads allowed)
			(copperpour not_allowed)
			(footprints allowed)
		)
		(placement
			(enabled no)
			(sheetname "")
		)
		(fill
			(thermal_gap 0.5)
			(thermal_bridge_width 0.5)
			(island_removal_mode 0)
		)
		(polygon
			(pts
				(xy 236.920532 -4.720082) (xy 237.479332 -4.720082) (xy 237.479332 -6.523482) (xy 236.920532 -6.523482)
			)
		)
	)
	(zone
		(layer "In12.Cu")
		(hatch none 0.5)
		(connect_pads
			(clearance 0)
		)
		(min_thickness 0.25)
		(keepout
			(tracks not_allowed)
			(vias allowed)
			(pads allowed)
			(copperpour not_allowed)
			(footprints allowed)
		)
		(placement
			(enabled no)
			(sheetname "")
		)
		(fill
			(thermal_gap 0.5)
			(thermal_bridge_width 0.5)
			(island_removal_mode 0)
		)
		(polygon
			(pts
				(xy 277.720552 -136.975342) (xy 278.279352 -136.975342) (xy 278.279352 -138.778742) (xy 277.720552 -138.778742)
			)
		)
	)
	(zone
		(layer "In12.Cu")
		(hatch none 0.5)
		(connect_pads
			(clearance 0)
		)
		(min_thickness 0.25)
		(keepout
			(tracks not_allowed)
			(vias allowed)
			(pads allowed)
			(copperpour not_allowed)
			(footprints allowed)
		)
		(placement
			(enabled no)
			(sheetname "")
		)
		(fill
			(thermal_gap 0.5)
			(thermal_bridge_width 0.5)
			(island_removal_mode 0)
		)
		(polygon
			(pts
				(xy 217.370406 -127.374142) (xy 217.929206 -127.374142) (xy 217.929206 -129.177542) (xy 217.370406 -129.177542)
			)
		)
	)
	(zone
		(layer "In12.Cu")
		(hatch none 0.5)
		(connect_pads
			(clearance 0)
		)
		(min_thickness 0.25)
		(keepout
			(tracks not_allowed)
			(vias allowed)
			(pads allowed)
			(copperpour not_allowed)
			(footprints allowed)
		)
		(placement
			(enabled no)
			(sheetname "")
		)
		(fill
			(thermal_gap 0.5)
			(thermal_bridge_width 0.5)
			(island_removal_mode 0)
		)
		(polygon
			(pts
				(xy 46.420024 -141.575282) (xy 46.978824 -141.575282) (xy 46.978824 -143.378682) (xy 46.420024 -143.378682)
			)
		)
	)
	(zone
		(layer "In12.Cu")
		(hatch none 0.5)
		(connect_pads
			(clearance 0)
		)
		(min_thickness 0.25)
		(keepout
			(tracks not_allowed)
			(vias allowed)
			(pads allowed)
			(copperpour not_allowed)
			(footprints allowed)
		)
		(placement
			(enabled no)
			(sheetname "")
		)
		(fill
			(thermal_gap 0.5)
			(thermal_bridge_width 0.5)
			(island_removal_mode 0)
		)
		(polygon
			(pts
				(xy 302.37049 -136.975342) (xy 302.92929 -136.975342) (xy 302.92929 -138.778742) (xy 302.37049 -138.778742)
			)
		)
	)
	(zone
		(layer "In12.Cu")
		(hatch none 0.5)
		(connect_pads
			(clearance 0)
		)
		(min_thickness 0.25)
		(keepout
			(tracks not_allowed)
			(vias allowed)
			(pads allowed)
			(copperpour not_allowed)
			(footprints allowed)
		)
		(placement
			(enabled no)
			(sheetname "")
		)
		(fill
			(thermal_gap 0.5)
			(thermal_bridge_width 0.5)
			(island_removal_mode 0)
		)
		(polygon
			(pts
				(xy 117.819932 -4.720082) (xy 118.378732 -4.720082) (xy 118.378732 -6.523482) (xy 117.819932 -6.523482)
			)
		)
	)
	(zone
		(layer "In12.Cu")
		(hatch none 0.5)
		(connect_pads
			(clearance 0)
		)
		(min_thickness 0.25)
		(keepout
			(tracks not_allowed)
			(vias allowed)
			(pads allowed)
			(copperpour not_allowed)
			(footprints allowed)
		)
		(placement
			(enabled no)
			(sheetname "")
		)
		(fill
			(thermal_gap 0.5)
			(thermal_bridge_width 0.5)
			(island_removal_mode 0)
		)
		(polygon
			(pts
				(xy 102.519988 -146.576542) (xy 103.078788 -146.576542) (xy 103.078788 -148.379942) (xy 102.519988 -148.379942)
			)
		)
	)
	(zone
		(layer "In12.Cu")
		(hatch none 0.5)
		(connect_pads
			(clearance 0)
		)
		(min_thickness 0.25)
		(keepout
			(tracks not_allowed)
			(vias allowed)
			(pads allowed)
			(copperpour not_allowed)
			(footprints allowed)
		)
		(placement
			(enabled no)
			(sheetname "")
		)
		(fill
			(thermal_gap 0.5)
			(thermal_bridge_width 0.5)
			(island_removal_mode 0)
		)
		(polygon
			(pts
				(xy 200.37044 -0.120142) (xy 200.92924 -0.120142) (xy 200.92924 -1.923542) (xy 200.37044 -1.923542)
			)
		)
	)
	(zone
		(layer "In12.Cu")
		(hatch none 0.5)
		(connect_pads
			(clearance 0)
		)
		(min_thickness 0.25)
		(keepout
			(tracks not_allowed)
			(vias allowed)
			(pads allowed)
			(copperpour not_allowed)
			(footprints allowed)
		)
		(placement
			(enabled no)
			(sheetname "")
		)
		(fill
			(thermal_gap 0.5)
			(thermal_bridge_width 0.5)
			(island_removal_mode 0)
		)
		(polygon
			(pts
				(xy 128.020064 -4.720082) (xy 128.578864 -4.720082) (xy 128.578864 -6.523482) (xy 128.020064 -6.523482)
			)
		)
	)
	(zone
		(layer "In12.Cu")
		(hatch none 0.5)
		(connect_pads
			(clearance 0)
		)
		(min_thickness 0.25)
		(keepout
			(tracks not_allowed)
			(vias allowed)
			(pads allowed)
			(copperpour not_allowed)
			(footprints allowed)
		)
		(placement
			(enabled no)
			(sheetname "")
		)
		(fill
			(thermal_gap 0.5)
			(thermal_bridge_width 0.5)
			(island_removal_mode 0)
		)
		(polygon
			(pts
				(xy 17.58442 -104.94772) (xy 18.98142 -104.94772) (xy 18.98142 -105.45572) (xy 17.58442 -105.45572)
			)
		)
	)
	(zone
		(layer "In12.Cu")
		(hatch none 0.5)
		(connect_pads
			(clearance 0)
		)
		(min_thickness 0.25)
		(keepout
			(tracks not_allowed)
			(vias allowed)
			(pads allowed)
			(copperpour not_allowed)
			(footprints allowed)
		)
		(placement
			(enabled no)
			(sheetname "")
		)
		(fill
			(thermal_gap 0.5)
			(thermal_bridge_width 0.5)
			(island_removal_mode 0)
		)
		(polygon
			(pts
				(xy 310.020462 -0.120142) (xy 310.579262 -0.120142) (xy 310.579262 -1.923542) (xy 310.020462 -1.923542)
			)
		)
	)
	(zone
		(layer "In12.Cu")
		(hatch none 0.5)
		(connect_pads
			(clearance 0)
		)
		(min_thickness 0.25)
		(keepout
			(tracks not_allowed)
			(vias allowed)
			(pads allowed)
			(copperpour not_allowed)
			(footprints allowed)
		)
		(placement
			(enabled no)
			(sheetname "")
		)
		(fill
			(thermal_gap 0.5)
			(thermal_bridge_width 0.5)
			(island_removal_mode 0)
		)
		(polygon
			(pts
				(xy 296.42054 -23.922482) (xy 296.97934 -23.922482) (xy 296.97934 -25.725882) (xy 296.42054 -25.725882)
			)
		)
	)
	(zone
		(layer "In12.Cu")
		(hatch none 0.5)
		(connect_pads
			(clearance 0)
		)
		(min_thickness 0.25)
		(keepout
			(tracks not_allowed)
			(vias allowed)
			(pads allowed)
			(copperpour not_allowed)
			(footprints allowed)
		)
		(placement
			(enabled no)
			(sheetname "")
		)
		(fill
			(thermal_gap 0.5)
			(thermal_bridge_width 0.5)
			(island_removal_mode 0)
		)
		(polygon
			(pts
				(xy 131.420108 -131.974082) (xy 131.978908 -131.974082) (xy 131.978908 -133.777482) (xy 131.420108 -133.777482)
			)
		)
	)
	(zone
		(layer "In12.Cu")
		(hatch none 0.5)
		(connect_pads
			(clearance 0)
		)
		(min_thickness 0.25)
		(keepout
			(tracks not_allowed)
			(vias allowed)
			(pads allowed)
			(copperpour not_allowed)
			(footprints allowed)
		)
		(placement
			(enabled no)
			(sheetname "")
		)
		(fill
			(thermal_gap 0.5)
			(thermal_bridge_width 0.5)
			(island_removal_mode 0)
		)
		(polygon
			(pts
				(xy 128.869948 -9.721342) (xy 129.428748 -9.721342) (xy 129.428748 -11.524742) (xy 128.869948 -11.524742)
			)
		)
	)
	(zone
		(layer "In12.Cu")
		(hatch none 0.5)
		(connect_pads
			(clearance 0)
		)
		(min_thickness 0.25)
		(keepout
			(tracks not_allowed)
			(vias allowed)
			(pads allowed)
			(copperpour not_allowed)
			(footprints allowed)
		)
		(placement
			(enabled no)
			(sheetname "")
		)
		(fill
			(thermal_gap 0.5)
			(thermal_bridge_width 0.5)
			(island_removal_mode 0)
		)
		(polygon
			(pts
				(xy 408.2542 -151.13) (xy 408.2542 -151.892) (xy 409.2448 -151.892) (xy 409.2448 -151.13)
			)
		)
	)
	(zone
		(net "PVDDQ_DEF")
		(layer "In12.Cu")
		(hatch none 0.5)
		(connect_pads
			(clearance 0.5)
		)
		(min_thickness 0.25)
		(fill yes
			(thermal_gap 0.5)
			(thermal_bridge_width 0.5)
			(island_removal_mode 0)
		)
		(polygon
			(pts
				(xy 265.229594 -129.1717) (xy 265.0363 -129.364994) (xy 265.0363 -130.654806) (xy 266.372594 -131.9911)
				(xy 278.127206 -131.9911) (xy 278.3713 -131.747006) (xy 278.3713 -130.761994) (xy 278.1427 -130.533394)
				(xy 278.1427 -129.943606) (xy 278.3205 -129.765806) (xy 278.3205 -129.415794) (xy 278.076406 -129.1717)
			)
		)
	)
	(zone
		(layer "In12.Cu")
		(hatch none 0.5)
		(connect_pads
			(clearance 0)
		)
		(min_thickness 0.25)
		(keepout
			(tracks not_allowed)
			(vias allowed)
			(pads allowed)
			(copperpour not_allowed)
			(footprints allowed)
		)
		(placement
			(enabled no)
			(sheetname "")
		)
		(fill
			(thermal_gap 0.5)
			(thermal_bridge_width 0.5)
			(island_removal_mode 0)
		)
		(polygon
			(pts
				(xy 12.86002 -100.20808) (xy 14.25702 -100.20808) (xy 14.25702 -100.71608) (xy 12.86002 -100.71608)
			)
		)
	)
	(zone
		(layer "In12.Cu")
		(hatch none 0.5)
		(connect_pads
			(clearance 0)
		)
		(min_thickness 0.25)
		(keepout
			(tracks not_allowed)
			(vias allowed)
			(pads allowed)
			(copperpour not_allowed)
			(footprints allowed)
		)
		(placement
			(enabled no)
			(sheetname "")
		)
		(fill
			(thermal_gap 0.5)
			(thermal_bridge_width 0.5)
			(island_removal_mode 0)
		)
		(polygon
			(pts
				(xy 385.209034 -27.268932) (xy 386.606034 -27.268932) (xy 386.606034 -27.776932) (xy 385.209034 -27.776932)
			)
		)
	)
	(zone
		(layer "In12.Cu")
		(hatch none 0.5)
		(connect_pads
			(clearance 0)
		)
		(min_thickness 0.25)
		(keepout
			(tracks not_allowed)
			(vias allowed)
			(pads allowed)
			(copperpour not_allowed)
			(footprints allowed)
		)
		(placement
			(enabled no)
			(sheetname "")
		)
		(fill
			(thermal_gap 0.5)
			(thermal_bridge_width 0.5)
			(island_removal_mode 0)
		)
		(polygon
			(pts
				(xy 302.37049 -141.575282) (xy 302.92929 -141.575282) (xy 302.92929 -143.378682) (xy 302.37049 -143.378682)
			)
		)
	)
	(zone
		(layer "In12.Cu")
		(hatch none 0.5)
		(connect_pads
			(clearance 0)
		)
		(min_thickness 0.25)
		(keepout
			(tracks not_allowed)
			(vias allowed)
			(pads allowed)
			(copperpour not_allowed)
			(footprints allowed)
		)
		(placement
			(enabled no)
			(sheetname "")
		)
		(fill
			(thermal_gap 0.5)
			(thermal_bridge_width 0.5)
			(island_removal_mode 0)
		)
		(polygon
			(pts
				(xy 137.370058 -0.120142) (xy 137.928858 -0.120142) (xy 137.928858 -1.923542) (xy 137.370058 -1.923542)
			)
		)
	)
	(zone
		(layer "In12.Cu")
		(hatch none 0.5)
		(connect_pads
			(clearance 0)
		)
		(min_thickness 0.25)
		(keepout
			(tracks not_allowed)
			(vias allowed)
			(pads allowed)
			(copperpour not_allowed)
			(footprints allowed)
		)
		(placement
			(enabled no)
			(sheetname "")
		)
		(fill
			(thermal_gap 0.5)
			(thermal_bridge_width 0.5)
			(island_removal_mode 0)
		)
		(polygon
			(pts
				(xy 133.970014 -146.576542) (xy 134.528814 -146.576542) (xy 134.528814 -148.379942) (xy 133.970014 -148.379942)
			)
		)
	)
	(zone
		(layer "In12.Cu")
		(hatch none 0.5)
		(connect_pads
			(clearance 0)
		)
		(min_thickness 0.25)
		(keepout
			(tracks not_allowed)
			(vias allowed)
			(pads allowed)
			(copperpour not_allowed)
			(footprints allowed)
		)
		(placement
			(enabled no)
			(sheetname "")
		)
		(fill
			(thermal_gap 0.5)
			(thermal_bridge_width 0.5)
			(island_removal_mode 0)
		)
		(polygon
			(pts
				(xy 310.870346 -23.922482) (xy 311.429146 -23.922482) (xy 311.429146 -25.725882) (xy 310.870346 -25.725882)
			)
		)
	)
	(zone
		(layer "In12.Cu")
		(hatch none 0.5)
		(connect_pads
			(clearance 0)
		)
		(min_thickness 0.25)
		(keepout
			(tracks not_allowed)
			(vias allowed)
			(pads allowed)
			(copperpour not_allowed)
			(footprints allowed)
		)
		(placement
			(enabled no)
			(sheetname "")
		)
		(fill
			(thermal_gap 0.5)
			(thermal_bridge_width 0.5)
			(island_removal_mode 0)
		)
		(polygon
			(pts
				(xy 139.07008 -131.974082) (xy 139.62888 -131.974082) (xy 139.62888 -133.777482) (xy 139.07008 -133.777482)
			)
		)
	)
	(zone
		(layer "In12.Cu")
		(hatch none 0.5)
		(connect_pads
			(clearance 0)
		)
		(min_thickness 0.25)
		(keepout
			(tracks not_allowed)
			(vias allowed)
			(pads allowed)
			(copperpour not_allowed)
			(footprints allowed)
		)
		(placement
			(enabled no)
			(sheetname "")
		)
		(fill
			(thermal_gap 0.5)
			(thermal_bridge_width 0.5)
			(island_removal_mode 0)
		)
		(polygon
			(pts
				(xy 251.370592 -151.176482) (xy 251.929392 -151.176482) (xy 251.929392 -152.979882) (xy 251.370592 -152.979882)
			)
		)
	)
	(zone
		(layer "In12.Cu")
		(hatch none 0.5)
		(connect_pads
			(clearance 0)
		)
		(min_thickness 0.25)
		(keepout
			(tracks not_allowed)
			(vias allowed)
			(pads allowed)
			(copperpour not_allowed)
			(footprints allowed)
		)
		(placement
			(enabled no)
			(sheetname "")
		)
		(fill
			(thermal_gap 0.5)
			(thermal_bridge_width 0.5)
			(island_removal_mode 0)
		)
		(polygon
			(pts
				(xy 235.22051 -4.720082) (xy 235.77931 -4.720082) (xy 235.77931 -6.523482) (xy 235.22051 -6.523482)
			)
		)
	)
	(zone
		(layer "In12.Cu")
		(hatch none 0.5)
		(connect_pads
			(clearance 0)
		)
		(min_thickness 0.25)
		(keepout
			(tracks not_allowed)
			(vias allowed)
			(pads allowed)
			(copperpour not_allowed)
			(footprints allowed)
		)
		(placement
			(enabled no)
			(sheetname "")
		)
		(fill
			(thermal_gap 0.5)
			(thermal_bridge_width 0.5)
			(island_removal_mode 0)
		)
		(polygon
			(pts
				(xy 302.37049 -23.922482) (xy 302.92929 -23.922482) (xy 302.92929 -25.725882) (xy 302.37049 -25.725882)
			)
		)
	)
	(zone
		(layer "In12.Cu")
		(hatch none 0.5)
		(connect_pads
			(clearance 0)
		)
		(min_thickness 0.25)
		(keepout
			(tracks not_allowed)
			(vias allowed)
			(pads allowed)
			(copperpour not_allowed)
			(footprints allowed)
		)
		(placement
			(enabled no)
			(sheetname "")
		)
		(fill
			(thermal_gap 0.5)
			(thermal_bridge_width 0.5)
			(island_removal_mode 0)
		)
		(polygon
			(pts
				(xy 254.770382 -0.120142) (xy 255.329182 -0.120142) (xy 255.329182 -1.923542) (xy 254.770382 -1.923542)
			)
		)
	)
	(zone
		(layer "In12.Cu")
		(hatch none 0.5)
		(connect_pads
			(clearance 0)
		)
		(min_thickness 0.25)
		(keepout
			(tracks not_allowed)
			(vias allowed)
			(pads allowed)
			(copperpour not_allowed)
			(footprints allowed)
		)
		(placement
			(enabled no)
			(sheetname "")
		)
		(fill
			(thermal_gap 0.5)
			(thermal_bridge_width 0.5)
			(island_removal_mode 0)
		)
		(polygon
			(pts
				(xy 137.370058 -23.922482) (xy 137.928858 -23.922482) (xy 137.928858 -25.725882) (xy 137.370058 -25.725882)
			)
		)
	)
	(zone
		(layer "In12.Cu")
		(hatch none 0.5)
		(connect_pads
			(clearance 0)
		)
		(min_thickness 0.25)
		(keepout
			(tracks not_allowed)
			(vias allowed)
			(pads allowed)
			(copperpour not_allowed)
			(footprints allowed)
		)
		(placement
			(enabled no)
			(sheetname "")
		)
		(fill
			(thermal_gap 0.5)
			(thermal_bridge_width 0.5)
			(island_removal_mode 0)
		)
		(polygon
			(pts
				(xy 140.770102 -141.575282) (xy 141.328902 -141.575282) (xy 141.328902 -143.378682) (xy 140.770102 -143.378682)
			)
		)
	)
	(zone
		(layer "In12.Cu")
		(hatch none 0.5)
		(connect_pads
			(clearance 0)
		)
		(min_thickness 0.25)
		(keepout
			(tracks not_allowed)
			(vias allowed)
			(pads allowed)
			(copperpour not_allowed)
			(footprints allowed)
		)
		(placement
			(enabled no)
			(sheetname "")
		)
		(fill
			(thermal_gap 0.5)
			(thermal_bridge_width 0.5)
			(island_removal_mode 0)
		)
		(polygon
			(pts
				(xy 67.669918 -19.322542) (xy 68.228718 -19.322542) (xy 68.228718 -21.125942) (xy 67.669918 -21.125942)
			)
		)
	)
	(zone
		(layer "In12.Cu")
		(hatch none 0.5)
		(connect_pads
			(clearance 0)
		)
		(min_thickness 0.25)
		(keepout
			(tracks not_allowed)
			(vias allowed)
			(pads allowed)
			(copperpour not_allowed)
			(footprints allowed)
		)
		(placement
			(enabled no)
			(sheetname "")
		)
		(fill
			(thermal_gap 0.5)
			(thermal_bridge_width 0.5)
			(island_removal_mode 0)
		)
		(polygon
			(pts
				(xy 410.4132 -148.717) (xy 410.4132 -149.479) (xy 411.4038 -149.479) (xy 411.4038 -148.717)
			)
		)
	)
	(zone
		(layer "In12.Cu")
		(hatch none 0.5)
		(connect_pads
			(clearance 0)
		)
		(min_thickness 0.25)
		(keepout
			(tracks not_allowed)
			(vias allowed)
			(pads allowed)
			(copperpour not_allowed)
			(footprints allowed)
		)
		(placement
			(enabled no)
			(sheetname "")
		)
		(fill
			(thermal_gap 0.5)
			(thermal_bridge_width 0.5)
			(island_removal_mode 0)
		)
		(polygon
			(pts
				(xy 303.220374 -9.721342) (xy 303.779174 -9.721342) (xy 303.779174 -11.524742) (xy 303.220374 -11.524742)
			)
		)
	)
	(zone
		(layer "In12.Cu")
		(hatch none 0.5)
		(connect_pads
			(clearance 0)
		)
		(min_thickness 0.25)
		(keepout
			(tracks not_allowed)
			(vias allowed)
			(pads allowed)
			(copperpour not_allowed)
			(footprints allowed)
		)
		(placement
			(enabled no)
			(sheetname "")
		)
		(fill
			(thermal_gap 0.5)
			(thermal_bridge_width 0.5)
			(island_removal_mode 0)
		)
		(polygon
			(pts
				(xy 79.570072 -131.974082) (xy 80.128872 -131.974082) (xy 80.128872 -133.777482) (xy 79.570072 -133.777482)
			)
		)
	)
	(zone
		(layer "In12.Cu")
		(hatch none 0.5)
		(connect_pads
			(clearance 0)
		)
		(min_thickness 0.25)
		(keepout
			(tracks not_allowed)
			(vias allowed)
			(pads allowed)
			(copperpour not_allowed)
			(footprints allowed)
		)
		(placement
			(enabled no)
			(sheetname "")
		)
		(fill
			(thermal_gap 0.5)
			(thermal_bridge_width 0.5)
			(island_removal_mode 0)
		)
		(polygon
			(pts
				(xy 209.720434 -23.922482) (xy 210.279234 -23.922482) (xy 210.279234 -25.725882) (xy 209.720434 -25.725882)
			)
		)
	)
	(zone
		(layer "In12.Cu")
		(hatch none 0.5)
		(connect_pads
			(clearance 0)
		)
		(min_thickness 0.25)
		(keepout
			(tracks not_allowed)
			(vias allowed)
			(pads allowed)
			(copperpour not_allowed)
			(footprints allowed)
		)
		(placement
			(enabled no)
			(sheetname "")
		)
		(fill
			(thermal_gap 0.5)
			(thermal_bridge_width 0.5)
			(island_removal_mode 0)
		)
		(polygon
			(pts
				(xy 351.761806 -59.225434) (xy 351.761806 -61.511434) (xy 351.253806 -61.511434) (xy 351.253806 -59.225434)
			)
		)
	)
	(zone
		(layer "In12.Cu")
		(hatch none 0.5)
		(connect_pads
			(clearance 0)
		)
		(min_thickness 0.25)
		(keepout
			(tracks not_allowed)
			(vias allowed)
			(pads allowed)
			(copperpour not_allowed)
			(footprints allowed)
		)
		(placement
			(enabled no)
			(sheetname "")
		)
		(fill
			(thermal_gap 0.5)
			(thermal_bridge_width 0.5)
			(island_removal_mode 0)
		)
		(polygon
			(pts
				(xy 265.820398 -4.720082) (xy 266.379198 -4.720082) (xy 266.379198 -6.523482) (xy 265.820398 -6.523482)
			)
		)
	)
	(zone
		(layer "In12.Cu")
		(hatch none 0.5)
		(connect_pads
			(clearance 0)
		)
		(min_thickness 0.25)
		(keepout
			(tracks not_allowed)
			(vias allowed)
			(pads allowed)
			(copperpour not_allowed)
			(footprints allowed)
		)
		(placement
			(enabled no)
			(sheetname "")
		)
		(fill
			(thermal_gap 0.5)
			(thermal_bridge_width 0.5)
			(island_removal_mode 0)
		)
		(polygon
			(pts
				(xy 287.92043 -19.322542) (xy 288.47923 -19.322542) (xy 288.47923 -21.125942) (xy 287.92043 -21.125942)
			)
		)
	)
	(zone
		(layer "In12.Cu")
		(hatch none 0.5)
		(connect_pads
			(clearance 0)
		)
		(min_thickness 0.25)
		(keepout
			(tracks not_allowed)
			(vias allowed)
			(pads allowed)
			(copperpour not_allowed)
			(footprints allowed)
		)
		(placement
			(enabled no)
			(sheetname "")
		)
		(fill
			(thermal_gap 0.5)
			(thermal_bridge_width 0.5)
			(island_removal_mode 0)
		)
		(polygon
			(pts
				(xy 301.520352 -4.720082) (xy 302.079152 -4.720082) (xy 302.079152 -6.523482) (xy 301.520352 -6.523482)
			)
		)
	)
	(zone
		(layer "In12.Cu")
		(hatch none 0.5)
		(connect_pads
			(clearance 0)
		)
		(min_thickness 0.25)
		(keepout
			(tracks not_allowed)
			(vias allowed)
			(pads allowed)
			(copperpour not_allowed)
			(footprints allowed)
		)
		(placement
			(enabled no)
			(sheetname "")
		)
		(fill
			(thermal_gap 0.5)
			(thermal_bridge_width 0.5)
			(island_removal_mode 0)
		)
		(polygon
			(pts
				(xy 76.170282 -141.575282) (xy 76.729082 -141.575282) (xy 76.729082 -143.378682) (xy 76.170282 -143.378682)
			)
		)
	)
	(zone
		(layer "In12.Cu")
		(hatch none 0.5)
		(connect_pads
			(clearance 0)
		)
		(min_thickness 0.25)
		(keepout
			(tracks not_allowed)
			(vias allowed)
			(pads allowed)
			(copperpour not_allowed)
			(footprints allowed)
		)
		(placement
			(enabled no)
			(sheetname "")
		)
		(fill
			(thermal_gap 0.5)
			(thermal_bridge_width 0.5)
			(island_removal_mode 0)
		)
		(polygon
			(pts
				(xy 219.070428 -127.374142) (xy 219.629228 -127.374142) (xy 219.629228 -129.177542) (xy 219.070428 -129.177542)
			)
		)
	)
	(zone
		(layer "In12.Cu")
		(hatch none 0.5)
		(connect_pads
			(clearance 0)
		)
		(min_thickness 0.25)
		(keepout
			(tracks not_allowed)
			(vias allowed)
			(pads allowed)
			(copperpour not_allowed)
			(footprints allowed)
		)
		(placement
			(enabled no)
			(sheetname "")
		)
		(fill
			(thermal_gap 0.5)
			(thermal_bridge_width 0.5)
			(island_removal_mode 0)
		)
		(polygon
			(pts
				(xy 63.41999 -141.575282) (xy 63.97879 -141.575282) (xy 63.97879 -143.378682) (xy 63.41999 -143.378682)
			)
		)
	)
	(zone
		(layer "In12.Cu")
		(hatch none 0.5)
		(connect_pads
			(clearance 0)
		)
		(min_thickness 0.25)
		(keepout
			(tracks not_allowed)
			(vias allowed)
			(pads allowed)
			(copperpour not_allowed)
			(footprints allowed)
		)
		(placement
			(enabled no)
			(sheetname "")
		)
		(fill
			(thermal_gap 0.5)
			(thermal_bridge_width 0.5)
			(island_removal_mode 0)
		)
		(polygon
			(pts
				(xy 219.070428 -136.975342) (xy 219.629228 -136.975342) (xy 219.629228 -138.778742) (xy 219.070428 -138.778742)
			)
		)
	)
	(zone
		(layer "In12.Cu")
		(hatch none 0.5)
		(connect_pads
			(clearance 0)
		)
		(min_thickness 0.25)
		(keepout
			(tracks not_allowed)
			(vias allowed)
			(pads allowed)
			(copperpour not_allowed)
			(footprints allowed)
		)
		(placement
			(enabled no)
			(sheetname "")
		)
		(fill
			(thermal_gap 0.5)
			(thermal_bridge_width 0.5)
			(island_removal_mode 0)
		)
		(polygon
			(pts
				(xy 217.370406 -19.322542) (xy 217.929206 -19.322542) (xy 217.929206 -21.125942) (xy 217.370406 -21.125942)
			)
		)
	)
	(zone
		(layer "In12.Cu")
		(hatch none 0.5)
		(connect_pads
			(clearance 0)
		)
		(min_thickness 0.25)
		(keepout
			(tracks not_allowed)
			(vias allowed)
			(pads allowed)
			(copperpour not_allowed)
			(footprints allowed)
		)
		(placement
			(enabled no)
			(sheetname "")
		)
		(fill
			(thermal_gap 0.5)
			(thermal_bridge_width 0.5)
			(island_removal_mode 0)
		)
		(polygon
			(pts
				(xy 44.720002 -9.721342) (xy 45.278802 -9.721342) (xy 45.278802 -11.524742) (xy 44.720002 -11.524742)
			)
		)
	)
	(zone
		(layer "In12.Cu")
		(hatch none 0.5)
		(connect_pads
			(clearance 0)
		)
		(min_thickness 0.25)
		(keepout
			(tracks not_allowed)
			(vias allowed)
			(pads allowed)
			(copperpour not_allowed)
			(footprints allowed)
		)
		(placement
			(enabled no)
			(sheetname "")
		)
		(fill
			(thermal_gap 0.5)
			(thermal_bridge_width 0.5)
			(island_removal_mode 0)
		)
		(polygon
			(pts
				(xy 336.394806 -59.225434) (xy 336.394806 -61.511434) (xy 335.886806 -61.511434) (xy 335.886806 -59.225434)
			)
		)
	)
	(zone
		(layer "In12.Cu")
		(hatch none 0.5)
		(connect_pads
			(clearance 0)
		)
		(min_thickness 0.25)
		(keepout
			(tracks not_allowed)
			(vias allowed)
			(pads allowed)
			(copperpour not_allowed)
			(footprints allowed)
		)
		(placement
			(enabled no)
			(sheetname "")
		)
		(fill
			(thermal_gap 0.5)
			(thermal_bridge_width 0.5)
			(island_removal_mode 0)
		)
		(polygon
			(pts
				(xy 279.42032 -14.321282) (xy 279.97912 -14.321282) (xy 279.97912 -16.124682) (xy 279.42032 -16.124682)
			)
		)
	)
	(zone
		(layer "In12.Cu")
		(hatch none 0.5)
		(connect_pads
			(clearance 0)
		)
		(min_thickness 0.25)
		(keepout
			(tracks not_allowed)
			(vias allowed)
			(pads allowed)
			(copperpour not_allowed)
			(footprints allowed)
		)
		(placement
			(enabled no)
			(sheetname "")
		)
		(fill
			(thermal_gap 0.5)
			(thermal_bridge_width 0.5)
			(island_removal_mode 0)
		)
		(polygon
			(pts
				(xy 72.769984 -19.322542) (xy 73.328784 -19.322542) (xy 73.328784 -21.125942) (xy 72.769984 -21.125942)
			)
		)
	)
	(zone
		(layer "In12.Cu")
		(hatch none 0.5)
		(connect_pads
			(clearance 0)
		)
		(min_thickness 0.25)
		(keepout
			(tracks not_allowed)
			(vias allowed)
			(pads allowed)
			(copperpour not_allowed)
			(footprints allowed)
		)
		(placement
			(enabled no)
			(sheetname "")
		)
		(fill
			(thermal_gap 0.5)
			(thermal_bridge_width 0.5)
			(island_removal_mode 0)
		)
		(polygon
			(pts
				(xy 146.720052 -9.721342) (xy 147.278852 -9.721342) (xy 147.278852 -11.524742) (xy 146.720052 -11.524742)
			)
		)
	)
	(zone
		(layer "In12.Cu")
		(hatch none 0.5)
		(connect_pads
			(clearance 0)
		)
		(min_thickness 0.25)
		(keepout
			(tracks not_allowed)
			(vias allowed)
			(pads allowed)
			(copperpour not_allowed)
			(footprints allowed)
		)
		(placement
			(enabled no)
			(sheetname "")
		)
		(fill
			(thermal_gap 0.5)
			(thermal_bridge_width 0.5)
			(island_removal_mode 0)
		)
		(polygon
			(pts
				(xy 206.32039 -0.120142) (xy 206.87919 -0.120142) (xy 206.87919 -1.923542) (xy 206.32039 -1.923542)
			)
		)
	)
	(zone
		(layer "In12.Cu")
		(hatch none 0.5)
		(connect_pads
			(clearance 0)
		)
		(min_thickness 0.25)
		(keepout
			(tracks not_allowed)
			(vias allowed)
			(pads allowed)
			(copperpour not_allowed)
			(footprints allowed)
		)
		(placement
			(enabled no)
			(sheetname "")
		)
		(fill
			(thermal_gap 0.5)
			(thermal_bridge_width 0.5)
			(island_removal_mode 0)
		)
		(polygon
			(pts
				(xy 43.01998 -0.120142) (xy 43.57878 -0.120142) (xy 43.57878 -1.923542) (xy 43.01998 -1.923542)
			)
		)
	)
	(zone
		(layer "In12.Cu")
		(hatch none 0.5)
		(connect_pads
			(clearance 0)
		)
		(min_thickness 0.25)
		(keepout
			(tracks not_allowed)
			(vias allowed)
			(pads allowed)
			(copperpour not_allowed)
			(footprints allowed)
		)
		(placement
			(enabled no)
			(sheetname "")
		)
		(fill
			(thermal_gap 0.5)
			(thermal_bridge_width 0.5)
			(island_removal_mode 0)
		)
		(polygon
			(pts
				(xy 310.870346 -141.575282) (xy 311.429146 -141.575282) (xy 311.429146 -143.378682) (xy 310.870346 -143.378682)
			)
		)
	)
	(zone
		(layer "In12.Cu")
		(hatch none 0.5)
		(connect_pads
			(clearance 0)
		)
		(min_thickness 0.25)
		(keepout
			(tracks not_allowed)
			(vias allowed)
			(pads allowed)
			(copperpour not_allowed)
			(footprints allowed)
		)
		(placement
			(enabled no)
			(sheetname "")
		)
		(fill
			(thermal_gap 0.5)
			(thermal_bridge_width 0.5)
			(island_removal_mode 0)
		)
		(polygon
			(pts
				(xy 224.170494 -4.720082) (xy 224.729294 -4.720082) (xy 224.729294 -6.523482) (xy 224.170494 -6.523482)
			)
		)
	)
	(zone
		(layer "In12.Cu")
		(hatch none 0.5)
		(connect_pads
			(clearance 0)
		)
		(min_thickness 0.25)
		(keepout
			(tracks not_allowed)
			(vias allowed)
			(pads allowed)
			(copperpour not_allowed)
			(footprints allowed)
		)
		(placement
			(enabled no)
			(sheetname "")
		)
		(fill
			(thermal_gap 0.5)
			(thermal_bridge_width 0.5)
			(island_removal_mode 0)
		)
		(polygon
			(pts
				(xy 54.069996 -0.120142) (xy 54.628796 -0.120142) (xy 54.628796 -1.923542) (xy 54.069996 -1.923542)
			)
		)
	)
	(zone
		(layer "In12.Cu")
		(hatch none 0.5)
		(connect_pads
			(clearance 0)
		)
		(min_thickness 0.25)
		(keepout
			(tracks not_allowed)
			(vias allowed)
			(pads allowed)
			(copperpour not_allowed)
			(footprints allowed)
		)
		(placement
			(enabled no)
			(sheetname "")
		)
		(fill
			(thermal_gap 0.5)
			(thermal_bridge_width 0.5)
			(island_removal_mode 0)
		)
		(polygon
			(pts
				(xy 118.67007 -23.922482) (xy 119.22887 -23.922482) (xy 119.22887 -25.725882) (xy 118.67007 -25.725882)
			)
		)
	)
	(zone
		(layer "In12.Cu")
		(hatch none 0.5)
		(connect_pads
			(clearance 0)
		)
		(min_thickness 0.25)
		(keepout
			(tracks not_allowed)
			(vias allowed)
			(pads allowed)
			(copperpour not_allowed)
			(footprints allowed)
		)
		(placement
			(enabled no)
			(sheetname "")
		)
		(fill
			(thermal_gap 0.5)
			(thermal_bridge_width 0.5)
			(island_removal_mode 0)
		)
		(polygon
			(pts
				(xy 273.47037 -146.576542) (xy 274.02917 -146.576542) (xy 274.02917 -148.379942) (xy 273.47037 -148.379942)
			)
		)
	)
	(zone
		(layer "In12.Cu")
		(hatch none 0.5)
		(connect_pads
			(clearance 0)
		)
		(min_thickness 0.25)
		(keepout
			(tracks not_allowed)
			(vias allowed)
			(pads allowed)
			(copperpour not_allowed)
			(footprints allowed)
		)
		(placement
			(enabled no)
			(sheetname "")
		)
		(fill
			(thermal_gap 0.5)
			(thermal_bridge_width 0.5)
			(island_removal_mode 0)
		)
		(polygon
			(pts
				(xy 70.220078 -141.575282) (xy 70.778878 -141.575282) (xy 70.778878 -143.378682) (xy 70.220078 -143.378682)
			)
		)
	)
	(zone
		(layer "In12.Cu")
		(hatch none 0.5)
		(connect_pads
			(clearance 0)
		)
		(min_thickness 0.25)
		(keepout
			(tracks not_allowed)
			(vias allowed)
			(pads allowed)
			(copperpour not_allowed)
			(footprints allowed)
		)
		(placement
			(enabled no)
			(sheetname "")
		)
		(fill
			(thermal_gap 0.5)
			(thermal_bridge_width 0.5)
			(island_removal_mode 0)
		)
		(polygon
			(pts
				(xy 103.370126 -141.575282) (xy 103.928926 -141.575282) (xy 103.928926 -143.378682) (xy 103.370126 -143.378682)
			)
		)
	)
	(zone
		(layer "In12.Cu")
		(hatch none 0.5)
		(connect_pads
			(clearance 0)
		)
		(min_thickness 0.25)
		(keepout
			(tracks not_allowed)
			(vias allowed)
			(pads allowed)
			(copperpour not_allowed)
			(footprints allowed)
		)
		(placement
			(enabled no)
			(sheetname "")
		)
		(fill
			(thermal_gap 0.5)
			(thermal_bridge_width 0.5)
			(island_removal_mode 0)
		)
		(polygon
			(pts
				(xy 410.1592 -140.6398) (xy 410.1592 -141.4018) (xy 411.1498 -141.4018) (xy 411.1498 -140.6398)
			)
		)
	)
	(zone
		(layer "In12.Cu")
		(hatch none 0.5)
		(connect_pads
			(clearance 0)
		)
		(min_thickness 0.25)
		(keepout
			(tracks not_allowed)
			(vias allowed)
			(pads allowed)
			(copperpour not_allowed)
			(footprints allowed)
		)
		(placement
			(enabled no)
			(sheetname "")
		)
		(fill
			(thermal_gap 0.5)
			(thermal_bridge_width 0.5)
			(island_removal_mode 0)
		)
		(polygon
			(pts
				(xy 237.770416 -9.721342) (xy 238.329216 -9.721342) (xy 238.329216 -11.524742) (xy 237.770416 -11.524742)
			)
		)
	)
	(zone
		(layer "In12.Cu")
		(hatch none 0.5)
		(connect_pads
			(clearance 0)
		)
		(min_thickness 0.25)
		(keepout
			(tracks not_allowed)
			(vias allowed)
			(pads allowed)
			(copperpour not_allowed)
			(footprints allowed)
		)
		(placement
			(enabled no)
			(sheetname "")
		)
		(fill
			(thermal_gap 0.5)
			(thermal_bridge_width 0.5)
			(island_removal_mode 0)
		)
		(polygon
			(pts
				(xy 249.67057 -141.575282) (xy 250.22937 -141.575282) (xy 250.22937 -143.378682) (xy 249.67057 -143.378682)
			)
		)
	)
	(zone
		(layer "In12.Cu")
		(hatch none 0.5)
		(connect_pads
			(clearance 0)
		)
		(min_thickness 0.25)
		(keepout
			(tracks not_allowed)
			(vias allowed)
			(pads allowed)
			(copperpour not_allowed)
			(footprints allowed)
		)
		(placement
			(enabled no)
			(sheetname "")
		)
		(fill
			(thermal_gap 0.5)
			(thermal_bridge_width 0.5)
			(island_removal_mode 0)
		)
		(polygon
			(pts
				(xy 286.220408 -9.721342) (xy 286.779208 -9.721342) (xy 286.779208 -11.524742) (xy 286.220408 -11.524742)
			)
		)
	)
	(zone
		(layer "In12.Cu")
		(hatch none 0.5)
		(connect_pads
			(clearance 0)
		)
		(min_thickness 0.25)
		(keepout
			(tracks not_allowed)
			(vias allowed)
			(pads allowed)
			(copperpour not_allowed)
			(footprints allowed)
		)
		(placement
			(enabled no)
			(sheetname "")
		)
		(fill
			(thermal_gap 0.5)
			(thermal_bridge_width 0.5)
			(island_removal_mode 0)
		)
		(polygon
			(pts
				(xy 252.220476 -127.374142) (xy 252.779276 -127.374142) (xy 252.779276 -129.177542) (xy 252.220476 -129.177542)
			)
		)
	)
	(zone
		(layer "In12.Cu")
		(hatch none 0.5)
		(connect_pads
			(clearance 0)
		)
		(min_thickness 0.25)
		(keepout
			(tracks not_allowed)
			(vias allowed)
			(pads allowed)
			(copperpour not_allowed)
			(footprints allowed)
		)
		(placement
			(enabled no)
			(sheetname "")
		)
		(fill
			(thermal_gap 0.5)
			(thermal_bridge_width 0.5)
			(island_removal_mode 0)
		)
		(polygon
			(pts
				(xy 50.669952 -136.975342) (xy 51.228752 -136.975342) (xy 51.228752 -138.778742) (xy 50.669952 -138.778742)
			)
		)
	)
	(zone
		(layer "In12.Cu")
		(hatch none 0.5)
		(connect_pads
			(clearance 0)
		)
		(min_thickness 0.25)
		(keepout
			(tracks not_allowed)
			(vias allowed)
			(pads allowed)
			(copperpour not_allowed)
			(footprints allowed)
		)
		(placement
			(enabled no)
			(sheetname "")
		)
		(fill
			(thermal_gap 0.5)
			(thermal_bridge_width 0.5)
			(island_removal_mode 0)
		)
		(polygon
			(pts
				(xy 31.12008 -23.922482) (xy 31.67888 -23.922482) (xy 31.67888 -25.725882) (xy 31.12008 -25.725882)
			)
		)
	)
	(zone
		(layer "In12.Cu")
		(hatch none 0.5)
		(connect_pads
			(clearance 0)
		)
		(min_thickness 0.25)
		(keepout
			(tracks not_allowed)
			(vias allowed)
			(pads allowed)
			(copperpour not_allowed)
			(footprints allowed)
		)
		(placement
			(enabled no)
			(sheetname "")
		)
		(fill
			(thermal_gap 0.5)
			(thermal_bridge_width 0.5)
			(island_removal_mode 0)
		)
		(polygon
			(pts
				(xy 458.597 -115.34902) (xy 459.105 -115.34902) (xy 459.105 -116.74602) (xy 458.597 -116.74602)
			)
		)
	)
	(zone
		(layer "In12.Cu")
		(hatch none 0.5)
		(connect_pads
			(clearance 0)
		)
		(min_thickness 0.25)
		(keepout
			(tracks not_allowed)
			(vias allowed)
			(pads allowed)
			(copperpour not_allowed)
			(footprints allowed)
		)
		(placement
			(enabled no)
			(sheetname "")
		)
		(fill
			(thermal_gap 0.5)
			(thermal_bridge_width 0.5)
			(island_removal_mode 0)
		)
		(polygon
			(pts
				(xy 199.520556 -131.974082) (xy 200.079356 -131.974082) (xy 200.079356 -133.777482) (xy 199.520556 -133.777482)
			)
		)
	)
	(zone
		(layer "In12.Cu")
		(hatch none 0.5)
		(connect_pads
			(clearance 0)
		)
		(min_thickness 0.25)
		(keepout
			(tracks not_allowed)
			(vias allowed)
			(pads allowed)
			(copperpour not_allowed)
			(footprints allowed)
		)
		(placement
			(enabled no)
			(sheetname "")
		)
		(fill
			(thermal_gap 0.5)
			(thermal_bridge_width 0.5)
			(island_removal_mode 0)
		)
		(polygon
			(pts
				(xy 311.720484 -23.922482) (xy 312.279284 -23.922482) (xy 312.279284 -25.725882) (xy 311.720484 -25.725882)
			)
		)
	)
	(zone
		(layer "In12.Cu")
		(hatch none 0.5)
		(connect_pads
			(clearance 0)
		)
		(min_thickness 0.25)
		(keepout
			(tracks not_allowed)
			(vias allowed)
			(pads allowed)
			(copperpour not_allowed)
			(footprints allowed)
		)
		(placement
			(enabled no)
			(sheetname "")
		)
		(fill
			(thermal_gap 0.5)
			(thermal_bridge_width 0.5)
			(island_removal_mode 0)
		)
		(polygon
			(pts
				(xy 140.770102 -14.321282) (xy 141.328902 -14.321282) (xy 141.328902 -16.124682) (xy 140.770102 -16.124682)
			)
		)
	)
	(zone
		(layer "In12.Cu")
		(hatch none 0.5)
		(connect_pads
			(clearance 0)
		)
		(min_thickness 0.25)
		(keepout
			(tracks not_allowed)
			(vias allowed)
			(pads allowed)
			(copperpour not_allowed)
			(footprints allowed)
		)
		(placement
			(enabled no)
			(sheetname "")
		)
		(fill
			(thermal_gap 0.5)
			(thermal_bridge_width 0.5)
			(island_removal_mode 0)
		)
		(polygon
			(pts
				(xy 124.62002 -19.322542) (xy 125.17882 -19.322542) (xy 125.17882 -21.125942) (xy 124.62002 -21.125942)
			)
		)
	)
	(zone
		(layer "In12.Cu")
		(hatch none 0.5)
		(connect_pads
			(clearance 0)
		)
		(min_thickness 0.25)
		(keepout
			(tracks not_allowed)
			(vias allowed)
			(pads allowed)
			(copperpour not_allowed)
			(footprints allowed)
		)
		(placement
			(enabled no)
			(sheetname "")
		)
		(fill
			(thermal_gap 0.5)
			(thermal_bridge_width 0.5)
			(island_removal_mode 0)
		)
		(polygon
			(pts
				(xy 81.270094 -141.575282) (xy 81.828894 -141.575282) (xy 81.828894 -143.378682) (xy 81.270094 -143.378682)
			)
		)
	)
	(zone
		(layer "In12.Cu")
		(hatch none 0.5)
		(connect_pads
			(clearance 0)
		)
		(min_thickness 0.25)
		(keepout
			(tracks not_allowed)
			(vias allowed)
			(pads allowed)
			(copperpour not_allowed)
			(footprints allowed)
		)
		(placement
			(enabled no)
			(sheetname "")
		)
		(fill
			(thermal_gap 0.5)
			(thermal_bridge_width 0.5)
			(island_removal_mode 0)
		)
		(polygon
			(pts
				(xy 226.7204 -136.975342) (xy 227.2792 -136.975342) (xy 227.2792 -138.778742) (xy 226.7204 -138.778742)
			)
		)
	)
	(zone
		(layer "In12.Cu")
		(hatch none 0.5)
		(connect_pads
			(clearance 0)
		)
		(min_thickness 0.25)
		(keepout
			(tracks not_allowed)
			(vias allowed)
			(pads allowed)
			(copperpour not_allowed)
			(footprints allowed)
		)
		(placement
			(enabled no)
			(sheetname "")
		)
		(fill
			(thermal_gap 0.5)
			(thermal_bridge_width 0.5)
			(island_removal_mode 0)
		)
		(polygon
			(pts
				(xy 401.00377 -127.405384) (xy 402.40077 -127.405384) (xy 402.40077 -127.913384) (xy 401.00377 -127.913384)
			)
		)
	)
	(zone
		(layer "In12.Cu")
		(hatch none 0.5)
		(connect_pads
			(clearance 0)
		)
		(min_thickness 0.25)
		(keepout
			(tracks not_allowed)
			(vias allowed)
			(pads allowed)
			(copperpour not_allowed)
			(footprints allowed)
		)
		(placement
			(enabled no)
			(sheetname "")
		)
		(fill
			(thermal_gap 0.5)
			(thermal_bridge_width 0.5)
			(island_removal_mode 0)
		)
		(polygon
			(pts
				(xy 212.270594 -19.322542) (xy 212.829394 -19.322542) (xy 212.829394 -21.125942) (xy 212.270594 -21.125942)
			)
		)
	)
	(zone
		(layer "In12.Cu")
		(hatch none 0.5)
		(connect_pads
			(clearance 0)
		)
		(min_thickness 0.25)
		(keepout
			(tracks not_allowed)
			(vias allowed)
			(pads allowed)
			(copperpour not_allowed)
			(footprints allowed)
		)
		(placement
			(enabled no)
			(sheetname "")
		)
		(fill
			(thermal_gap 0.5)
			(thermal_bridge_width 0.5)
			(island_removal_mode 0)
		)
		(polygon
			(pts
				(xy 130.56997 -146.576542) (xy 131.12877 -146.576542) (xy 131.12877 -148.379942) (xy 130.56997 -148.379942)
			)
		)
	)
	(zone
		(layer "In12.Cu")
		(hatch none 0.5)
		(connect_pads
			(clearance 0)
		)
		(min_thickness 0.25)
		(keepout
			(tracks not_allowed)
			(vias allowed)
			(pads allowed)
			(copperpour not_allowed)
			(footprints allowed)
		)
		(placement
			(enabled no)
			(sheetname "")
		)
		(fill
			(thermal_gap 0.5)
			(thermal_bridge_width 0.5)
			(island_removal_mode 0)
		)
		(polygon
			(pts
				(xy 202.070462 -151.176482) (xy 202.629262 -151.176482) (xy 202.629262 -152.979882) (xy 202.070462 -152.979882)
			)
		)
	)
	(zone
		(layer "In12.Cu")
		(hatch none 0.5)
		(connect_pads
			(clearance 0)
		)
		(min_thickness 0.25)
		(keepout
			(tracks not_allowed)
			(vias allowed)
			(pads allowed)
			(copperpour not_allowed)
			(footprints allowed)
		)
		(placement
			(enabled no)
			(sheetname "")
		)
		(fill
			(thermal_gap 0.5)
			(thermal_bridge_width 0.5)
			(island_removal_mode 0)
		)
		(polygon
			(pts
				(xy 54.920134 -0.120142) (xy 55.478934 -0.120142) (xy 55.478934 -1.923542) (xy 54.920134 -1.923542)
			)
		)
	)
	(zone
		(layer "In12.Cu")
		(hatch none 0.5)
		(connect_pads
			(clearance 0)
		)
		(min_thickness 0.25)
		(keepout
			(tracks not_allowed)
			(vias allowed)
			(pads allowed)
			(copperpour not_allowed)
			(footprints allowed)
		)
		(placement
			(enabled no)
			(sheetname "")
		)
		(fill
			(thermal_gap 0.5)
			(thermal_bridge_width 0.5)
			(island_removal_mode 0)
		)
		(polygon
			(pts
				(xy 134.819898 -14.321282) (xy 135.378698 -14.321282) (xy 135.378698 -16.124682) (xy 134.819898 -16.124682)
			)
		)
	)
	(zone
		(layer "In12.Cu")
		(hatch none 0.5)
		(connect_pads
			(clearance 0)
		)
		(min_thickness 0.25)
		(keepout
			(tracks not_allowed)
			(vias allowed)
			(pads allowed)
			(copperpour not_allowed)
			(footprints allowed)
		)
		(placement
			(enabled no)
			(sheetname "")
		)
		(fill
			(thermal_gap 0.5)
			(thermal_bridge_width 0.5)
			(island_removal_mode 0)
		)
		(polygon
			(pts
				(xy 200.37044 -146.576542) (xy 200.92924 -146.576542) (xy 200.92924 -148.379942) (xy 200.37044 -148.379942)
			)
		)
	)
	(zone
		(layer "In12.Cu")
		(hatch none 0.5)
		(connect_pads
			(clearance 0)
		)
		(min_thickness 0.25)
		(keepout
			(tracks not_allowed)
			(vias allowed)
			(pads allowed)
			(copperpour not_allowed)
			(footprints allowed)
		)
		(placement
			(enabled no)
			(sheetname "")
		)
		(fill
			(thermal_gap 0.5)
			(thermal_bridge_width 0.5)
			(island_removal_mode 0)
		)
		(polygon
			(pts
				(xy 209.720434 -9.721342) (xy 210.279234 -9.721342) (xy 210.279234 -11.524742) (xy 209.720434 -11.524742)
			)
		)
	)
	(zone
		(layer "In12.Cu")
		(hatch none 0.5)
		(connect_pads
			(clearance 0)
		)
		(min_thickness 0.25)
		(keepout
			(tracks not_allowed)
			(vias allowed)
			(pads allowed)
			(copperpour not_allowed)
			(footprints allowed)
		)
		(placement
			(enabled no)
			(sheetname "")
		)
		(fill
			(thermal_gap 0.5)
			(thermal_bridge_width 0.5)
			(island_removal_mode 0)
		)
		(polygon
			(pts
				(xy 137.370058 -151.176482) (xy 137.928858 -151.176482) (xy 137.928858 -152.979882) (xy 137.370058 -152.979882)
			)
		)
	)
	(zone
		(layer "In12.Cu")
		(hatch none 0.5)
		(connect_pads
			(clearance 0)
		)
		(min_thickness 0.25)
		(keepout
			(tracks not_allowed)
			(vias allowed)
			(pads allowed)
			(copperpour not_allowed)
			(footprints allowed)
		)
		(placement
			(enabled no)
			(sheetname "")
		)
		(fill
			(thermal_gap 0.5)
			(thermal_bridge_width 0.5)
			(island_removal_mode 0)
		)
		(polygon
			(pts
				(xy 48.96993 -19.322542) (xy 49.52873 -19.322542) (xy 49.52873 -21.125942) (xy 48.96993 -21.125942)
			)
		)
	)
	(zone
		(layer "In12.Cu")
		(hatch none 0.5)
		(connect_pads
			(clearance 0)
		)
		(min_thickness 0.25)
		(keepout
			(tracks not_allowed)
			(vias allowed)
			(pads allowed)
			(copperpour not_allowed)
			(footprints allowed)
		)
		(placement
			(enabled no)
			(sheetname "")
		)
		(fill
			(thermal_gap 0.5)
			(thermal_bridge_width 0.5)
			(island_removal_mode 0)
		)
		(polygon
			(pts
				(xy 296.42054 -141.575282) (xy 296.97934 -141.575282) (xy 296.97934 -143.378682) (xy 296.42054 -143.378682)
			)
		)
	)
	(zone
		(layer "In12.Cu")
		(hatch none 0.5)
		(connect_pads
			(clearance 0)
		)
		(min_thickness 0.25)
		(keepout
			(tracks not_allowed)
			(vias allowed)
			(pads allowed)
			(copperpour not_allowed)
			(footprints allowed)
		)
		(placement
			(enabled no)
			(sheetname "")
		)
		(fill
			(thermal_gap 0.5)
			(thermal_bridge_width 0.5)
			(island_removal_mode 0)
		)
		(polygon
			(pts
				(xy 291.320474 -0.120142) (xy 291.879274 -0.120142) (xy 291.879274 -1.923542) (xy 291.320474 -1.923542)
			)
		)
	)
	(zone
		(layer "In12.Cu")
		(hatch none 0.5)
		(connect_pads
			(clearance 0)
		)
		(min_thickness 0.25)
		(keepout
			(tracks not_allowed)
			(vias allowed)
			(pads allowed)
			(copperpour not_allowed)
			(footprints allowed)
		)
		(placement
			(enabled no)
			(sheetname "")
		)
		(fill
			(thermal_gap 0.5)
			(thermal_bridge_width 0.5)
			(island_removal_mode 0)
		)
		(polygon
			(pts
				(xy 354.61829 -76.772516) (xy 354.61829 -79.058516) (xy 354.11029 -79.058516) (xy 354.11029 -76.772516)
			)
		)
	)
	(zone
		(layer "In12.Cu")
		(hatch none 0.5)
		(connect_pads
			(clearance 0)
		)
		(min_thickness 0.25)
		(keepout
			(tracks not_allowed)
			(vias allowed)
			(pads allowed)
			(copperpour not_allowed)
			(footprints allowed)
		)
		(placement
			(enabled no)
			(sheetname "")
		)
		(fill
			(thermal_gap 0.5)
			(thermal_bridge_width 0.5)
			(island_removal_mode 0)
		)
		(polygon
			(pts
				(xy 41.319958 -127.374142) (xy 41.878758 -127.374142) (xy 41.878758 -129.177542) (xy 41.319958 -129.177542)
			)
		)
	)
	(zone
		(layer "In12.Cu")
		(hatch none 0.5)
		(connect_pads
			(clearance 0)
		)
		(min_thickness 0.25)
		(keepout
			(tracks not_allowed)
			(vias allowed)
			(pads allowed)
			(copperpour not_allowed)
			(footprints allowed)
		)
		(placement
			(enabled no)
			(sheetname "")
		)
		(fill
			(thermal_gap 0.5)
			(thermal_bridge_width 0.5)
			(island_removal_mode 0)
		)
		(polygon
			(pts
				(xy 111.020098 -151.176482) (xy 111.578898 -151.176482) (xy 111.578898 -152.979882) (xy 111.020098 -152.979882)
			)
		)
	)
	(zone
		(layer "In12.Cu")
		(hatch none 0.5)
		(connect_pads
			(clearance 0)
		)
		(min_thickness 0.25)
		(keepout
			(tracks not_allowed)
			(vias allowed)
			(pads allowed)
			(copperpour not_allowed)
			(footprints allowed)
		)
		(placement
			(enabled no)
			(sheetname "")
		)
		(fill
			(thermal_gap 0.5)
			(thermal_bridge_width 0.5)
			(island_removal_mode 0)
		)
		(polygon
			(pts
				(xy 82.970116 -0.120142) (xy 83.528916 -0.120142) (xy 83.528916 -1.923542) (xy 82.970116 -1.923542)
			)
		)
	)
	(zone
		(layer "In12.Cu")
		(hatch none 0.5)
		(connect_pads
			(clearance 0)
		)
		(min_thickness 0.25)
		(keepout
			(tracks not_allowed)
			(vias allowed)
			(pads allowed)
			(copperpour not_allowed)
			(footprints allowed)
		)
		(placement
			(enabled no)
			(sheetname "")
		)
		(fill
			(thermal_gap 0.5)
			(thermal_bridge_width 0.5)
			(island_removal_mode 0)
		)
		(polygon
			(pts
				(xy 446.658238 -51.264058) (xy 447.166238 -51.264058) (xy 447.166238 -52.661058) (xy 446.658238 -52.661058)
			)
		)
	)
	(zone
		(layer "In12.Cu")
		(hatch none 0.5)
		(connect_pads
			(clearance 0)
		)
		(min_thickness 0.25)
		(keepout
			(tracks not_allowed)
			(vias allowed)
			(pads allowed)
			(copperpour not_allowed)
			(footprints allowed)
		)
		(placement
			(enabled no)
			(sheetname "")
		)
		(fill
			(thermal_gap 0.5)
			(thermal_bridge_width 0.5)
			(island_removal_mode 0)
		)
		(polygon
			(pts
				(xy 293.020496 -146.576542) (xy 293.579296 -146.576542) (xy 293.579296 -148.379942) (xy 293.020496 -148.379942)
			)
		)
	)
	(zone
		(layer "In12.Cu")
		(hatch none 0.5)
		(connect_pads
			(clearance 0)
		)
		(min_thickness 0.25)
		(keepout
			(tracks not_allowed)
			(vias allowed)
			(pads allowed)
			(copperpour not_allowed)
			(footprints allowed)
		)
		(placement
			(enabled no)
			(sheetname "")
		)
		(fill
			(thermal_gap 0.5)
			(thermal_bridge_width 0.5)
			(island_removal_mode 0)
		)
		(polygon
			(pts
				(xy 127.169926 -131.974082) (xy 127.728726 -131.974082) (xy 127.728726 -133.777482) (xy 127.169926 -133.777482)
			)
		)
	)
	(zone
		(layer "In12.Cu")
		(hatch none 0.5)
		(connect_pads
			(clearance 0)
		)
		(min_thickness 0.25)
		(keepout
			(tracks not_allowed)
			(vias allowed)
			(pads allowed)
			(copperpour not_allowed)
			(footprints allowed)
		)
		(placement
			(enabled no)
			(sheetname "")
		)
		(fill
			(thermal_gap 0.5)
			(thermal_bridge_width 0.5)
			(island_removal_mode 0)
		)
		(polygon
			(pts
				(xy 212.270594 -9.721342) (xy 212.829394 -9.721342) (xy 212.829394 -11.524742) (xy 212.270594 -11.524742)
			)
		)
	)
	(zone
		(layer "In12.Cu")
		(hatch none 0.5)
		(connect_pads
			(clearance 0)
		)
		(min_thickness 0.25)
		(keepout
			(tracks not_allowed)
			(vias allowed)
			(pads allowed)
			(copperpour not_allowed)
			(footprints allowed)
		)
		(placement
			(enabled no)
			(sheetname "")
		)
		(fill
			(thermal_gap 0.5)
			(thermal_bridge_width 0.5)
			(island_removal_mode 0)
		)
		(polygon
			(pts
				(xy 65.97015 -9.721342) (xy 66.52895 -9.721342) (xy 66.52895 -11.524742) (xy 65.97015 -11.524742)
			)
		)
	)
	(zone
		(layer "In12.Cu")
		(hatch none 0.5)
		(connect_pads
			(clearance 0)
		)
		(min_thickness 0.25)
		(keepout
			(tracks not_allowed)
			(vias allowed)
			(pads allowed)
			(copperpour not_allowed)
			(footprints allowed)
		)
		(placement
			(enabled no)
			(sheetname "")
		)
		(fill
			(thermal_gap 0.5)
			(thermal_bridge_width 0.5)
			(island_removal_mode 0)
		)
		(polygon
			(pts
				(xy 45.57014 -9.721342) (xy 46.12894 -9.721342) (xy 46.12894 -11.524742) (xy 45.57014 -11.524742)
			)
		)
	)
	(zone
		(net "AGND_PVPP_KLM")
		(layer "In12.Cu")
		(hatch none 0.5)
		(connect_pads
			(clearance 0.5)
		)
		(min_thickness 0.25)
		(fill yes
			(thermal_gap 0.5)
			(thermal_bridge_width 0.5)
			(island_removal_mode 0)
		)
		(polygon
			(pts
				(xy 171.529756 -129.5146) (xy 171.5262 -129.518156) (xy 171.5262 -131.550156) (xy 171.224956 -131.8514)
				(xy 170.793156 -131.8514) (xy 170.688 -131.956556) (xy 170.688 -133.625844) (xy 171.326556 -134.2644)
				(xy 177.694844 -134.2644) (xy 178.308 -133.651244) (xy 178.308 -132.185156) (xy 178.1556 -132.032756)
				(xy 178.1556 -129.797556) (xy 178.101244 -129.7432) (xy 172.672756 -129.7432) (xy 172.462444 -129.7432)
				(xy 172.3136 -129.594356) (xy 172.233844 -129.5146)
			)
		)
	)
	(zone
		(layer "In12.Cu")
		(hatch none 0.5)
		(connect_pads
			(clearance 0)
		)
		(min_thickness 0.25)
		(keepout
			(tracks not_allowed)
			(vias allowed)
			(pads allowed)
			(copperpour not_allowed)
			(footprints allowed)
		)
		(placement
			(enabled no)
			(sheetname "")
		)
		(fill
			(thermal_gap 0.5)
			(thermal_bridge_width 0.5)
			(island_removal_mode 0)
		)
		(polygon
			(pts
				(xy 410.4132 -149.606) (xy 410.4132 -150.368) (xy 411.4038 -150.368) (xy 411.4038 -149.606)
			)
		)
	)
	(zone
		(layer "In12.Cu")
		(hatch none 0.5)
		(connect_pads
			(clearance 0)
		)
		(min_thickness 0.25)
		(keepout
			(tracks not_allowed)
			(vias allowed)
			(pads allowed)
			(copperpour not_allowed)
			(footprints allowed)
		)
		(placement
			(enabled no)
			(sheetname "")
		)
		(fill
			(thermal_gap 0.5)
			(thermal_bridge_width 0.5)
			(island_removal_mode 0)
		)
		(polygon
			(pts
				(xy 17.58442 -105.83672) (xy 18.98142 -105.83672) (xy 18.98142 -106.34472) (xy 17.58442 -106.34472)
			)
		)
	)
	(zone
		(layer "In12.Cu")
		(hatch none 0.5)
		(connect_pads
			(clearance 0)
		)
		(min_thickness 0.25)
		(keepout
			(tracks not_allowed)
			(vias allowed)
			(pads allowed)
			(copperpour not_allowed)
			(footprints allowed)
		)
		(placement
			(enabled no)
			(sheetname "")
		)
		(fill
			(thermal_gap 0.5)
			(thermal_bridge_width 0.5)
			(island_removal_mode 0)
		)
		(polygon
			(pts
				(xy 293.87038 -0.120142) (xy 294.42918 -0.120142) (xy 294.42918 -1.923542) (xy 293.87038 -1.923542)
			)
		)
	)
	(zone
		(layer "In12.Cu")
		(hatch none 0.5)
		(connect_pads
			(clearance 0)
		)
		(min_thickness 0.25)
		(keepout
			(tracks not_allowed)
			(vias allowed)
			(pads allowed)
			(copperpour not_allowed)
			(footprints allowed)
		)
		(placement
			(enabled no)
			(sheetname "")
		)
		(fill
			(thermal_gap 0.5)
			(thermal_bridge_width 0.5)
			(island_removal_mode 0)
		)
		(polygon
			(pts
				(xy 109.320076 -151.176482) (xy 109.878876 -151.176482) (xy 109.878876 -152.979882) (xy 109.320076 -152.979882)
			)
		)
	)
	(zone
		(layer "In12.Cu")
		(hatch none 0.5)
		(connect_pads
			(clearance 0)
		)
		(min_thickness 0.25)
		(keepout
			(tracks not_allowed)
			(vias allowed)
			(pads allowed)
			(copperpour not_allowed)
			(footprints allowed)
		)
		(placement
			(enabled no)
			(sheetname "")
		)
		(fill
			(thermal_gap 0.5)
			(thermal_bridge_width 0.5)
			(island_removal_mode 0)
		)
		(polygon
			(pts
				(xy 196.970396 -0.120142) (xy 197.529196 -0.120142) (xy 197.529196 -1.923542) (xy 196.970396 -1.923542)
			)
		)
	)
	(zone
		(layer "In12.Cu")
		(hatch none 0.5)
		(connect_pads
			(clearance 0)
		)
		(min_thickness 0.25)
		(keepout
			(tracks not_allowed)
			(vias allowed)
			(pads allowed)
			(copperpour not_allowed)
			(footprints allowed)
		)
		(placement
			(enabled no)
			(sheetname "")
		)
		(fill
			(thermal_gap 0.5)
			(thermal_bridge_width 0.5)
			(island_removal_mode 0)
		)
		(polygon
			(pts
				(xy 314.27039 -0.120142) (xy 314.82919 -0.120142) (xy 314.82919 -1.923542) (xy 314.27039 -1.923542)
			)
		)
	)
	(zone
		(layer "In12.Cu")
		(hatch none 0.5)
		(connect_pads
			(clearance 0)
		)
		(min_thickness 0.25)
		(keepout
			(tracks not_allowed)
			(vias allowed)
			(pads allowed)
			(copperpour not_allowed)
			(footprints allowed)
		)
		(placement
			(enabled no)
			(sheetname "")
		)
		(fill
			(thermal_gap 0.5)
			(thermal_bridge_width 0.5)
			(island_removal_mode 0)
		)
		(polygon
			(pts
				(xy 214.8205 -23.922482) (xy 215.3793 -23.922482) (xy 215.3793 -25.725882) (xy 214.8205 -25.725882)
			)
		)
	)
	(zone
		(layer "In12.Cu")
		(hatch none 0.5)
		(connect_pads
			(clearance 0)
		)
		(min_thickness 0.25)
		(keepout
			(tracks not_allowed)
			(vias allowed)
			(pads allowed)
			(copperpour not_allowed)
			(footprints allowed)
		)
		(placement
			(enabled no)
			(sheetname "")
		)
		(fill
			(thermal_gap 0.5)
			(thermal_bridge_width 0.5)
			(island_removal_mode 0)
		)
		(polygon
			(pts
				(xy 220.77045 -141.575282) (xy 221.32925 -141.575282) (xy 221.32925 -143.378682) (xy 220.77045 -143.378682)
			)
		)
	)
	(zone
		(layer "In12.Cu")
		(hatch none 0.5)
		(connect_pads
			(clearance 0)
		)
		(min_thickness 0.25)
		(keepout
			(tracks not_allowed)
			(vias allowed)
			(pads allowed)
			(copperpour not_allowed)
			(footprints allowed)
		)
		(placement
			(enabled no)
			(sheetname "")
		)
		(fill
			(thermal_gap 0.5)
			(thermal_bridge_width 0.5)
			(island_removal_mode 0)
		)
		(polygon
			(pts
				(xy 240.320576 -146.576542) (xy 240.879376 -146.576542) (xy 240.879376 -148.379942) (xy 240.320576 -148.379942)
			)
		)
	)
	(zone
		(layer "In12.Cu")
		(hatch none 0.5)
		(connect_pads
			(clearance 0)
		)
		(min_thickness 0.25)
		(keepout
			(tracks not_allowed)
			(vias allowed)
			(pads allowed)
			(copperpour not_allowed)
			(footprints allowed)
		)
		(placement
			(enabled no)
			(sheetname "")
		)
		(fill
			(thermal_gap 0.5)
			(thermal_bridge_width 0.5)
			(island_removal_mode 0)
		)
		(polygon
			(pts
				(xy 62.570106 -4.720082) (xy 63.128906 -4.720082) (xy 63.128906 -6.523482) (xy 62.570106 -6.523482)
			)
		)
	)
	(zone
		(layer "In12.Cu")
		(hatch none 0.5)
		(connect_pads
			(clearance 0)
		)
		(min_thickness 0.25)
		(keepout
			(tracks not_allowed)
			(vias allowed)
			(pads allowed)
			(copperpour not_allowed)
			(footprints allowed)
		)
		(placement
			(enabled no)
			(sheetname "")
		)
		(fill
			(thermal_gap 0.5)
			(thermal_bridge_width 0.5)
			(island_removal_mode 0)
		)
		(polygon
			(pts
				(xy 284.520386 -0.120142) (xy 285.079186 -0.120142) (xy 285.079186 -1.923542) (xy 284.520386 -1.923542)
			)
		)
	)
	(zone
		(layer "In12.Cu")
		(hatch none 0.5)
		(connect_pads
			(clearance 0)
		)
		(min_thickness 0.25)
		(keepout
			(tracks not_allowed)
			(vias allowed)
			(pads allowed)
			(copperpour not_allowed)
			(footprints allowed)
		)
		(placement
			(enabled no)
			(sheetname "")
		)
		(fill
			(thermal_gap 0.5)
			(thermal_bridge_width 0.5)
			(island_removal_mode 0)
		)
		(polygon
			(pts
				(xy 35.370008 -19.322542) (xy 35.928808 -19.322542) (xy 35.928808 -21.125942) (xy 35.370008 -21.125942)
			)
		)
	)
	(zone
		(layer "In12.Cu")
		(hatch none 0.5)
		(connect_pads
			(clearance 0)
		)
		(min_thickness 0.25)
		(keepout
			(tracks not_allowed)
			(vias allowed)
			(pads allowed)
			(copperpour not_allowed)
			(footprints allowed)
		)
		(placement
			(enabled no)
			(sheetname "")
		)
		(fill
			(thermal_gap 0.5)
			(thermal_bridge_width 0.5)
			(island_removal_mode 0)
		)
		(polygon
			(pts
				(xy 91.469972 -146.576542) (xy 92.028772 -146.576542) (xy 92.028772 -148.379942) (xy 91.469972 -148.379942)
			)
		)
	)
	(zone
		(layer "In12.Cu")
		(hatch none 0.5)
		(connect_pads
			(clearance 0)
		)
		(min_thickness 0.25)
		(keepout
			(tracks not_allowed)
			(vias allowed)
			(pads allowed)
			(copperpour not_allowed)
			(footprints allowed)
		)
		(placement
			(enabled no)
			(sheetname "")
		)
		(fill
			(thermal_gap 0.5)
			(thermal_bridge_width 0.5)
			(island_removal_mode 0)
		)
		(polygon
			(pts
				(xy 79.570072 -151.176482) (xy 80.128872 -151.176482) (xy 80.128872 -152.979882) (xy 79.570072 -152.979882)
			)
		)
	)
	(zone
		(layer "In12.Cu")
		(hatch none 0.5)
		(connect_pads
			(clearance 0)
		)
		(min_thickness 0.25)
		(keepout
			(tracks not_allowed)
			(vias allowed)
			(pads allowed)
			(copperpour not_allowed)
			(footprints allowed)
		)
		(placement
			(enabled no)
			(sheetname "")
		)
		(fill
			(thermal_gap 0.5)
			(thermal_bridge_width 0.5)
			(island_removal_mode 0)
		)
		(polygon
			(pts
				(xy 128.869948 -0.120142) (xy 129.428748 -0.120142) (xy 129.428748 -1.923542) (xy 128.869948 -1.923542)
			)
		)
	)
	(zone
		(layer "In12.Cu")
		(hatch none 0.5)
		(connect_pads
			(clearance 0)
		)
		(min_thickness 0.25)
		(keepout
			(tracks not_allowed)
			(vias allowed)
			(pads allowed)
			(copperpour not_allowed)
			(footprints allowed)
		)
		(placement
			(enabled no)
			(sheetname "")
		)
		(fill
			(thermal_gap 0.5)
			(thermal_bridge_width 0.5)
			(island_removal_mode 0)
		)
		(polygon
			(pts
				(xy 257.320542 -141.575282) (xy 257.879342 -141.575282) (xy 257.879342 -143.378682) (xy 257.320542 -143.378682)
			)
		)
	)
	(zone
		(layer "In12.Cu")
		(hatch none 0.5)
		(connect_pads
			(clearance 0)
		)
		(min_thickness 0.25)
		(keepout
			(tracks not_allowed)
			(vias allowed)
			(pads allowed)
			(copperpour not_allowed)
			(footprints allowed)
		)
		(placement
			(enabled no)
			(sheetname "")
		)
		(fill
			(thermal_gap 0.5)
			(thermal_bridge_width 0.5)
			(island_removal_mode 0)
		)
		(polygon
			(pts
				(xy 77.87005 -14.321282) (xy 78.42885 -14.321282) (xy 78.42885 -16.124682) (xy 77.87005 -16.124682)
			)
		)
	)
	(zone
		(layer "In12.Cu")
		(hatch none 0.5)
		(connect_pads
			(clearance 0)
		)
		(min_thickness 0.25)
		(keepout
			(tracks not_allowed)
			(vias allowed)
			(pads allowed)
			(copperpour not_allowed)
			(footprints allowed)
		)
		(placement
			(enabled no)
			(sheetname "")
		)
		(fill
			(thermal_gap 0.5)
			(thermal_bridge_width 0.5)
			(island_removal_mode 0)
		)
		(polygon
			(pts
				(xy 128.020064 -136.975342) (xy 128.578864 -136.975342) (xy 128.578864 -138.778742) (xy 128.020064 -138.778742)
			)
		)
	)
	(zone
		(layer "In12.Cu")
		(hatch none 0.5)
		(connect_pads
			(clearance 0)
		)
		(min_thickness 0.25)
		(keepout
			(tracks not_allowed)
			(vias allowed)
			(pads allowed)
			(copperpour not_allowed)
			(footprints allowed)
		)
		(placement
			(enabled no)
			(sheetname "")
		)
		(fill
			(thermal_gap 0.5)
			(thermal_bridge_width 0.5)
			(island_removal_mode 0)
		)
		(polygon
			(pts
				(xy 410.4132 -151.892) (xy 410.4132 -152.654) (xy 411.4038 -152.654) (xy 411.4038 -151.892)
			)
		)
	)
	(zone
		(layer "In12.Cu")
		(hatch none 0.5)
		(connect_pads
			(clearance 0)
		)
		(min_thickness 0.25)
		(keepout
			(tracks not_allowed)
			(vias allowed)
			(pads allowed)
			(copperpour not_allowed)
			(footprints allowed)
		)
		(placement
			(enabled no)
			(sheetname "")
		)
		(fill
			(thermal_gap 0.5)
			(thermal_bridge_width 0.5)
			(island_removal_mode 0)
		)
		(polygon
			(pts
				(xy 150.120096 -141.575282) (xy 150.678896 -141.575282) (xy 150.678896 -143.378682) (xy 150.120096 -143.378682)
			)
		)
	)
	(zone
		(layer "In12.Cu")
		(hatch none 0.5)
		(connect_pads
			(clearance 0)
		)
		(min_thickness 0.25)
		(keepout
			(tracks not_allowed)
			(vias allowed)
			(pads allowed)
			(copperpour not_allowed)
			(footprints allowed)
		)
		(placement
			(enabled no)
			(sheetname "")
		)
		(fill
			(thermal_gap 0.5)
			(thermal_bridge_width 0.5)
			(island_removal_mode 0)
		)
		(polygon
			(pts
				(xy 101.670104 -136.975342) (xy 102.228904 -136.975342) (xy 102.228904 -138.778742) (xy 101.670104 -138.778742)
			)
		)
	)
	(zone
		(layer "In12.Cu")
		(hatch none 0.5)
		(connect_pads
			(clearance 0)
		)
		(min_thickness 0.25)
		(keepout
			(tracks not_allowed)
			(vias allowed)
			(pads allowed)
			(copperpour not_allowed)
			(footprints allowed)
		)
		(placement
			(enabled no)
			(sheetname "")
		)
		(fill
			(thermal_gap 0.5)
			(thermal_bridge_width 0.5)
			(island_removal_mode 0)
		)
		(polygon
			(pts
				(xy 236.070394 -9.721342) (xy 236.629194 -9.721342) (xy 236.629194 -11.524742) (xy 236.070394 -11.524742)
			)
		)
	)
	(zone
		(layer "In12.Cu")
		(hatch none 0.5)
		(connect_pads
			(clearance 0)
		)
		(min_thickness 0.25)
		(keepout
			(tracks not_allowed)
			(vias allowed)
			(pads allowed)
			(copperpour not_allowed)
			(footprints allowed)
		)
		(placement
			(enabled no)
			(sheetname "")
		)
		(fill
			(thermal_gap 0.5)
			(thermal_bridge_width 0.5)
			(island_removal_mode 0)
		)
		(polygon
			(pts
				(xy 31.969964 -19.322542) (xy 32.528764 -19.322542) (xy 32.528764 -21.125942) (xy 31.969964 -21.125942)
			)
		)
	)
	(zone
		(layer "In12.Cu")
		(hatch none 0.5)
		(connect_pads
			(clearance 0)
		)
		(min_thickness 0.25)
		(keepout
			(tracks not_allowed)
			(vias allowed)
			(pads allowed)
			(copperpour not_allowed)
			(footprints allowed)
		)
		(placement
			(enabled no)
			(sheetname "")
		)
		(fill
			(thermal_gap 0.5)
			(thermal_bridge_width 0.5)
			(island_removal_mode 0)
		)
		(polygon
			(pts
				(xy 237.770416 -151.176482) (xy 238.329216 -151.176482) (xy 238.329216 -152.979882) (xy 237.770416 -152.979882)
			)
		)
	)
	(zone
		(layer "In12.Cu")
		(hatch none 0.5)
		(connect_pads
			(clearance 0)
		)
		(min_thickness 0.25)
		(keepout
			(tracks not_allowed)
			(vias allowed)
			(pads allowed)
			(copperpour not_allowed)
			(footprints allowed)
		)
		(placement
			(enabled no)
			(sheetname "")
		)
		(fill
			(thermal_gap 0.5)
			(thermal_bridge_width 0.5)
			(island_removal_mode 0)
		)
		(polygon
			(pts
				(xy 250.520454 -9.721342) (xy 251.079254 -9.721342) (xy 251.079254 -11.524742) (xy 250.520454 -11.524742)
			)
		)
	)
	(zone
		(layer "In12.Cu")
		(hatch none 0.5)
		(connect_pads
			(clearance 0)
		)
		(min_thickness 0.25)
		(keepout
			(tracks not_allowed)
			(vias allowed)
			(pads allowed)
			(copperpour not_allowed)
			(footprints allowed)
		)
		(placement
			(enabled no)
			(sheetname "")
		)
		(fill
			(thermal_gap 0.5)
			(thermal_bridge_width 0.5)
			(island_removal_mode 0)
		)
		(polygon
			(pts
				(xy 270.07058 -14.321282) (xy 270.62938 -14.321282) (xy 270.62938 -16.124682) (xy 270.07058 -16.124682)
			)
		)
	)
	(zone
		(layer "In12.Cu")
		(hatch none 0.5)
		(connect_pads
			(clearance 0)
		)
		(min_thickness 0.25)
		(keepout
			(tracks not_allowed)
			(vias allowed)
			(pads allowed)
			(copperpour not_allowed)
			(footprints allowed)
		)
		(placement
			(enabled no)
			(sheetname "")
		)
		(fill
			(thermal_gap 0.5)
			(thermal_bridge_width 0.5)
			(island_removal_mode 0)
		)
		(polygon
			(pts
				(xy 231.820466 -14.321282) (xy 232.379266 -14.321282) (xy 232.379266 -16.124682) (xy 231.820466 -16.124682)
			)
		)
	)
	(zone
		(layer "In12.Cu")
		(hatch none 0.5)
		(connect_pads
			(clearance 0)
		)
		(min_thickness 0.25)
		(keepout
			(tracks not_allowed)
			(vias allowed)
			(pads allowed)
			(copperpour not_allowed)
			(footprints allowed)
		)
		(placement
			(enabled no)
			(sheetname "")
		)
		(fill
			(thermal_gap 0.5)
			(thermal_bridge_width 0.5)
			(island_removal_mode 0)
		)
		(polygon
			(pts
				(xy 221.620588 -19.322542) (xy 222.179388 -19.322542) (xy 222.179388 -21.125942) (xy 221.620588 -21.125942)
			)
		)
	)
	(zone
		(layer "In12.Cu")
		(hatch none 0.5)
		(connect_pads
			(clearance 0)
		)
		(min_thickness 0.25)
		(keepout
			(tracks not_allowed)
			(vias allowed)
			(pads allowed)
			(copperpour not_allowed)
			(footprints allowed)
		)
		(placement
			(enabled no)
			(sheetname "")
		)
		(fill
			(thermal_gap 0.5)
			(thermal_bridge_width 0.5)
			(island_removal_mode 0)
		)
		(polygon
			(pts
				(xy 253.070614 -19.322542) (xy 253.629414 -19.322542) (xy 253.629414 -21.125942) (xy 253.070614 -21.125942)
			)
		)
	)
	(zone
		(layer "In12.Cu")
		(hatch none 0.5)
		(connect_pads
			(clearance 0)
		)
		(min_thickness 0.25)
		(keepout
			(tracks not_allowed)
			(vias allowed)
			(pads allowed)
			(copperpour not_allowed)
			(footprints allowed)
		)
		(placement
			(enabled no)
			(sheetname "")
		)
		(fill
			(thermal_gap 0.5)
			(thermal_bridge_width 0.5)
			(island_removal_mode 0)
		)
		(polygon
			(pts
				(xy 346.173806 -59.225434) (xy 346.173806 -61.511434) (xy 345.665806 -61.511434) (xy 345.665806 -59.225434)
			)
		)
	)
	(zone
		(layer "In12.Cu")
		(hatch none 0.5)
		(connect_pads
			(clearance 0)
		)
		(min_thickness 0.25)
		(keepout
			(tracks not_allowed)
			(vias allowed)
			(pads allowed)
			(copperpour not_allowed)
			(footprints allowed)
		)
		(placement
			(enabled no)
			(sheetname "")
		)
		(fill
			(thermal_gap 0.5)
			(thermal_bridge_width 0.5)
			(island_removal_mode 0)
		)
		(polygon
			(pts
				(xy 142.46987 -14.321282) (xy 143.02867 -14.321282) (xy 143.02867 -16.124682) (xy 142.46987 -16.124682)
			)
		)
	)
	(zone
		(layer "In12.Cu")
		(hatch none 0.5)
		(connect_pads
			(clearance 0)
		)
		(min_thickness 0.25)
		(keepout
			(tracks not_allowed)
			(vias allowed)
			(pads allowed)
			(copperpour not_allowed)
			(footprints allowed)
		)
		(placement
			(enabled no)
			(sheetname "")
		)
		(fill
			(thermal_gap 0.5)
			(thermal_bridge_width 0.5)
			(island_removal_mode 0)
		)
		(polygon
			(pts
				(xy 132.269992 -136.975342) (xy 132.828792 -136.975342) (xy 132.828792 -138.778742) (xy 132.269992 -138.778742)
			)
		)
	)
	(zone
		(layer "In12.Cu")
		(hatch none 0.5)
		(connect_pads
			(clearance 0)
		)
		(min_thickness 0.25)
		(keepout
			(tracks not_allowed)
			(vias allowed)
			(pads allowed)
			(copperpour not_allowed)
			(footprints allowed)
		)
		(placement
			(enabled no)
			(sheetname "")
		)
		(fill
			(thermal_gap 0.5)
			(thermal_bridge_width 0.5)
			(island_removal_mode 0)
		)
		(polygon
			(pts
				(xy 353.22129 -76.772516) (xy 353.22129 -79.058516) (xy 352.71329 -79.058516) (xy 352.71329 -76.772516)
			)
		)
	)
	(zone
		(layer "In12.Cu")
		(hatch none 0.5)
		(connect_pads
			(clearance 0)
		)
		(min_thickness 0.25)
		(keepout
			(tracks not_allowed)
			(vias allowed)
			(pads allowed)
			(copperpour not_allowed)
			(footprints allowed)
		)
		(placement
			(enabled no)
			(sheetname "")
		)
		(fill
			(thermal_gap 0.5)
			(thermal_bridge_width 0.5)
			(island_removal_mode 0)
		)
		(polygon
			(pts
				(xy 89.76995 -4.720082) (xy 90.32875 -4.720082) (xy 90.32875 -6.523482) (xy 89.76995 -6.523482)
			)
		)
	)
	(zone
		(layer "In12.Cu")
		(hatch none 0.5)
		(connect_pads
			(clearance 0)
		)
		(min_thickness 0.25)
		(keepout
			(tracks not_allowed)
			(vias allowed)
			(pads allowed)
			(copperpour not_allowed)
			(footprints allowed)
		)
		(placement
			(enabled no)
			(sheetname "")
		)
		(fill
			(thermal_gap 0.5)
			(thermal_bridge_width 0.5)
			(island_removal_mode 0)
		)
		(polygon
			(pts
				(xy 287.92043 -0.120142) (xy 288.47923 -0.120142) (xy 288.47923 -1.923542) (xy 287.92043 -1.923542)
			)
		)
	)
	(zone
		(layer "In12.Cu")
		(hatch none 0.5)
		(connect_pads
			(clearance 0)
		)
		(min_thickness 0.25)
		(keepout
			(tracks not_allowed)
			(vias allowed)
			(pads allowed)
			(copperpour not_allowed)
			(footprints allowed)
		)
		(placement
			(enabled no)
			(sheetname "")
		)
		(fill
			(thermal_gap 0.5)
			(thermal_bridge_width 0.5)
			(island_removal_mode 0)
		)
		(polygon
			(pts
				(xy 128.020064 -19.322542) (xy 128.578864 -19.322542) (xy 128.578864 -21.125942) (xy 128.020064 -21.125942)
			)
		)
	)
	(zone
		(layer "In12.Cu")
		(hatch none 0.5)
		(connect_pads
			(clearance 0)
		)
		(min_thickness 0.25)
		(keepout
			(tracks not_allowed)
			(vias allowed)
			(pads allowed)
			(copperpour not_allowed)
			(footprints allowed)
		)
		(placement
			(enabled no)
			(sheetname "")
		)
		(fill
			(thermal_gap 0.5)
			(thermal_bridge_width 0.5)
			(island_removal_mode 0)
		)
		(polygon
			(pts
				(xy 50.669952 -9.721342) (xy 51.228752 -9.721342) (xy 51.228752 -11.524742) (xy 50.669952 -11.524742)
			)
		)
	)
	(zone
		(layer "In12.Cu")
		(hatch none 0.5)
		(connect_pads
			(clearance 0)
		)
		(min_thickness 0.25)
		(keepout
			(tracks not_allowed)
			(vias allowed)
			(pads allowed)
			(copperpour not_allowed)
			(footprints allowed)
		)
		(placement
			(enabled no)
			(sheetname "")
		)
		(fill
			(thermal_gap 0.5)
			(thermal_bridge_width 0.5)
			(island_removal_mode 0)
		)
		(polygon
			(pts
				(xy 207.170528 -131.974082) (xy 207.729328 -131.974082) (xy 207.729328 -133.777482) (xy 207.170528 -133.777482)
			)
		)
	)
	(zone
		(layer "In12.Cu")
		(hatch none 0.5)
		(connect_pads
			(clearance 0)
		)
		(min_thickness 0.25)
		(keepout
			(tracks not_allowed)
			(vias allowed)
			(pads allowed)
			(copperpour not_allowed)
			(footprints allowed)
		)
		(placement
			(enabled no)
			(sheetname "")
		)
		(fill
			(thermal_gap 0.5)
			(thermal_bridge_width 0.5)
			(island_removal_mode 0)
		)
		(polygon
			(pts
				(xy 221.620588 -0.120142) (xy 222.179388 -0.120142) (xy 222.179388 -1.923542) (xy 221.620588 -1.923542)
			)
		)
	)
	(zone
		(layer "In12.Cu")
		(hatch none 0.5)
		(connect_pads
			(clearance 0)
		)
		(min_thickness 0.25)
		(keepout
			(tracks not_allowed)
			(vias allowed)
			(pads allowed)
			(copperpour not_allowed)
			(footprints allowed)
		)
		(placement
			(enabled no)
			(sheetname "")
		)
		(fill
			(thermal_gap 0.5)
			(thermal_bridge_width 0.5)
			(island_removal_mode 0)
		)
		(polygon
			(pts
				(xy 304.070512 -23.922482) (xy 304.629312 -23.922482) (xy 304.629312 -25.725882) (xy 304.070512 -25.725882)
			)
		)
	)
	(zone
		(layer "In12.Cu")
		(hatch none 0.5)
		(connect_pads
			(clearance 0)
		)
		(min_thickness 0.25)
		(keepout
			(tracks not_allowed)
			(vias allowed)
			(pads allowed)
			(copperpour not_allowed)
			(footprints allowed)
		)
		(placement
			(enabled no)
			(sheetname "")
		)
		(fill
			(thermal_gap 0.5)
			(thermal_bridge_width 0.5)
			(island_removal_mode 0)
		)
		(polygon
			(pts
				(xy 348.967806 -59.225434) (xy 348.967806 -61.511434) (xy 348.459806 -61.511434) (xy 348.459806 -59.225434)
			)
		)
	)
	(zone
		(layer "In12.Cu")
		(hatch none 0.5)
		(connect_pads
			(clearance 0)
		)
		(min_thickness 0.25)
		(keepout
			(tracks not_allowed)
			(vias allowed)
			(pads allowed)
			(copperpour not_allowed)
			(footprints allowed)
		)
		(placement
			(enabled no)
			(sheetname "")
		)
		(fill
			(thermal_gap 0.5)
			(thermal_bridge_width 0.5)
			(island_removal_mode 0)
		)
		(polygon
			(pts
				(xy 215.670384 -127.374142) (xy 216.229184 -127.374142) (xy 216.229184 -129.177542) (xy 215.670384 -129.177542)
			)
		)
	)
	(zone
		(layer "In12.Cu")
		(hatch none 0.5)
		(connect_pads
			(clearance 0)
		)
		(min_thickness 0.25)
		(keepout
			(tracks not_allowed)
			(vias allowed)
			(pads allowed)
			(copperpour not_allowed)
			(footprints allowed)
		)
		(placement
			(enabled no)
			(sheetname "")
		)
		(fill
			(thermal_gap 0.5)
			(thermal_bridge_width 0.5)
			(island_removal_mode 0)
		)
		(polygon
			(pts
				(xy 214.8205 -151.176482) (xy 215.3793 -151.176482) (xy 215.3793 -152.979882) (xy 214.8205 -152.979882)
			)
		)
	)
	(zone
		(layer "In12.Cu")
		(hatch none 0.5)
		(connect_pads
			(clearance 0)
		)
		(min_thickness 0.25)
		(keepout
			(tracks not_allowed)
			(vias allowed)
			(pads allowed)
			(copperpour not_allowed)
			(footprints allowed)
		)
		(placement
			(enabled no)
			(sheetname "")
		)
		(fill
			(thermal_gap 0.5)
			(thermal_bridge_width 0.5)
			(island_removal_mode 0)
		)
		(polygon
			(pts
				(xy 133.970014 -0.120142) (xy 134.528814 -0.120142) (xy 134.528814 -1.923542) (xy 133.970014 -1.923542)
			)
		)
	)
	(zone
		(layer "In12.Cu")
		(hatch none 0.5)
		(connect_pads
			(clearance 0)
		)
		(min_thickness 0.25)
		(keepout
			(tracks not_allowed)
			(vias allowed)
			(pads allowed)
			(copperpour not_allowed)
			(footprints allowed)
		)
		(placement
			(enabled no)
			(sheetname "")
		)
		(fill
			(thermal_gap 0.5)
			(thermal_bridge_width 0.5)
			(island_removal_mode 0)
		)
		(polygon
			(pts
				(xy 212.270594 -136.975342) (xy 212.829394 -136.975342) (xy 212.829394 -138.778742) (xy 212.270594 -138.778742)
			)
		)
	)
	(zone
		(layer "In12.Cu")
		(hatch none 0.5)
		(connect_pads
			(clearance 0)
		)
		(min_thickness 0.25)
		(keepout
			(tracks not_allowed)
			(vias allowed)
			(pads allowed)
			(copperpour not_allowed)
			(footprints allowed)
		)
		(placement
			(enabled no)
			(sheetname "")
		)
		(fill
			(thermal_gap 0.5)
			(thermal_bridge_width 0.5)
			(island_removal_mode 0)
		)
		(polygon
			(pts
				(xy 208.87055 -4.720082) (xy 209.42935 -4.720082) (xy 209.42935 -6.523482) (xy 208.87055 -6.523482)
			)
		)
	)
	(zone
		(layer "In12.Cu")
		(hatch none 0.5)
		(connect_pads
			(clearance 0)
		)
		(min_thickness 0.25)
		(keepout
			(tracks not_allowed)
			(vias allowed)
			(pads allowed)
			(copperpour not_allowed)
			(footprints allowed)
		)
		(placement
			(enabled no)
			(sheetname "")
		)
		(fill
			(thermal_gap 0.5)
			(thermal_bridge_width 0.5)
			(island_removal_mode 0)
		)
		(polygon
			(pts
				(xy 102.519988 -141.575282) (xy 103.078788 -141.575282) (xy 103.078788 -143.378682) (xy 102.519988 -143.378682)
			)
		)
	)
	(zone
		(layer "In12.Cu")
		(hatch none 0.5)
		(connect_pads
			(clearance 0)
		)
		(min_thickness 0.25)
		(keepout
			(tracks not_allowed)
			(vias allowed)
			(pads allowed)
			(copperpour not_allowed)
			(footprints allowed)
		)
		(placement
			(enabled no)
			(sheetname "")
		)
		(fill
			(thermal_gap 0.5)
			(thermal_bridge_width 0.5)
			(island_removal_mode 0)
		)
		(polygon
			(pts
				(xy 64.270128 -127.374142) (xy 64.828928 -127.374142) (xy 64.828928 -129.177542) (xy 64.270128 -129.177542)
			)
		)
	)
	(zone
		(layer "In12.Cu")
		(hatch none 0.5)
		(connect_pads
			(clearance 0)
		)
		(min_thickness 0.25)
		(keepout
			(tracks not_allowed)
			(vias allowed)
			(pads allowed)
			(copperpour not_allowed)
			(footprints allowed)
		)
		(placement
			(enabled no)
			(sheetname "")
		)
		(fill
			(thermal_gap 0.5)
			(thermal_bridge_width 0.5)
			(island_removal_mode 0)
		)
		(polygon
			(pts
				(xy 213.970362 -146.576542) (xy 214.529162 -146.576542) (xy 214.529162 -148.379942) (xy 213.970362 -148.379942)
			)
		)
	)
	(zone
		(layer "In12.Cu")
		(hatch none 0.5)
		(connect_pads
			(clearance 0)
		)
		(min_thickness 0.25)
		(keepout
			(tracks not_allowed)
			(vias allowed)
			(pads allowed)
			(copperpour not_allowed)
			(footprints allowed)
		)
		(placement
			(enabled no)
			(sheetname "")
		)
		(fill
			(thermal_gap 0.5)
			(thermal_bridge_width 0.5)
			(island_removal_mode 0)
		)
		(polygon
			(pts
				(xy 139.07008 -141.575282) (xy 139.62888 -141.575282) (xy 139.62888 -143.378682) (xy 139.07008 -143.378682)
			)
		)
	)
	(zone
		(layer "In12.Cu")
		(hatch none 0.5)
		(connect_pads
			(clearance 0)
		)
		(min_thickness 0.25)
		(keepout
			(tracks not_allowed)
			(vias allowed)
			(pads allowed)
			(copperpour not_allowed)
			(footprints allowed)
		)
		(placement
			(enabled no)
			(sheetname "")
		)
		(fill
			(thermal_gap 0.5)
			(thermal_bridge_width 0.5)
			(island_removal_mode 0)
		)
		(polygon
			(pts
				(xy 30.269942 -146.576542) (xy 30.828742 -146.576542) (xy 30.828742 -148.379942) (xy 30.269942 -148.379942)
			)
		)
	)
	(zone
		(layer "In12.Cu")
		(hatch none 0.5)
		(connect_pads
			(clearance 0)
		)
		(min_thickness 0.25)
		(keepout
			(tracks not_allowed)
			(vias allowed)
			(pads allowed)
			(copperpour not_allowed)
			(footprints allowed)
		)
		(placement
			(enabled no)
			(sheetname "")
		)
		(fill
			(thermal_gap 0.5)
			(thermal_bridge_width 0.5)
			(island_removal_mode 0)
		)
		(polygon
			(pts
				(xy 305.770534 -151.176482) (xy 306.329334 -151.176482) (xy 306.329334 -152.979882) (xy 305.770534 -152.979882)
			)
		)
	)
	(zone
		(layer "In12.Cu")
		(hatch none 0.5)
		(connect_pads
			(clearance 0)
		)
		(min_thickness 0.25)
		(keepout
			(tracks not_allowed)
			(vias allowed)
			(pads allowed)
			(copperpour not_allowed)
			(footprints allowed)
		)
		(placement
			(enabled no)
			(sheetname "")
		)
		(fill
			(thermal_gap 0.5)
			(thermal_bridge_width 0.5)
			(island_removal_mode 0)
		)
		(polygon
			(pts
				(xy 298.120308 -131.974082) (xy 298.679108 -131.974082) (xy 298.679108 -133.777482) (xy 298.120308 -133.777482)
			)
		)
	)
	(zone
		(layer "In12.Cu")
		(hatch none 0.5)
		(connect_pads
			(clearance 0)
		)
		(min_thickness 0.25)
		(keepout
			(tracks not_allowed)
			(vias allowed)
			(pads allowed)
			(copperpour not_allowed)
			(footprints allowed)
		)
		(placement
			(enabled no)
			(sheetname "")
		)
		(fill
			(thermal_gap 0.5)
			(thermal_bridge_width 0.5)
			(island_removal_mode 0)
		)
		(polygon
			(pts
				(xy 116.970048 -146.576542) (xy 117.528848 -146.576542) (xy 117.528848 -148.379942) (xy 116.970048 -148.379942)
			)
		)
	)
	(zone
		(net "PVDDQ_ABC")
		(layer "In12.Cu")
		(hatch none 0.5)
		(connect_pads
			(clearance 0.5)
		)
		(min_thickness 0.25)
		(fill yes
			(thermal_gap 0.5)
			(thermal_bridge_width 0.5)
			(island_removal_mode 0)
		)
		(polygon
			(pts
				(xy 265.356594 -21.1201) (xy 265.0617 -21.414994) (xy 265.0617 -22.654006) (xy 265.6713 -23.263606)
				(xy 265.6713 -23.695406) (xy 265.889994 -23.9141) (xy 278.127206 -23.9141) (xy 278.3713 -23.670006)
				(xy 278.3713 -21.389594) (xy 278.101806 -21.1201)
			)
		)
	)
	(zone
		(layer "In12.Cu")
		(hatch none 0.5)
		(connect_pads
			(clearance 0)
		)
		(min_thickness 0.25)
		(keepout
			(tracks not_allowed)
			(vias allowed)
			(pads allowed)
			(copperpour not_allowed)
			(footprints allowed)
		)
		(placement
			(enabled no)
			(sheetname "")
		)
		(fill
			(thermal_gap 0.5)
			(thermal_bridge_width 0.5)
			(island_removal_mode 0)
		)
		(polygon
			(pts
				(xy 106.77017 -14.321282) (xy 107.32897 -14.321282) (xy 107.32897 -16.124682) (xy 106.77017 -16.124682)
			)
		)
	)
	(zone
		(layer "In12.Cu")
		(hatch none 0.5)
		(connect_pads
			(clearance 0)
		)
		(min_thickness 0.25)
		(keepout
			(tracks not_allowed)
			(vias allowed)
			(pads allowed)
			(copperpour not_allowed)
			(footprints allowed)
		)
		(placement
			(enabled no)
			(sheetname "")
		)
		(fill
			(thermal_gap 0.5)
			(thermal_bridge_width 0.5)
			(island_removal_mode 0)
		)
		(polygon
			(pts
				(xy 51.52009 -141.575282) (xy 52.07889 -141.575282) (xy 52.07889 -143.378682) (xy 51.52009 -143.378682)
			)
		)
	)
	(zone
		(layer "In12.Cu")
		(hatch none 0.5)
		(connect_pads
			(clearance 0)
		)
		(min_thickness 0.25)
		(keepout
			(tracks not_allowed)
			(vias allowed)
			(pads allowed)
			(copperpour not_allowed)
			(footprints allowed)
		)
		(placement
			(enabled no)
			(sheetname "")
		)
		(fill
			(thermal_gap 0.5)
			(thermal_bridge_width 0.5)
			(island_removal_mode 0)
		)
		(polygon
			(pts
				(xy 110.16996 -127.374142) (xy 110.72876 -127.374142) (xy 110.72876 -129.177542) (xy 110.16996 -129.177542)
			)
		)
	)
	(zone
		(layer "In12.Cu")
		(hatch none 0.5)
		(connect_pads
			(clearance 0)
		)
		(min_thickness 0.25)
		(keepout
			(tracks not_allowed)
			(vias allowed)
			(pads allowed)
			(copperpour not_allowed)
			(footprints allowed)
		)
		(placement
			(enabled no)
			(sheetname "")
		)
		(fill
			(thermal_gap 0.5)
			(thermal_bridge_width 0.5)
			(island_removal_mode 0)
		)
		(polygon
			(pts
				(xy 43.870118 -14.321282) (xy 44.428918 -14.321282) (xy 44.428918 -16.124682) (xy 43.870118 -16.124682)
			)
		)
	)
	(zone
		(layer "In12.Cu")
		(hatch none 0.5)
		(connect_pads
			(clearance 0)
		)
		(min_thickness 0.25)
		(keepout
			(tracks not_allowed)
			(vias allowed)
			(pads allowed)
			(copperpour not_allowed)
			(footprints allowed)
		)
		(placement
			(enabled no)
			(sheetname "")
		)
		(fill
			(thermal_gap 0.5)
			(thermal_bridge_width 0.5)
			(island_removal_mode 0)
		)
		(polygon
			(pts
				(xy 109.320076 -141.575282) (xy 109.878876 -141.575282) (xy 109.878876 -143.378682) (xy 109.320076 -143.378682)
			)
		)
	)
	(zone
		(layer "In12.Cu")
		(hatch none 0.5)
		(connect_pads
			(clearance 0)
		)
		(min_thickness 0.25)
		(keepout
			(tracks not_allowed)
			(vias allowed)
			(pads allowed)
			(copperpour not_allowed)
			(footprints allowed)
		)
		(placement
			(enabled no)
			(sheetname "")
		)
		(fill
			(thermal_gap 0.5)
			(thermal_bridge_width 0.5)
			(island_removal_mode 0)
		)
		(polygon
			(pts
				(xy 295.570402 -9.721342) (xy 296.129202 -9.721342) (xy 296.129202 -11.524742) (xy 295.570402 -11.524742)
			)
		)
	)
	(zone
		(layer "In12.Cu")
		(hatch none 0.5)
		(connect_pads
			(clearance 0)
		)
		(min_thickness 0.25)
		(keepout
			(tracks not_allowed)
			(vias allowed)
			(pads allowed)
			(copperpour not_allowed)
			(footprints allowed)
		)
		(placement
			(enabled no)
			(sheetname "")
		)
		(fill
			(thermal_gap 0.5)
			(thermal_bridge_width 0.5)
			(island_removal_mode 0)
		)
		(polygon
			(pts
				(xy 420.5732 -147.447) (xy 420.5732 -148.209) (xy 421.5638 -148.209) (xy 421.5638 -147.447)
			)
		)
	)
	(zone
		(layer "In12.Cu")
		(hatch none 0.5)
		(connect_pads
			(clearance 0)
		)
		(min_thickness 0.25)
		(keepout
			(tracks not_allowed)
			(vias allowed)
			(pads allowed)
			(copperpour not_allowed)
			(footprints allowed)
		)
		(placement
			(enabled no)
			(sheetname "")
		)
		(fill
			(thermal_gap 0.5)
			(thermal_bridge_width 0.5)
			(island_removal_mode 0)
		)
		(polygon
			(pts
				(xy 63.41999 -9.721342) (xy 63.97879 -9.721342) (xy 63.97879 -11.524742) (xy 63.41999 -11.524742)
			)
		)
	)
	(zone
		(layer "In12.Cu")
		(hatch none 0.5)
		(connect_pads
			(clearance 0)
		)
		(min_thickness 0.25)
		(keepout
			(tracks not_allowed)
			(vias allowed)
			(pads allowed)
			(copperpour not_allowed)
			(footprints allowed)
		)
		(placement
			(enabled no)
			(sheetname "")
		)
		(fill
			(thermal_gap 0.5)
			(thermal_bridge_width 0.5)
			(island_removal_mode 0)
		)
		(polygon
			(pts
				(xy 150.120096 -131.974082) (xy 150.678896 -131.974082) (xy 150.678896 -133.777482) (xy 150.120096 -133.777482)
			)
		)
	)
	(zone
		(layer "In12.Cu")
		(hatch none 0.5)
		(connect_pads
			(clearance 0)
		)
		(min_thickness 0.25)
		(keepout
			(tracks not_allowed)
			(vias allowed)
			(pads allowed)
			(copperpour not_allowed)
			(footprints allowed)
		)
		(placement
			(enabled no)
			(sheetname "")
		)
		(fill
			(thermal_gap 0.5)
			(thermal_bridge_width 0.5)
			(island_removal_mode 0)
		)
		(polygon
			(pts
				(xy 122.070114 -14.321282) (xy 122.628914 -14.321282) (xy 122.628914 -16.124682) (xy 122.070114 -16.124682)
			)
		)
	)
	(zone
		(layer "In12.Cu")
		(hatch none 0.5)
		(connect_pads
			(clearance 0)
		)
		(min_thickness 0.25)
		(keepout
			(tracks not_allowed)
			(vias allowed)
			(pads allowed)
			(copperpour not_allowed)
			(footprints allowed)
		)
		(placement
			(enabled no)
			(sheetname "")
		)
		(fill
			(thermal_gap 0.5)
			(thermal_bridge_width 0.5)
			(island_removal_mode 0)
		)
		(polygon
			(pts
				(xy 211.420456 -23.922482) (xy 211.979256 -23.922482) (xy 211.979256 -25.725882) (xy 211.420456 -25.725882)
			)
		)
	)
	(zone
		(layer "In12.Cu")
		(hatch none 0.5)
		(connect_pads
			(clearance 0)
		)
		(min_thickness 0.25)
		(keepout
			(tracks not_allowed)
			(vias allowed)
			(pads allowed)
			(copperpour not_allowed)
			(footprints allowed)
		)
		(placement
			(enabled no)
			(sheetname "")
		)
		(fill
			(thermal_gap 0.5)
			(thermal_bridge_width 0.5)
			(island_removal_mode 0)
		)
		(polygon
			(pts
				(xy 87.220044 -146.576542) (xy 87.778844 -146.576542) (xy 87.778844 -148.379942) (xy 87.220044 -148.379942)
			)
		)
	)
	(zone
		(layer "In12.Cu")
		(hatch none 0.5)
		(connect_pads
			(clearance 0)
		)
		(min_thickness 0.25)
		(keepout
			(tracks not_allowed)
			(vias allowed)
			(pads allowed)
			(copperpour not_allowed)
			(footprints allowed)
		)
		(placement
			(enabled no)
			(sheetname "")
		)
		(fill
			(thermal_gap 0.5)
			(thermal_bridge_width 0.5)
			(island_removal_mode 0)
		)
		(polygon
			(pts
				(xy 65.97015 -146.576542) (xy 66.52895 -146.576542) (xy 66.52895 -148.379942) (xy 65.97015 -148.379942)
			)
		)
	)
	(zone
		(layer "In12.Cu")
		(hatch none 0.5)
		(connect_pads
			(clearance 0)
		)
		(min_thickness 0.25)
		(keepout
			(tracks not_allowed)
			(vias allowed)
			(pads allowed)
			(copperpour not_allowed)
			(footprints allowed)
		)
		(placement
			(enabled no)
			(sheetname "")
		)
		(fill
			(thermal_gap 0.5)
			(thermal_bridge_width 0.5)
			(island_removal_mode 0)
		)
		(polygon
			(pts
				(xy 139.07008 -14.321282) (xy 139.62888 -14.321282) (xy 139.62888 -16.124682) (xy 139.07008 -16.124682)
			)
		)
	)
	(zone
		(layer "In12.Cu")
		(hatch none 0.5)
		(connect_pads
			(clearance 0)
		)
		(min_thickness 0.25)
		(keepout
			(tracks not_allowed)
			(vias allowed)
			(pads allowed)
			(copperpour not_allowed)
			(footprints allowed)
		)
		(placement
			(enabled no)
			(sheetname "")
		)
		(fill
			(thermal_gap 0.5)
			(thermal_bridge_width 0.5)
			(island_removal_mode 0)
		)
		(polygon
			(pts
				(xy 111.020098 -4.720082) (xy 111.578898 -4.720082) (xy 111.578898 -6.523482) (xy 111.020098 -6.523482)
			)
		)
	)
	(zone
		(layer "In12.Cu")
		(hatch none 0.5)
		(connect_pads
			(clearance 0)
		)
		(min_thickness 0.25)
		(keepout
			(tracks not_allowed)
			(vias allowed)
			(pads allowed)
			(copperpour not_allowed)
			(footprints allowed)
		)
		(placement
			(enabled no)
			(sheetname "")
		)
		(fill
			(thermal_gap 0.5)
			(thermal_bridge_width 0.5)
			(island_removal_mode 0)
		)
		(polygon
			(pts
				(xy 112.72012 -14.321282) (xy 113.27892 -14.321282) (xy 113.27892 -16.124682) (xy 112.72012 -16.124682)
			)
		)
	)
	(zone
		(layer "In12.Cu")
		(hatch none 0.5)
		(connect_pads
			(clearance 0)
		)
		(min_thickness 0.25)
		(keepout
			(tracks not_allowed)
			(vias allowed)
			(pads allowed)
			(copperpour not_allowed)
			(footprints allowed)
		)
		(placement
			(enabled no)
			(sheetname "")
		)
		(fill
			(thermal_gap 0.5)
			(thermal_bridge_width 0.5)
			(island_removal_mode 0)
		)
		(polygon
			(pts
				(xy 401.00377 -126.135384) (xy 402.40077 -126.135384) (xy 402.40077 -126.643384) (xy 401.00377 -126.643384)
			)
		)
	)
	(zone
		(layer "In12.Cu")
		(hatch none 0.5)
		(connect_pads
			(clearance 0)
		)
		(min_thickness 0.25)
		(keepout
			(tracks not_allowed)
			(vias allowed)
			(pads allowed)
			(copperpour not_allowed)
			(footprints allowed)
		)
		(placement
			(enabled no)
			(sheetname "")
		)
		(fill
			(thermal_gap 0.5)
			(thermal_bridge_width 0.5)
			(island_removal_mode 0)
		)
		(polygon
			(pts
				(xy 54.069996 -19.322542) (xy 54.628796 -19.322542) (xy 54.628796 -21.125942) (xy 54.069996 -21.125942)
			)
		)
	)
	(zone
		(layer "In12.Cu")
		(hatch none 0.5)
		(connect_pads
			(clearance 0)
		)
		(min_thickness 0.25)
		(keepout
			(tracks not_allowed)
			(vias allowed)
			(pads allowed)
			(copperpour not_allowed)
			(footprints allowed)
		)
		(placement
			(enabled no)
			(sheetname "")
		)
		(fill
			(thermal_gap 0.5)
			(thermal_bridge_width 0.5)
			(island_removal_mode 0)
		)
		(polygon
			(pts
				(xy 92.32011 -4.720082) (xy 92.87891 -4.720082) (xy 92.87891 -6.523482) (xy 92.32011 -6.523482)
			)
		)
	)
	(zone
		(layer "In12.Cu")
		(hatch none 0.5)
		(connect_pads
			(clearance 0)
		)
		(min_thickness 0.25)
		(keepout
			(tracks not_allowed)
			(vias allowed)
			(pads allowed)
			(copperpour not_allowed)
			(footprints allowed)
		)
		(placement
			(enabled no)
			(sheetname "")
		)
		(fill
			(thermal_gap 0.5)
			(thermal_bridge_width 0.5)
			(island_removal_mode 0)
		)
		(polygon
			(pts
				(xy 219.070428 -9.721342) (xy 219.629228 -9.721342) (xy 219.629228 -11.524742) (xy 219.070428 -11.524742)
			)
		)
	)
	(zone
		(layer "In12.Cu")
		(hatch none 0.5)
		(connect_pads
			(clearance 0)
		)
		(min_thickness 0.25)
		(keepout
			(tracks not_allowed)
			(vias allowed)
			(pads allowed)
			(copperpour not_allowed)
			(footprints allowed)
		)
		(placement
			(enabled no)
			(sheetname "")
		)
		(fill
			(thermal_gap 0.5)
			(thermal_bridge_width 0.5)
			(island_removal_mode 0)
		)
		(polygon
			(pts
				(xy 212.270594 -146.576542) (xy 212.829394 -146.576542) (xy 212.829394 -148.379942) (xy 212.270594 -148.379942)
			)
		)
	)
	(zone
		(layer "In12.Cu")
		(hatch none 0.5)
		(connect_pads
			(clearance 0)
		)
		(min_thickness 0.25)
		(keepout
			(tracks not_allowed)
			(vias allowed)
			(pads allowed)
			(copperpour not_allowed)
			(footprints allowed)
		)
		(placement
			(enabled no)
			(sheetname "")
		)
		(fill
			(thermal_gap 0.5)
			(thermal_bridge_width 0.5)
			(island_removal_mode 0)
		)
		(polygon
			(pts
				(xy 271.770602 -141.575282) (xy 272.329402 -141.575282) (xy 272.329402 -143.378682) (xy 271.770602 -143.378682)
			)
		)
	)
	(zone
		(layer "In12.Cu")
		(hatch none 0.5)
		(connect_pads
			(clearance 0)
		)
		(min_thickness 0.25)
		(keepout
			(tracks not_allowed)
			(vias allowed)
			(pads allowed)
			(copperpour not_allowed)
			(footprints allowed)
		)
		(placement
			(enabled no)
			(sheetname "")
		)
		(fill
			(thermal_gap 0.5)
			(thermal_bridge_width 0.5)
			(island_removal_mode 0)
		)
		(polygon
			(pts
				(xy 295.570402 -19.322542) (xy 296.129202 -19.322542) (xy 296.129202 -21.125942) (xy 295.570402 -21.125942)
			)
		)
	)
	(zone
		(layer "In12.Cu")
		(hatch none 0.5)
		(connect_pads
			(clearance 0)
		)
		(min_thickness 0.25)
		(keepout
			(tracks not_allowed)
			(vias allowed)
			(pads allowed)
			(copperpour not_allowed)
			(footprints allowed)
		)
		(placement
			(enabled no)
			(sheetname "")
		)
		(fill
			(thermal_gap 0.5)
			(thermal_bridge_width 0.5)
			(island_removal_mode 0)
		)
		(polygon
			(pts
				(xy 254.770382 -131.974082) (xy 255.329182 -131.974082) (xy 255.329182 -133.777482) (xy 254.770382 -133.777482)
			)
		)
	)
	(zone
		(layer "In12.Cu")
		(hatch none 0.5)
		(connect_pads
			(clearance 0)
		)
		(min_thickness 0.25)
		(keepout
			(tracks not_allowed)
			(vias allowed)
			(pads allowed)
			(copperpour not_allowed)
			(footprints allowed)
		)
		(placement
			(enabled no)
			(sheetname "")
		)
		(fill
			(thermal_gap 0.5)
			(thermal_bridge_width 0.5)
			(island_removal_mode 0)
		)
		(polygon
			(pts
				(xy 202.070462 -131.974082) (xy 202.629262 -131.974082) (xy 202.629262 -133.777482) (xy 202.070462 -133.777482)
			)
		)
	)
	(zone
		(layer "In12.Cu")
		(hatch none 0.5)
		(connect_pads
			(clearance 0)
		)
		(min_thickness 0.25)
		(keepout
			(tracks not_allowed)
			(vias allowed)
			(pads allowed)
			(copperpour not_allowed)
			(footprints allowed)
		)
		(placement
			(enabled no)
			(sheetname "")
		)
		(fill
			(thermal_gap 0.5)
			(thermal_bridge_width 0.5)
			(island_removal_mode 0)
		)
		(polygon
			(pts
				(xy 91.469972 -14.321282) (xy 92.028772 -14.321282) (xy 92.028772 -16.124682) (xy 91.469972 -16.124682)
			)
		)
	)
	(zone
		(layer "In12.Cu")
		(hatch none 0.5)
		(connect_pads
			(clearance 0)
		)
		(min_thickness 0.25)
		(keepout
			(tracks not_allowed)
			(vias allowed)
			(pads allowed)
			(copperpour not_allowed)
			(footprints allowed)
		)
		(placement
			(enabled no)
			(sheetname "")
		)
		(fill
			(thermal_gap 0.5)
			(thermal_bridge_width 0.5)
			(island_removal_mode 0)
		)
		(polygon
			(pts
				(xy 150.96998 -146.576542) (xy 151.52878 -146.576542) (xy 151.52878 -148.379942) (xy 150.96998 -148.379942)
			)
		)
	)
	(zone
		(layer "In12.Cu")
		(hatch none 0.5)
		(connect_pads
			(clearance 0)
		)
		(min_thickness 0.25)
		(keepout
			(tracks not_allowed)
			(vias allowed)
			(pads allowed)
			(copperpour not_allowed)
			(footprints allowed)
		)
		(placement
			(enabled no)
			(sheetname "")
		)
		(fill
			(thermal_gap 0.5)
			(thermal_bridge_width 0.5)
			(island_removal_mode 0)
		)
		(polygon
			(pts
				(xy 265.820398 -23.922482) (xy 266.379198 -23.922482) (xy 266.379198 -25.725882) (xy 265.820398 -25.725882)
			)
		)
	)
	(zone
		(layer "In12.Cu")
		(hatch none 0.5)
		(connect_pads
			(clearance 0)
		)
		(min_thickness 0.25)
		(keepout
			(tracks not_allowed)
			(vias allowed)
			(pads allowed)
			(copperpour not_allowed)
			(footprints allowed)
		)
		(placement
			(enabled no)
			(sheetname "")
		)
		(fill
			(thermal_gap 0.5)
			(thermal_bridge_width 0.5)
			(island_removal_mode 0)
		)
		(polygon
			(pts
				(xy 121.219976 -9.721342) (xy 121.778776 -9.721342) (xy 121.778776 -11.524742) (xy 121.219976 -11.524742)
			)
		)
	)
	(zone
		(layer "In12.Cu")
		(hatch none 0.5)
		(connect_pads
			(clearance 0)
		)
		(min_thickness 0.25)
		(keepout
			(tracks not_allowed)
			(vias allowed)
			(pads allowed)
			(copperpour not_allowed)
			(footprints allowed)
		)
		(placement
			(enabled no)
			(sheetname "")
		)
		(fill
			(thermal_gap 0.5)
			(thermal_bridge_width 0.5)
			(island_removal_mode 0)
		)
		(polygon
			(pts
				(xy 340.585806 -59.225434) (xy 340.585806 -61.511434) (xy 340.077806 -61.511434) (xy 340.077806 -59.225434)
			)
		)
	)
	(zone
		(layer "In12.Cu")
		(hatch none 0.5)
		(connect_pads
			(clearance 0)
		)
		(min_thickness 0.25)
		(keepout
			(tracks not_allowed)
			(vias allowed)
			(pads allowed)
			(copperpour not_allowed)
			(footprints allowed)
		)
		(placement
			(enabled no)
			(sheetname "")
		)
		(fill
			(thermal_gap 0.5)
			(thermal_bridge_width 0.5)
			(island_removal_mode 0)
		)
		(polygon
			(pts
				(xy 119.519954 -19.322542) (xy 120.078754 -19.322542) (xy 120.078754 -21.125942) (xy 119.519954 -21.125942)
			)
		)
	)
	(zone
		(layer "In12.Cu")
		(hatch none 0.5)
		(connect_pads
			(clearance 0)
		)
		(min_thickness 0.25)
		(keepout
			(tracks not_allowed)
			(vias allowed)
			(pads allowed)
			(copperpour not_allowed)
			(footprints allowed)
		)
		(placement
			(enabled no)
			(sheetname "")
		)
		(fill
			(thermal_gap 0.5)
			(thermal_bridge_width 0.5)
			(island_removal_mode 0)
		)
		(polygon
			(pts
				(xy 103.370126 -14.321282) (xy 103.928926 -14.321282) (xy 103.928926 -16.124682) (xy 103.370126 -16.124682)
			)
		)
	)
	(zone
		(layer "In12.Cu")
		(hatch none 0.5)
		(connect_pads
			(clearance 0)
		)
		(min_thickness 0.25)
		(keepout
			(tracks not_allowed)
			(vias allowed)
			(pads allowed)
			(copperpour not_allowed)
			(footprints allowed)
		)
		(placement
			(enabled no)
			(sheetname "")
		)
		(fill
			(thermal_gap 0.5)
			(thermal_bridge_width 0.5)
			(island_removal_mode 0)
		)
		(polygon
			(pts
				(xy 68.520056 -4.720082) (xy 69.078856 -4.720082) (xy 69.078856 -6.523482) (xy 68.520056 -6.523482)
			)
		)
	)
	(zone
		(layer "In12.Cu")
		(hatch none 0.5)
		(connect_pads
			(clearance 0)
		)
		(min_thickness 0.25)
		(keepout
			(tracks not_allowed)
			(vias allowed)
			(pads allowed)
			(copperpour not_allowed)
			(footprints allowed)
		)
		(placement
			(enabled no)
			(sheetname "")
		)
		(fill
			(thermal_gap 0.5)
			(thermal_bridge_width 0.5)
			(island_removal_mode 0)
		)
		(polygon
			(pts
				(xy 276.02053 -4.720082) (xy 276.57933 -4.720082) (xy 276.57933 -6.523482) (xy 276.02053 -6.523482)
			)
		)
	)
	(zone
		(layer "In12.Cu")
		(hatch none 0.5)
		(connect_pads
			(clearance 0)
		)
		(min_thickness 0.25)
		(keepout
			(tracks not_allowed)
			(vias allowed)
			(pads allowed)
			(copperpour not_allowed)
			(footprints allowed)
		)
		(placement
			(enabled no)
			(sheetname "")
		)
		(fill
			(thermal_gap 0.5)
			(thermal_bridge_width 0.5)
			(island_removal_mode 0)
		)
		(polygon
			(pts
				(xy 213.970362 -9.721342) (xy 214.529162 -9.721342) (xy 214.529162 -11.524742) (xy 213.970362 -11.524742)
			)
		)
	)
	(zone
		(layer "In12.Cu")
		(hatch none 0.5)
		(connect_pads
			(clearance 0)
		)
		(min_thickness 0.25)
		(keepout
			(tracks not_allowed)
			(vias allowed)
			(pads allowed)
			(copperpour not_allowed)
			(footprints allowed)
		)
		(placement
			(enabled no)
			(sheetname "")
		)
		(fill
			(thermal_gap 0.5)
			(thermal_bridge_width 0.5)
			(island_removal_mode 0)
		)
		(polygon
			(pts
				(xy 268.370558 -4.720082) (xy 268.929358 -4.720082) (xy 268.929358 -6.523482) (xy 268.370558 -6.523482)
			)
		)
	)
	(zone
		(layer "In12.Cu")
		(hatch none 0.5)
		(connect_pads
			(clearance 0)
		)
		(min_thickness 0.25)
		(keepout
			(tracks not_allowed)
			(vias allowed)
			(pads allowed)
			(copperpour not_allowed)
			(footprints allowed)
		)
		(placement
			(enabled no)
			(sheetname "")
		)
		(fill
			(thermal_gap 0.5)
			(thermal_bridge_width 0.5)
			(island_removal_mode 0)
		)
		(polygon
			(pts
				(xy 207.170528 -23.922482) (xy 207.729328 -23.922482) (xy 207.729328 -25.725882) (xy 207.170528 -25.725882)
			)
		)
	)
	(zone
		(layer "In12.Cu")
		(hatch none 0.5)
		(connect_pads
			(clearance 0)
		)
		(min_thickness 0.25)
		(keepout
			(tracks not_allowed)
			(vias allowed)
			(pads allowed)
			(copperpour not_allowed)
			(footprints allowed)
		)
		(placement
			(enabled no)
			(sheetname "")
		)
		(fill
			(thermal_gap 0.5)
			(thermal_bridge_width 0.5)
			(island_removal_mode 0)
		)
		(polygon
			(pts
				(xy 283.670502 -136.975342) (xy 284.229302 -136.975342) (xy 284.229302 -138.778742) (xy 283.670502 -138.778742)
			)
		)
	)
	(zone
		(layer "In12.Cu")
		(hatch none 0.5)
		(connect_pads
			(clearance 0)
		)
		(min_thickness 0.25)
		(keepout
			(tracks not_allowed)
			(vias allowed)
			(pads allowed)
			(copperpour not_allowed)
			(footprints allowed)
		)
		(placement
			(enabled no)
			(sheetname "")
		)
		(fill
			(thermal_gap 0.5)
			(thermal_bridge_width 0.5)
			(island_removal_mode 0)
		)
		(polygon
			(pts
				(xy 315.970412 -146.576542) (xy 316.529212 -146.576542) (xy 316.529212 -148.379942) (xy 315.970412 -148.379942)
			)
		)
	)
	(zone
		(layer "In12.Cu")
		(hatch none 0.5)
		(connect_pads
			(clearance 0)
		)
		(min_thickness 0.25)
		(keepout
			(tracks not_allowed)
			(vias allowed)
			(pads allowed)
			(copperpour not_allowed)
			(footprints allowed)
		)
		(placement
			(enabled no)
			(sheetname "")
		)
		(fill
			(thermal_gap 0.5)
			(thermal_bridge_width 0.5)
			(island_removal_mode 0)
		)
		(polygon
			(pts
				(xy 50.669952 -19.322542) (xy 51.228752 -19.322542) (xy 51.228752 -21.125942) (xy 50.669952 -21.125942)
			)
		)
	)
	(zone
		(layer "In12.Cu")
		(hatch none 0.5)
		(connect_pads
			(clearance 0)
		)
		(min_thickness 0.25)
		(keepout
			(tracks not_allowed)
			(vias allowed)
			(pads allowed)
			(copperpour not_allowed)
			(footprints allowed)
		)
		(placement
			(enabled no)
			(sheetname "")
		)
		(fill
			(thermal_gap 0.5)
			(thermal_bridge_width 0.5)
			(island_removal_mode 0)
		)
		(polygon
			(pts
				(xy 44.720002 -127.374142) (xy 45.278802 -127.374142) (xy 45.278802 -129.177542) (xy 44.720002 -129.177542)
			)
		)
	)
	(zone
		(layer "In12.Cu")
		(hatch none 0.5)
		(connect_pads
			(clearance 0)
		)
		(min_thickness 0.25)
		(keepout
			(tracks not_allowed)
			(vias allowed)
			(pads allowed)
			(copperpour not_allowed)
			(footprints allowed)
		)
		(placement
			(enabled no)
			(sheetname "")
		)
		(fill
			(thermal_gap 0.5)
			(thermal_bridge_width 0.5)
			(island_removal_mode 0)
		)
		(polygon
			(pts
				(xy 304.920396 -19.322542) (xy 305.479196 -19.322542) (xy 305.479196 -21.125942) (xy 304.920396 -21.125942)
			)
		)
	)
	(zone
		(layer "In12.Cu")
		(hatch none 0.5)
		(connect_pads
			(clearance 0)
		)
		(min_thickness 0.25)
		(keepout
			(tracks not_allowed)
			(vias allowed)
			(pads allowed)
			(copperpour not_allowed)
			(footprints allowed)
		)
		(placement
			(enabled no)
			(sheetname "")
		)
		(fill
			(thermal_gap 0.5)
			(thermal_bridge_width 0.5)
			(island_removal_mode 0)
		)
		(polygon
			(pts
				(xy 48.120046 -151.176482) (xy 48.678846 -151.176482) (xy 48.678846 -152.979882) (xy 48.120046 -152.979882)
			)
		)
	)
	(zone
		(layer "In12.Cu")
		(hatch none 0.5)
		(connect_pads
			(clearance 0)
		)
		(min_thickness 0.25)
		(keepout
			(tracks not_allowed)
			(vias allowed)
			(pads allowed)
			(copperpour not_allowed)
			(footprints allowed)
		)
		(placement
			(enabled no)
			(sheetname "")
		)
		(fill
			(thermal_gap 0.5)
			(thermal_bridge_width 0.5)
			(island_removal_mode 0)
		)
		(polygon
			(pts
				(xy 63.41999 -151.176482) (xy 63.97879 -151.176482) (xy 63.97879 -152.979882) (xy 63.41999 -152.979882)
			)
		)
	)
	(zone
		(layer "In12.Cu")
		(hatch none 0.5)
		(connect_pads
			(clearance 0)
		)
		(min_thickness 0.25)
		(keepout
			(tracks not_allowed)
			(vias allowed)
			(pads allowed)
			(copperpour not_allowed)
			(footprints allowed)
		)
		(placement
			(enabled no)
			(sheetname "")
		)
		(fill
			(thermal_gap 0.5)
			(thermal_bridge_width 0.5)
			(island_removal_mode 0)
		)
		(polygon
			(pts
				(xy 445.77 -115.34902) (xy 446.278 -115.34902) (xy 446.278 -116.74602) (xy 445.77 -116.74602)
			)
		)
	)
	(zone
		(layer "In12.Cu")
		(hatch none 0.5)
		(connect_pads
			(clearance 0)
		)
		(min_thickness 0.25)
		(keepout
			(tracks not_allowed)
			(vias allowed)
			(pads allowed)
			(copperpour not_allowed)
			(footprints allowed)
		)
		(placement
			(enabled no)
			(sheetname "")
		)
		(fill
			(thermal_gap 0.5)
			(thermal_bridge_width 0.5)
			(island_removal_mode 0)
		)
		(polygon
			(pts
				(xy 142.46987 -4.720082) (xy 143.02867 -4.720082) (xy 143.02867 -6.523482) (xy 142.46987 -6.523482)
			)
		)
	)
	(zone
		(layer "In12.Cu")
		(hatch none 0.5)
		(connect_pads
			(clearance 0)
		)
		(min_thickness 0.25)
		(keepout
			(tracks not_allowed)
			(vias allowed)
			(pads allowed)
			(copperpour not_allowed)
			(footprints allowed)
		)
		(placement
			(enabled no)
			(sheetname "")
		)
		(fill
			(thermal_gap 0.5)
			(thermal_bridge_width 0.5)
			(island_removal_mode 0)
		)
		(polygon
			(pts
				(xy 220.77045 -151.176482) (xy 221.32925 -151.176482) (xy 221.32925 -152.979882) (xy 220.77045 -152.979882)
			)
		)
	)
	(zone
		(layer "In12.Cu")
		(hatch none 0.5)
		(connect_pads
			(clearance 0)
		)
		(min_thickness 0.25)
		(keepout
			(tracks not_allowed)
			(vias allowed)
			(pads allowed)
			(copperpour not_allowed)
			(footprints allowed)
		)
		(placement
			(enabled no)
			(sheetname "")
		)
		(fill
			(thermal_gap 0.5)
			(thermal_bridge_width 0.5)
			(island_removal_mode 0)
		)
		(polygon
			(pts
				(xy 84.670138 -9.721342) (xy 85.228938 -9.721342) (xy 85.228938 -11.524742) (xy 84.670138 -11.524742)
			)
		)
	)
	(zone
		(layer "In12.Cu")
		(hatch none 0.5)
		(connect_pads
			(clearance 0)
		)
		(min_thickness 0.25)
		(keepout
			(tracks not_allowed)
			(vias allowed)
			(pads allowed)
			(copperpour not_allowed)
			(footprints allowed)
		)
		(placement
			(enabled no)
			(sheetname "")
		)
		(fill
			(thermal_gap 0.5)
			(thermal_bridge_width 0.5)
			(island_removal_mode 0)
		)
		(polygon
			(pts
				(xy 35.370008 -14.321282) (xy 35.928808 -14.321282) (xy 35.928808 -16.124682) (xy 35.370008 -16.124682)
			)
		)
	)
	(zone
		(layer "In12.Cu")
		(hatch none 0.5)
		(connect_pads
			(clearance 0)
		)
		(min_thickness 0.25)
		(keepout
			(tracks not_allowed)
			(vias allowed)
			(pads allowed)
			(copperpour not_allowed)
			(footprints allowed)
		)
		(placement
			(enabled no)
			(sheetname "")
		)
		(fill
			(thermal_gap 0.5)
			(thermal_bridge_width 0.5)
			(island_removal_mode 0)
		)
		(polygon
			(pts
				(xy 298.120308 -4.720082) (xy 298.679108 -4.720082) (xy 298.679108 -6.523482) (xy 298.120308 -6.523482)
			)
		)
	)
	(zone
		(layer "In12.Cu")
		(hatch none 0.5)
		(connect_pads
			(clearance 0)
		)
		(min_thickness 0.25)
		(keepout
			(tracks not_allowed)
			(vias allowed)
			(pads allowed)
			(copperpour not_allowed)
			(footprints allowed)
		)
		(placement
			(enabled no)
			(sheetname "")
		)
		(fill
			(thermal_gap 0.5)
			(thermal_bridge_width 0.5)
			(island_removal_mode 0)
		)
		(polygon
			(pts
				(xy 195.270374 -9.721342) (xy 195.829174 -9.721342) (xy 195.829174 -11.524742) (xy 195.270374 -11.524742)
			)
		)
	)
	(zone
		(layer "In12.Cu")
		(hatch none 0.5)
		(connect_pads
			(clearance 0)
		)
		(min_thickness 0.25)
		(keepout
			(tracks not_allowed)
			(vias allowed)
			(pads allowed)
			(copperpour not_allowed)
			(footprints allowed)
		)
		(placement
			(enabled no)
			(sheetname "")
		)
		(fill
			(thermal_gap 0.5)
			(thermal_bridge_width 0.5)
			(island_removal_mode 0)
		)
		(polygon
			(pts
				(xy 110.16996 -19.322542) (xy 110.72876 -19.322542) (xy 110.72876 -21.125942) (xy 110.16996 -21.125942)
			)
		)
	)
	(zone
		(layer "In12.Cu")
		(hatch none 0.5)
		(connect_pads
			(clearance 0)
		)
		(min_thickness 0.25)
		(keepout
			(tracks not_allowed)
			(vias allowed)
			(pads allowed)
			(copperpour not_allowed)
			(footprints allowed)
		)
		(placement
			(enabled no)
			(sheetname "")
		)
		(fill
			(thermal_gap 0.5)
			(thermal_bridge_width 0.5)
			(island_removal_mode 0)
		)
		(polygon
			(pts
				(xy 308.32044 -136.975342) (xy 308.87924 -136.975342) (xy 308.87924 -138.778742) (xy 308.32044 -138.778742)
			)
		)
	)
	(zone
		(layer "In12.Cu")
		(hatch none 0.5)
		(connect_pads
			(clearance 0)
		)
		(min_thickness 0.25)
		(keepout
			(tracks not_allowed)
			(vias allowed)
			(pads allowed)
			(copperpour not_allowed)
			(footprints allowed)
		)
		(placement
			(enabled no)
			(sheetname "")
		)
		(fill
			(thermal_gap 0.5)
			(thermal_bridge_width 0.5)
			(island_removal_mode 0)
		)
		(polygon
			(pts
				(xy 311.720484 -136.975342) (xy 312.279284 -136.975342) (xy 312.279284 -138.778742) (xy 311.720484 -138.778742)
			)
		)
	)
	(zone
		(layer "In12.Cu")
		(hatch none 0.5)
		(connect_pads
			(clearance 0)
		)
		(min_thickness 0.25)
		(keepout
			(tracks not_allowed)
			(vias allowed)
			(pads allowed)
			(copperpour not_allowed)
			(footprints allowed)
		)
		(placement
			(enabled no)
			(sheetname "")
		)
		(fill
			(thermal_gap 0.5)
			(thermal_bridge_width 0.5)
			(island_removal_mode 0)
		)
		(polygon
			(pts
				(xy 120.370092 -151.176482) (xy 120.928892 -151.176482) (xy 120.928892 -152.979882) (xy 120.370092 -152.979882)
			)
		)
	)
	(zone
		(layer "In12.Cu")
		(hatch none 0.5)
		(connect_pads
			(clearance 0)
		)
		(min_thickness 0.25)
		(keepout
			(tracks not_allowed)
			(vias allowed)
			(pads allowed)
			(copperpour not_allowed)
			(footprints allowed)
		)
		(placement
			(enabled no)
			(sheetname "")
		)
		(fill
			(thermal_gap 0.5)
			(thermal_bridge_width 0.5)
			(island_removal_mode 0)
		)
		(polygon
			(pts
				(xy 203.770484 -23.922482) (xy 204.329284 -23.922482) (xy 204.329284 -25.725882) (xy 203.770484 -25.725882)
			)
		)
	)
	(zone
		(layer "In12.Cu")
		(hatch none 0.5)
		(connect_pads
			(clearance 0)
		)
		(min_thickness 0.25)
		(keepout
			(tracks not_allowed)
			(vias allowed)
			(pads allowed)
			(copperpour not_allowed)
			(footprints allowed)
		)
		(placement
			(enabled no)
			(sheetname "")
		)
		(fill
			(thermal_gap 0.5)
			(thermal_bridge_width 0.5)
			(island_removal_mode 0)
		)
		(polygon
			(pts
				(xy 311.720484 -131.974082) (xy 312.279284 -131.974082) (xy 312.279284 -133.777482) (xy 311.720484 -133.777482)
			)
		)
	)
	(zone
		(layer "In12.Cu")
		(hatch none 0.5)
		(connect_pads
			(clearance 0)
		)
		(min_thickness 0.25)
		(keepout
			(tracks not_allowed)
			(vias allowed)
			(pads allowed)
			(copperpour not_allowed)
			(footprints allowed)
		)
		(placement
			(enabled no)
			(sheetname "")
		)
		(fill
			(thermal_gap 0.5)
			(thermal_bridge_width 0.5)
			(island_removal_mode 0)
		)
		(polygon
			(pts
				(xy 294.720518 -14.321282) (xy 295.279318 -14.321282) (xy 295.279318 -16.124682) (xy 294.720518 -16.124682)
			)
		)
	)
	(zone
		(layer "In12.Cu")
		(hatch none 0.5)
		(connect_pads
			(clearance 0)
		)
		(min_thickness 0.25)
		(keepout
			(tracks not_allowed)
			(vias allowed)
			(pads allowed)
			(copperpour not_allowed)
			(footprints allowed)
		)
		(placement
			(enabled no)
			(sheetname "")
		)
		(fill
			(thermal_gap 0.5)
			(thermal_bridge_width 0.5)
			(island_removal_mode 0)
		)
		(polygon
			(pts
				(xy 202.9206 -9.721342) (xy 203.4794 -9.721342) (xy 203.4794 -11.524742) (xy 202.9206 -11.524742)
			)
		)
	)
	(zone
		(layer "In12.Cu")
		(hatch none 0.5)
		(connect_pads
			(clearance 0)
		)
		(min_thickness 0.25)
		(keepout
			(tracks not_allowed)
			(vias allowed)
			(pads allowed)
			(copperpour not_allowed)
			(footprints allowed)
		)
		(placement
			(enabled no)
			(sheetname "")
		)
		(fill
			(thermal_gap 0.5)
			(thermal_bridge_width 0.5)
			(island_removal_mode 0)
		)
		(polygon
			(pts
				(xy 36.220146 -9.721342) (xy 36.778946 -9.721342) (xy 36.778946 -11.524742) (xy 36.220146 -11.524742)
			)
		)
	)
	(zone
		(layer "In12.Cu")
		(hatch none 0.5)
		(connect_pads
			(clearance 0)
		)
		(min_thickness 0.25)
		(keepout
			(tracks not_allowed)
			(vias allowed)
			(pads allowed)
			(copperpour not_allowed)
			(footprints allowed)
		)
		(placement
			(enabled no)
			(sheetname "")
		)
		(fill
			(thermal_gap 0.5)
			(thermal_bridge_width 0.5)
			(island_removal_mode 0)
		)
		(polygon
			(pts
				(xy 220.77045 -23.922482) (xy 221.32925 -23.922482) (xy 221.32925 -25.725882) (xy 220.77045 -25.725882)
			)
		)
	)
	(zone
		(layer "In12.Cu")
		(hatch none 0.5)
		(connect_pads
			(clearance 0)
		)
		(min_thickness 0.25)
		(keepout
			(tracks not_allowed)
			(vias allowed)
			(pads allowed)
			(copperpour not_allowed)
			(footprints allowed)
		)
		(placement
			(enabled no)
			(sheetname "")
		)
		(fill
			(thermal_gap 0.5)
			(thermal_bridge_width 0.5)
			(island_removal_mode 0)
		)
		(polygon
			(pts
				(xy 232.67035 -127.374142) (xy 233.22915 -127.374142) (xy 233.22915 -129.177542) (xy 232.67035 -129.177542)
			)
		)
	)
	(zone
		(layer "In12.Cu")
		(hatch none 0.5)
		(connect_pads
			(clearance 0)
		)
		(min_thickness 0.25)
		(keepout
			(tracks not_allowed)
			(vias allowed)
			(pads allowed)
			(copperpour not_allowed)
			(footprints allowed)
		)
		(placement
			(enabled no)
			(sheetname "")
		)
		(fill
			(thermal_gap 0.5)
			(thermal_bridge_width 0.5)
			(island_removal_mode 0)
		)
		(polygon
			(pts
				(xy 72.769984 -141.575282) (xy 73.328784 -141.575282) (xy 73.328784 -143.378682) (xy 72.769984 -143.378682)
			)
		)
	)
	(zone
		(layer "In12.Cu")
		(hatch none 0.5)
		(connect_pads
			(clearance 0)
		)
		(min_thickness 0.25)
		(keepout
			(tracks not_allowed)
			(vias allowed)
			(pads allowed)
			(copperpour not_allowed)
			(footprints allowed)
		)
		(placement
			(enabled no)
			(sheetname "")
		)
		(fill
			(thermal_gap 0.5)
			(thermal_bridge_width 0.5)
			(island_removal_mode 0)
		)
		(polygon
			(pts
				(xy 101.670104 -9.721342) (xy 102.228904 -9.721342) (xy 102.228904 -11.524742) (xy 101.670104 -11.524742)
			)
		)
	)
	(zone
		(layer "In12.Cu")
		(hatch none 0.5)
		(connect_pads
			(clearance 0)
		)
		(min_thickness 0.25)
		(keepout
			(tracks not_allowed)
			(vias allowed)
			(pads allowed)
			(copperpour not_allowed)
			(footprints allowed)
		)
		(placement
			(enabled no)
			(sheetname "")
		)
		(fill
			(thermal_gap 0.5)
			(thermal_bridge_width 0.5)
			(island_removal_mode 0)
		)
		(polygon
			(pts
				(xy 60.019946 -146.576542) (xy 60.578746 -146.576542) (xy 60.578746 -148.379942) (xy 60.019946 -148.379942)
			)
		)
	)
	(zone
		(layer "In12.Cu")
		(hatch none 0.5)
		(connect_pads
			(clearance 0)
		)
		(min_thickness 0.25)
		(keepout
			(tracks not_allowed)
			(vias allowed)
			(pads allowed)
			(copperpour not_allowed)
			(footprints allowed)
		)
		(placement
			(enabled no)
			(sheetname "")
		)
		(fill
			(thermal_gap 0.5)
			(thermal_bridge_width 0.5)
			(island_removal_mode 0)
		)
		(polygon
			(pts
				(xy 81.270094 -131.974082) (xy 81.828894 -131.974082) (xy 81.828894 -133.777482) (xy 81.270094 -133.777482)
			)
		)
	)
	(zone
		(layer "In12.Cu")
		(hatch none 0.5)
		(connect_pads
			(clearance 0)
		)
		(min_thickness 0.25)
		(keepout
			(tracks not_allowed)
			(vias allowed)
			(pads allowed)
			(copperpour not_allowed)
			(footprints allowed)
		)
		(placement
			(enabled no)
			(sheetname "")
		)
		(fill
			(thermal_gap 0.5)
			(thermal_bridge_width 0.5)
			(island_removal_mode 0)
		)
		(polygon
			(pts
				(xy 310.870346 -14.321282) (xy 311.429146 -14.321282) (xy 311.429146 -16.124682) (xy 310.870346 -16.124682)
			)
		)
	)
	(zone
		(layer "In12.Cu")
		(hatch none 0.5)
		(connect_pads
			(clearance 0)
		)
		(min_thickness 0.25)
		(keepout
			(tracks not_allowed)
			(vias allowed)
			(pads allowed)
			(copperpour not_allowed)
			(footprints allowed)
		)
		(placement
			(enabled no)
			(sheetname "")
		)
		(fill
			(thermal_gap 0.5)
			(thermal_bridge_width 0.5)
			(island_removal_mode 0)
		)
		(polygon
			(pts
				(xy 344.689176 -76.551536) (xy 344.689176 -78.837536) (xy 344.181176 -78.837536) (xy 344.181176 -76.551536)
			)
		)
	)
	(zone
		(layer "In12.Cu")
		(hatch none 0.5)
		(connect_pads
			(clearance 0)
		)
		(min_thickness 0.25)
		(keepout
			(tracks not_allowed)
			(vias allowed)
			(pads allowed)
			(copperpour not_allowed)
			(footprints allowed)
		)
		(placement
			(enabled no)
			(sheetname "")
		)
		(fill
			(thermal_gap 0.5)
			(thermal_bridge_width 0.5)
			(island_removal_mode 0)
		)
		(polygon
			(pts
				(xy 42.170096 -141.575282) (xy 42.728896 -141.575282) (xy 42.728896 -143.378682) (xy 42.170096 -143.378682)
			)
		)
	)
	(zone
		(layer "In12.Cu")
		(hatch none 0.5)
		(connect_pads
			(clearance 0)
		)
		(min_thickness 0.25)
		(keepout
			(tracks not_allowed)
			(vias allowed)
			(pads allowed)
			(copperpour not_allowed)
			(footprints allowed)
		)
		(placement
			(enabled no)
			(sheetname "")
		)
		(fill
			(thermal_gap 0.5)
			(thermal_bridge_width 0.5)
			(island_removal_mode 0)
		)
		(polygon
			(pts
				(xy 40.470074 -23.922482) (xy 41.028874 -23.922482) (xy 41.028874 -25.725882) (xy 40.470074 -25.725882)
			)
		)
	)
	(zone
		(layer "In12.Cu")
		(hatch none 0.5)
		(connect_pads
			(clearance 0)
		)
		(min_thickness 0.25)
		(keepout
			(tracks not_allowed)
			(vias allowed)
			(pads allowed)
			(copperpour not_allowed)
			(footprints allowed)
		)
		(placement
			(enabled no)
			(sheetname "")
		)
		(fill
			(thermal_gap 0.5)
			(thermal_bridge_width 0.5)
			(island_removal_mode 0)
		)
		(polygon
			(pts
				(xy 32.820102 -23.922482) (xy 33.378902 -23.922482) (xy 33.378902 -25.725882) (xy 32.820102 -25.725882)
			)
		)
	)
	(zone
		(layer "In12.Cu")
		(hatch none 0.5)
		(connect_pads
			(clearance 0)
		)
		(min_thickness 0.25)
		(keepout
			(tracks not_allowed)
			(vias allowed)
			(pads allowed)
			(copperpour not_allowed)
			(footprints allowed)
		)
		(placement
			(enabled no)
			(sheetname "")
		)
		(fill
			(thermal_gap 0.5)
			(thermal_bridge_width 0.5)
			(island_removal_mode 0)
		)
		(polygon
			(pts
				(xy 136.51992 -141.575282) (xy 137.07872 -141.575282) (xy 137.07872 -143.378682) (xy 136.51992 -143.378682)
			)
		)
	)
	(zone
		(layer "In12.Cu")
		(hatch none 0.5)
		(connect_pads
			(clearance 0)
		)
		(min_thickness 0.25)
		(keepout
			(tracks not_allowed)
			(vias allowed)
			(pads allowed)
			(copperpour not_allowed)
			(footprints allowed)
		)
		(placement
			(enabled no)
			(sheetname "")
		)
		(fill
			(thermal_gap 0.5)
			(thermal_bridge_width 0.5)
			(island_removal_mode 0)
		)
		(polygon
			(pts
				(xy 271.770602 -23.922482) (xy 272.329402 -23.922482) (xy 272.329402 -25.725882) (xy 271.770602 -25.725882)
			)
		)
	)
	(zone
		(layer "In12.Cu")
		(hatch none 0.5)
		(connect_pads
			(clearance 0)
		)
		(min_thickness 0.25)
		(keepout
			(tracks not_allowed)
			(vias allowed)
			(pads allowed)
			(copperpour not_allowed)
			(footprints allowed)
		)
		(placement
			(enabled no)
			(sheetname "")
		)
		(fill
			(thermal_gap 0.5)
			(thermal_bridge_width 0.5)
			(island_removal_mode 0)
		)
		(polygon
			(pts
				(xy 73.620122 -146.576542) (xy 74.178922 -146.576542) (xy 74.178922 -148.379942) (xy 73.620122 -148.379942)
			)
		)
	)
	(zone
		(layer "In12.Cu")
		(hatch none 0.5)
		(connect_pads
			(clearance 0)
		)
		(min_thickness 0.25)
		(keepout
			(tracks not_allowed)
			(vias allowed)
			(pads allowed)
			(copperpour not_allowed)
			(footprints allowed)
		)
		(placement
			(enabled no)
			(sheetname "")
		)
		(fill
			(thermal_gap 0.5)
			(thermal_bridge_width 0.5)
			(island_removal_mode 0)
		)
		(polygon
			(pts
				(xy 285.370524 -131.974082) (xy 285.929324 -131.974082) (xy 285.929324 -133.777482) (xy 285.370524 -133.777482)
			)
		)
	)
	(zone
		(layer "In12.Cu")
		(hatch none 0.5)
		(connect_pads
			(clearance 0)
		)
		(min_thickness 0.25)
		(keepout
			(tracks not_allowed)
			(vias allowed)
			(pads allowed)
			(copperpour not_allowed)
			(footprints allowed)
		)
		(placement
			(enabled no)
			(sheetname "")
		)
		(fill
			(thermal_gap 0.5)
			(thermal_bridge_width 0.5)
			(island_removal_mode 0)
		)
		(polygon
			(pts
				(xy 247.12041 -9.721342) (xy 247.67921 -9.721342) (xy 247.67921 -11.524742) (xy 247.12041 -11.524742)
			)
		)
	)
	(zone
		(layer "In12.Cu")
		(hatch none 0.5)
		(connect_pads
			(clearance 0)
		)
		(min_thickness 0.25)
		(keepout
			(tracks not_allowed)
			(vias allowed)
			(pads allowed)
			(copperpour not_allowed)
			(footprints allowed)
		)
		(placement
			(enabled no)
			(sheetname "")
		)
		(fill
			(thermal_gap 0.5)
			(thermal_bridge_width 0.5)
			(island_removal_mode 0)
		)
		(polygon
			(pts
				(xy 267.52042 -146.576542) (xy 268.07922 -146.576542) (xy 268.07922 -148.379942) (xy 267.52042 -148.379942)
			)
		)
	)
	(zone
		(layer "In12.Cu")
		(hatch none 0.5)
		(connect_pads
			(clearance 0)
		)
		(min_thickness 0.25)
		(keepout
			(tracks not_allowed)
			(vias allowed)
			(pads allowed)
			(copperpour not_allowed)
			(footprints allowed)
		)
		(placement
			(enabled no)
			(sheetname "")
		)
		(fill
			(thermal_gap 0.5)
			(thermal_bridge_width 0.5)
			(island_removal_mode 0)
		)
		(polygon
			(pts
				(xy 281.120342 -4.720082) (xy 281.679142 -4.720082) (xy 281.679142 -6.523482) (xy 281.120342 -6.523482)
			)
		)
	)
	(zone
		(layer "In12.Cu")
		(hatch none 0.5)
		(connect_pads
			(clearance 0)
		)
		(min_thickness 0.25)
		(keepout
			(tracks not_allowed)
			(vias allowed)
			(pads allowed)
			(copperpour not_allowed)
			(footprints allowed)
		)
		(placement
			(enabled no)
			(sheetname "")
		)
		(fill
			(thermal_gap 0.5)
			(thermal_bridge_width 0.5)
			(island_removal_mode 0)
		)
		(polygon
			(pts
				(xy 61.719968 -146.576542) (xy 62.278768 -146.576542) (xy 62.278768 -148.379942) (xy 61.719968 -148.379942)
			)
		)
	)
	(zone
		(layer "In12.Cu")
		(hatch none 0.5)
		(connect_pads
			(clearance 0)
		)
		(min_thickness 0.25)
		(keepout
			(tracks not_allowed)
			(vias allowed)
			(pads allowed)
			(copperpour not_allowed)
			(footprints allowed)
		)
		(placement
			(enabled no)
			(sheetname "")
		)
		(fill
			(thermal_gap 0.5)
			(thermal_bridge_width 0.5)
			(island_removal_mode 0)
		)
		(polygon
			(pts
				(xy 87.220044 -23.922482) (xy 87.778844 -23.922482) (xy 87.778844 -25.725882) (xy 87.220044 -25.725882)
			)
		)
	)
	(zone
		(layer "In12.Cu")
		(hatch none 0.5)
		(connect_pads
			(clearance 0)
		)
		(min_thickness 0.25)
		(keepout
			(tracks not_allowed)
			(vias allowed)
			(pads allowed)
			(copperpour not_allowed)
			(footprints allowed)
		)
		(placement
			(enabled no)
			(sheetname "")
		)
		(fill
			(thermal_gap 0.5)
			(thermal_bridge_width 0.5)
			(island_removal_mode 0)
		)
		(polygon
			(pts
				(xy 198.670418 -9.721342) (xy 199.229218 -9.721342) (xy 199.229218 -11.524742) (xy 198.670418 -11.524742)
			)
		)
	)
	(zone
		(layer "In12.Cu")
		(hatch none 0.5)
		(connect_pads
			(clearance 0)
		)
		(min_thickness 0.25)
		(keepout
			(tracks not_allowed)
			(vias allowed)
			(pads allowed)
			(copperpour not_allowed)
			(footprints allowed)
		)
		(placement
			(enabled no)
			(sheetname "")
		)
		(fill
			(thermal_gap 0.5)
			(thermal_bridge_width 0.5)
			(island_removal_mode 0)
		)
		(polygon
			(pts
				(xy 251.370592 -141.575282) (xy 251.929392 -141.575282) (xy 251.929392 -143.378682) (xy 251.370592 -143.378682)
			)
		)
	)
	(zone
		(layer "In12.Cu")
		(hatch none 0.5)
		(connect_pads
			(clearance 0)
		)
		(min_thickness 0.25)
		(keepout
			(tracks not_allowed)
			(vias allowed)
			(pads allowed)
			(copperpour not_allowed)
			(footprints allowed)
		)
		(placement
			(enabled no)
			(sheetname "")
		)
		(fill
			(thermal_gap 0.5)
			(thermal_bridge_width 0.5)
			(island_removal_mode 0)
		)
		(polygon
			(pts
				(xy 102.519988 -4.720082) (xy 103.078788 -4.720082) (xy 103.078788 -6.523482) (xy 102.519988 -6.523482)
			)
		)
	)
	(zone
		(layer "In12.Cu")
		(hatch none 0.5)
		(connect_pads
			(clearance 0)
		)
		(min_thickness 0.25)
		(keepout
			(tracks not_allowed)
			(vias allowed)
			(pads allowed)
			(copperpour not_allowed)
			(footprints allowed)
		)
		(placement
			(enabled no)
			(sheetname "")
		)
		(fill
			(thermal_gap 0.5)
			(thermal_bridge_width 0.5)
			(island_removal_mode 0)
		)
		(polygon
			(pts
				(xy 293.020496 -19.322542) (xy 293.579296 -19.322542) (xy 293.579296 -21.125942) (xy 293.020496 -21.125942)
			)
		)
	)
	(zone
		(layer "In12.Cu")
		(hatch none 0.5)
		(connect_pads
			(clearance 0)
		)
		(min_thickness 0.25)
		(keepout
			(tracks not_allowed)
			(vias allowed)
			(pads allowed)
			(copperpour not_allowed)
			(footprints allowed)
		)
		(placement
			(enabled no)
			(sheetname "")
		)
		(fill
			(thermal_gap 0.5)
			(thermal_bridge_width 0.5)
			(island_removal_mode 0)
		)
		(polygon
			(pts
				(xy 59.170062 -23.922482) (xy 59.728862 -23.922482) (xy 59.728862 -25.725882) (xy 59.170062 -25.725882)
			)
		)
	)
	(zone
		(layer "In12.Cu")
		(hatch none 0.5)
		(connect_pads
			(clearance 0)
		)
		(min_thickness 0.25)
		(keepout
			(tracks not_allowed)
			(vias allowed)
			(pads allowed)
			(copperpour not_allowed)
			(footprints allowed)
		)
		(placement
			(enabled no)
			(sheetname "")
		)
		(fill
			(thermal_gap 0.5)
			(thermal_bridge_width 0.5)
			(island_removal_mode 0)
		)
		(polygon
			(pts
				(xy 32.820102 -4.720082) (xy 33.378902 -4.720082) (xy 33.378902 -6.523482) (xy 32.820102 -6.523482)
			)
		)
	)
	(zone
		(layer "In12.Cu")
		(hatch none 0.5)
		(connect_pads
			(clearance 0)
		)
		(min_thickness 0.25)
		(keepout
			(tracks not_allowed)
			(vias allowed)
			(pads allowed)
			(copperpour not_allowed)
			(footprints allowed)
		)
		(placement
			(enabled no)
			(sheetname "")
		)
		(fill
			(thermal_gap 0.5)
			(thermal_bridge_width 0.5)
			(island_removal_mode 0)
		)
		(polygon
			(pts
				(xy 456.438 -115.34902) (xy 456.946 -115.34902) (xy 456.946 -116.74602) (xy 456.438 -116.74602)
			)
		)
	)
	(zone
		(layer "In12.Cu")
		(hatch none 0.5)
		(connect_pads
			(clearance 0)
		)
		(min_thickness 0.25)
		(keepout
			(tracks not_allowed)
			(vias allowed)
			(pads allowed)
			(copperpour not_allowed)
			(footprints allowed)
		)
		(placement
			(enabled no)
			(sheetname "")
		)
		(fill
			(thermal_gap 0.5)
			(thermal_bridge_width 0.5)
			(island_removal_mode 0)
		)
		(polygon
			(pts
				(xy 232.67035 -146.576542) (xy 233.22915 -146.576542) (xy 233.22915 -148.379942) (xy 232.67035 -148.379942)
			)
		)
	)
	(zone
		(layer "In12.Cu")
		(hatch none 0.5)
		(connect_pads
			(clearance 0)
		)
		(min_thickness 0.25)
		(keepout
			(tracks not_allowed)
			(vias allowed)
			(pads allowed)
			(copperpour not_allowed)
			(footprints allowed)
		)
		(placement
			(enabled no)
			(sheetname "")
		)
		(fill
			(thermal_gap 0.5)
			(thermal_bridge_width 0.5)
			(island_removal_mode 0)
		)
		(polygon
			(pts
				(xy 276.02053 -131.974082) (xy 276.57933 -131.974082) (xy 276.57933 -133.777482) (xy 276.02053 -133.777482)
			)
		)
	)
	(zone
		(layer "In12.Cu")
		(hatch none 0.5)
		(connect_pads
			(clearance 0)
		)
		(min_thickness 0.25)
		(keepout
			(tracks not_allowed)
			(vias allowed)
			(pads allowed)
			(copperpour not_allowed)
			(footprints allowed)
		)
		(placement
			(enabled no)
			(sheetname "")
		)
		(fill
			(thermal_gap 0.5)
			(thermal_bridge_width 0.5)
			(island_removal_mode 0)
		)
		(polygon
			(pts
				(xy 137.370058 -146.576542) (xy 137.928858 -146.576542) (xy 137.928858 -148.379942) (xy 137.370058 -148.379942)
			)
		)
	)
	(zone
		(layer "In12.Cu")
		(hatch none 0.5)
		(connect_pads
			(clearance 0)
		)
		(min_thickness 0.25)
		(keepout
			(tracks not_allowed)
			(vias allowed)
			(pads allowed)
			(copperpour not_allowed)
			(footprints allowed)
		)
		(placement
			(enabled no)
			(sheetname "")
		)
		(fill
			(thermal_gap 0.5)
			(thermal_bridge_width 0.5)
			(island_removal_mode 0)
		)
		(polygon
			(pts
				(xy 304.070512 -14.321282) (xy 304.629312 -14.321282) (xy 304.629312 -16.124682) (xy 304.070512 -16.124682)
			)
		)
	)
	(zone
		(layer "In12.Cu")
		(hatch none 0.5)
		(connect_pads
			(clearance 0)
		)
		(min_thickness 0.25)
		(keepout
			(tracks not_allowed)
			(vias allowed)
			(pads allowed)
			(copperpour not_allowed)
			(footprints allowed)
		)
		(placement
			(enabled no)
			(sheetname "")
		)
		(fill
			(thermal_gap 0.5)
			(thermal_bridge_width 0.5)
			(island_removal_mode 0)
		)
		(polygon
			(pts
				(xy 44.720002 -146.576542) (xy 45.278802 -146.576542) (xy 45.278802 -148.379942) (xy 44.720002 -148.379942)
			)
		)
	)
	(zone
		(layer "In12.Cu")
		(hatch none 0.5)
		(connect_pads
			(clearance 0)
		)
		(min_thickness 0.25)
		(keepout
			(tracks not_allowed)
			(vias allowed)
			(pads allowed)
			(copperpour not_allowed)
			(footprints allowed)
		)
		(placement
			(enabled no)
			(sheetname "")
		)
		(fill
			(thermal_gap 0.5)
			(thermal_bridge_width 0.5)
			(island_removal_mode 0)
		)
		(polygon
			(pts
				(xy 232.67035 -136.975342) (xy 233.22915 -136.975342) (xy 233.22915 -138.778742) (xy 232.67035 -138.778742)
			)
		)
	)
	(zone
		(layer "In12.Cu")
		(hatch none 0.5)
		(connect_pads
			(clearance 0)
		)
		(min_thickness 0.25)
		(keepout
			(tracks not_allowed)
			(vias allowed)
			(pads allowed)
			(copperpour not_allowed)
			(footprints allowed)
		)
		(placement
			(enabled no)
			(sheetname "")
		)
		(fill
			(thermal_gap 0.5)
			(thermal_bridge_width 0.5)
			(island_removal_mode 0)
		)
		(polygon
			(pts
				(xy 222.470472 -14.321282) (xy 223.029272 -14.321282) (xy 223.029272 -16.124682) (xy 222.470472 -16.124682)
			)
		)
	)
	(zone
		(layer "In12.Cu")
		(hatch none 0.5)
		(connect_pads
			(clearance 0)
		)
		(min_thickness 0.25)
		(keepout
			(tracks not_allowed)
			(vias allowed)
			(pads allowed)
			(copperpour not_allowed)
			(footprints allowed)
		)
		(placement
			(enabled no)
			(sheetname "")
		)
		(fill
			(thermal_gap 0.5)
			(thermal_bridge_width 0.5)
			(island_removal_mode 0)
		)
		(polygon
			(pts
				(xy 129.720086 -141.575282) (xy 130.278886 -141.575282) (xy 130.278886 -143.378682) (xy 129.720086 -143.378682)
			)
		)
	)
	(zone
		(layer "In12.Cu")
		(hatch none 0.5)
		(connect_pads
			(clearance 0)
		)
		(min_thickness 0.25)
		(keepout
			(tracks not_allowed)
			(vias allowed)
			(pads allowed)
			(copperpour not_allowed)
			(footprints allowed)
		)
		(placement
			(enabled no)
			(sheetname "")
		)
		(fill
			(thermal_gap 0.5)
			(thermal_bridge_width 0.5)
			(island_removal_mode 0)
		)
		(polygon
			(pts
				(xy 235.22051 -151.176482) (xy 235.77931 -151.176482) (xy 235.77931 -152.979882) (xy 235.22051 -152.979882)
			)
		)
	)
	(zone
		(layer "In12.Cu")
		(hatch none 0.5)
		(connect_pads
			(clearance 0)
		)
		(min_thickness 0.25)
		(keepout
			(tracks not_allowed)
			(vias allowed)
			(pads allowed)
			(copperpour not_allowed)
			(footprints allowed)
		)
		(placement
			(enabled no)
			(sheetname "")
		)
		(fill
			(thermal_gap 0.5)
			(thermal_bridge_width 0.5)
			(island_removal_mode 0)
		)
		(polygon
			(pts
				(xy 457.2508 -51.340258) (xy 457.7588 -51.340258) (xy 457.7588 -52.737258) (xy 457.2508 -52.737258)
			)
		)
	)
	(zone
		(layer "In12.Cu")
		(hatch none 0.5)
		(connect_pads
			(clearance 0)
		)
		(min_thickness 0.25)
		(keepout
			(tracks not_allowed)
			(vias allowed)
			(pads allowed)
			(copperpour not_allowed)
			(footprints allowed)
		)
		(placement
			(enabled no)
			(sheetname "")
		)
		(fill
			(thermal_gap 0.5)
			(thermal_bridge_width 0.5)
			(island_removal_mode 0)
		)
		(polygon
			(pts
				(xy 134.819898 -23.922482) (xy 135.378698 -23.922482) (xy 135.378698 -25.725882) (xy 134.819898 -25.725882)
			)
		)
	)
	(zone
		(layer "In12.Cu")
		(hatch none 0.5)
		(connect_pads
			(clearance 0)
		)
		(min_thickness 0.25)
		(keepout
			(tracks not_allowed)
			(vias allowed)
			(pads allowed)
			(copperpour not_allowed)
			(footprints allowed)
		)
		(placement
			(enabled no)
			(sheetname "")
		)
		(fill
			(thermal_gap 0.5)
			(thermal_bridge_width 0.5)
			(island_removal_mode 0)
		)
		(polygon
			(pts
				(xy 71.9201 -4.720082) (xy 72.4789 -4.720082) (xy 72.4789 -6.523482) (xy 71.9201 -6.523482)
			)
		)
	)
	(zone
		(layer "In12.Cu")
		(hatch none 0.5)
		(connect_pads
			(clearance 0)
		)
		(min_thickness 0.25)
		(keepout
			(tracks not_allowed)
			(vias allowed)
			(pads allowed)
			(copperpour not_allowed)
			(footprints allowed)
		)
		(placement
			(enabled no)
			(sheetname "")
		)
		(fill
			(thermal_gap 0.5)
			(thermal_bridge_width 0.5)
			(island_removal_mode 0)
		)
		(polygon
			(pts
				(xy 238.620554 -127.374142) (xy 239.179354 -127.374142) (xy 239.179354 -129.177542) (xy 238.620554 -129.177542)
			)
		)
	)
	(zone
		(layer "In12.Cu")
		(hatch none 0.5)
		(connect_pads
			(clearance 0)
		)
		(min_thickness 0.25)
		(keepout
			(tracks not_allowed)
			(vias allowed)
			(pads allowed)
			(copperpour not_allowed)
			(footprints allowed)
		)
		(placement
			(enabled no)
			(sheetname "")
		)
		(fill
			(thermal_gap 0.5)
			(thermal_bridge_width 0.5)
			(island_removal_mode 0)
		)
		(polygon
			(pts
				(xy 38.770052 -131.974082) (xy 39.328852 -131.974082) (xy 39.328852 -133.777482) (xy 38.770052 -133.777482)
			)
		)
	)
	(zone
		(layer "In12.Cu")
		(hatch none 0.5)
		(connect_pads
			(clearance 0)
		)
		(min_thickness 0.25)
		(keepout
			(tracks not_allowed)
			(vias allowed)
			(pads allowed)
			(copperpour not_allowed)
			(footprints allowed)
		)
		(placement
			(enabled no)
			(sheetname "")
		)
		(fill
			(thermal_gap 0.5)
			(thermal_bridge_width 0.5)
			(island_removal_mode 0)
		)
		(polygon
			(pts
				(xy 51.52009 -14.321282) (xy 52.07889 -14.321282) (xy 52.07889 -16.124682) (xy 51.52009 -16.124682)
			)
		)
	)
	(zone
		(layer "In12.Cu")
		(hatch none 0.5)
		(connect_pads
			(clearance 0)
		)
		(min_thickness 0.25)
		(keepout
			(tracks not_allowed)
			(vias allowed)
			(pads allowed)
			(copperpour not_allowed)
			(footprints allowed)
		)
		(placement
			(enabled no)
			(sheetname "")
		)
		(fill
			(thermal_gap 0.5)
			(thermal_bridge_width 0.5)
			(island_removal_mode 0)
		)
		(polygon
			(pts
				(xy 447.674238 -51.264058) (xy 448.182238 -51.264058) (xy 448.182238 -52.661058) (xy 447.674238 -52.661058)
			)
		)
	)
	(zone
		(layer "In12.Cu")
		(hatch none 0.5)
		(connect_pads
			(clearance 0)
		)
		(min_thickness 0.25)
		(keepout
			(tracks not_allowed)
			(vias allowed)
			(pads allowed)
			(copperpour not_allowed)
			(footprints allowed)
		)
		(placement
			(enabled no)
			(sheetname "")
		)
		(fill
			(thermal_gap 0.5)
			(thermal_bridge_width 0.5)
			(island_removal_mode 0)
		)
		(polygon
			(pts
				(xy 116.11991 -4.720082) (xy 116.67871 -4.720082) (xy 116.67871 -6.523482) (xy 116.11991 -6.523482)
			)
		)
	)
	(zone
		(layer "In12.Cu")
		(hatch none 0.5)
		(connect_pads
			(clearance 0)
		)
		(min_thickness 0.25)
		(keepout
			(tracks not_allowed)
			(vias allowed)
			(pads allowed)
			(copperpour not_allowed)
			(footprints allowed)
		)
		(placement
			(enabled no)
			(sheetname "")
		)
		(fill
			(thermal_gap 0.5)
			(thermal_bridge_width 0.5)
			(island_removal_mode 0)
		)
		(polygon
			(pts
				(xy 40.470074 -151.176482) (xy 41.028874 -151.176482) (xy 41.028874 -152.979882) (xy 40.470074 -152.979882)
			)
		)
	)
	(zone
		(layer "In12.Cu")
		(hatch none 0.5)
		(connect_pads
			(clearance 0)
		)
		(min_thickness 0.25)
		(keepout
			(tracks not_allowed)
			(vias allowed)
			(pads allowed)
			(copperpour not_allowed)
			(footprints allowed)
		)
		(placement
			(enabled no)
			(sheetname "")
		)
		(fill
			(thermal_gap 0.5)
			(thermal_bridge_width 0.5)
			(island_removal_mode 0)
		)
		(polygon
			(pts
				(xy 247.12041 -14.321282) (xy 247.67921 -14.321282) (xy 247.67921 -16.124682) (xy 247.12041 -16.124682)
			)
		)
	)
	(zone
		(layer "In12.Cu")
		(hatch none 0.5)
		(connect_pads
			(clearance 0)
		)
		(min_thickness 0.25)
		(keepout
			(tracks not_allowed)
			(vias allowed)
			(pads allowed)
			(copperpour not_allowed)
			(footprints allowed)
		)
		(placement
			(enabled no)
			(sheetname "")
		)
		(fill
			(thermal_gap 0.5)
			(thermal_bridge_width 0.5)
			(island_removal_mode 0)
		)
		(polygon
			(pts
				(xy 298.970446 -127.374142) (xy 299.529246 -127.374142) (xy 299.529246 -129.177542) (xy 298.970446 -129.177542)
			)
		)
	)
	(zone
		(layer "In12.Cu")
		(hatch none 0.5)
		(connect_pads
			(clearance 0)
		)
		(min_thickness 0.25)
		(keepout
			(tracks not_allowed)
			(vias allowed)
			(pads allowed)
			(copperpour not_allowed)
			(footprints allowed)
		)
		(placement
			(enabled no)
			(sheetname "")
		)
		(fill
			(thermal_gap 0.5)
			(thermal_bridge_width 0.5)
			(island_removal_mode 0)
		)
		(polygon
			(pts
				(xy 223.320356 -0.120142) (xy 223.879156 -0.120142) (xy 223.879156 -1.923542) (xy 223.320356 -1.923542)
			)
		)
	)
	(zone
		(layer "In12.Cu")
		(hatch none 0.5)
		(connect_pads
			(clearance 0)
		)
		(min_thickness 0.25)
		(keepout
			(tracks not_allowed)
			(vias allowed)
			(pads allowed)
			(copperpour not_allowed)
			(footprints allowed)
		)
		(placement
			(enabled no)
			(sheetname "")
		)
		(fill
			(thermal_gap 0.5)
			(thermal_bridge_width 0.5)
			(island_removal_mode 0)
		)
		(polygon
			(pts
				(xy 228.420422 -131.974082) (xy 228.979222 -131.974082) (xy 228.979222 -133.777482) (xy 228.420422 -133.777482)
			)
		)
	)
	(zone
		(layer "In12.Cu")
		(hatch none 0.5)
		(connect_pads
			(clearance 0)
		)
		(min_thickness 0.25)
		(keepout
			(tracks not_allowed)
			(vias allowed)
			(pads allowed)
			(copperpour not_allowed)
			(footprints allowed)
		)
		(placement
			(enabled no)
			(sheetname "")
		)
		(fill
			(thermal_gap 0.5)
			(thermal_bridge_width 0.5)
			(island_removal_mode 0)
		)
		(polygon
			(pts
				(xy 82.119978 -127.374142) (xy 82.678778 -127.374142) (xy 82.678778 -129.177542) (xy 82.119978 -129.177542)
			)
		)
	)
	(zone
		(layer "In12.Cu")
		(hatch none 0.5)
		(connect_pads
			(clearance 0)
		)
		(min_thickness 0.25)
		(keepout
			(tracks not_allowed)
			(vias allowed)
			(pads allowed)
			(copperpour not_allowed)
			(footprints allowed)
		)
		(placement
			(enabled no)
			(sheetname "")
		)
		(fill
			(thermal_gap 0.5)
			(thermal_bridge_width 0.5)
			(island_removal_mode 0)
		)
		(polygon
			(pts
				(xy 149.269958 -127.374142) (xy 149.828758 -127.374142) (xy 149.828758 -129.177542) (xy 149.269958 -129.177542)
			)
		)
	)
	(zone
		(layer "In12.Cu")
		(hatch none 0.5)
		(connect_pads
			(clearance 0)
		)
		(min_thickness 0.25)
		(keepout
			(tracks not_allowed)
			(vias allowed)
			(pads allowed)
			(copperpour not_allowed)
			(footprints allowed)
		)
		(placement
			(enabled no)
			(sheetname "")
		)
		(fill
			(thermal_gap 0.5)
			(thermal_bridge_width 0.5)
			(island_removal_mode 0)
		)
		(polygon
			(pts
				(xy 303.220374 -0.120142) (xy 303.779174 -0.120142) (xy 303.779174 -1.923542) (xy 303.220374 -1.923542)
			)
		)
	)
	(zone
		(layer "In12.Cu")
		(hatch none 0.5)
		(connect_pads
			(clearance 0)
		)
		(min_thickness 0.25)
		(keepout
			(tracks not_allowed)
			(vias allowed)
			(pads allowed)
			(copperpour not_allowed)
			(footprints allowed)
		)
		(placement
			(enabled no)
			(sheetname "")
		)
		(fill
			(thermal_gap 0.5)
			(thermal_bridge_width 0.5)
			(island_removal_mode 0)
		)
		(polygon
			(pts
				(xy 70.220078 -4.720082) (xy 70.778878 -4.720082) (xy 70.778878 -6.523482) (xy 70.220078 -6.523482)
			)
		)
	)
	(zone
		(layer "In12.Cu")
		(hatch none 0.5)
		(connect_pads
			(clearance 0)
		)
		(min_thickness 0.25)
		(keepout
			(tracks not_allowed)
			(vias allowed)
			(pads allowed)
			(copperpour not_allowed)
			(footprints allowed)
		)
		(placement
			(enabled no)
			(sheetname "")
		)
		(fill
			(thermal_gap 0.5)
			(thermal_bridge_width 0.5)
			(island_removal_mode 0)
		)
		(polygon
			(pts
				(xy 257.320542 -19.322542) (xy 257.879342 -19.322542) (xy 257.879342 -21.125942) (xy 257.320542 -21.125942)
			)
		)
	)
	(zone
		(layer "In12.Cu")
		(hatch none 0.5)
		(connect_pads
			(clearance 0)
		)
		(min_thickness 0.25)
		(keepout
			(tracks not_allowed)
			(vias allowed)
			(pads allowed)
			(copperpour not_allowed)
			(footprints allowed)
		)
		(placement
			(enabled no)
			(sheetname "")
		)
		(fill
			(thermal_gap 0.5)
			(thermal_bridge_width 0.5)
			(island_removal_mode 0)
		)
		(polygon
			(pts
				(xy 200.37044 -136.975342) (xy 200.92924 -136.975342) (xy 200.92924 -138.778742) (xy 200.37044 -138.778742)
			)
		)
	)
	(zone
		(layer "In12.Cu")
		(hatch none 0.5)
		(connect_pads
			(clearance 0)
		)
		(min_thickness 0.25)
		(keepout
			(tracks not_allowed)
			(vias allowed)
			(pads allowed)
			(copperpour not_allowed)
			(footprints allowed)
		)
		(placement
			(enabled no)
			(sheetname "")
		)
		(fill
			(thermal_gap 0.5)
			(thermal_bridge_width 0.5)
			(island_removal_mode 0)
		)
		(polygon
			(pts
				(xy 207.170528 -151.176482) (xy 207.729328 -151.176482) (xy 207.729328 -152.979882) (xy 207.170528 -152.979882)
			)
		)
	)
	(zone
		(layer "In12.Cu")
		(hatch none 0.5)
		(connect_pads
			(clearance 0)
		)
		(min_thickness 0.25)
		(keepout
			(tracks not_allowed)
			(vias allowed)
			(pads allowed)
			(copperpour not_allowed)
			(footprints allowed)
		)
		(placement
			(enabled no)
			(sheetname "")
		)
		(fill
			(thermal_gap 0.5)
			(thermal_bridge_width 0.5)
			(island_removal_mode 0)
		)
		(polygon
			(pts
				(xy 130.56997 -9.721342) (xy 131.12877 -9.721342) (xy 131.12877 -11.524742) (xy 130.56997 -11.524742)
			)
		)
	)
	(zone
		(layer "In12.Cu")
		(hatch none 0.5)
		(connect_pads
			(clearance 0)
		)
		(min_thickness 0.25)
		(keepout
			(tracks not_allowed)
			(vias allowed)
			(pads allowed)
			(copperpour not_allowed)
			(footprints allowed)
		)
		(placement
			(enabled no)
			(sheetname "")
		)
		(fill
			(thermal_gap 0.5)
			(thermal_bridge_width 0.5)
			(island_removal_mode 0)
		)
		(polygon
			(pts
				(xy 256.470404 -0.120142) (xy 257.029204 -0.120142) (xy 257.029204 -1.923542) (xy 256.470404 -1.923542)
			)
		)
	)
	(zone
		(layer "In12.Cu")
		(hatch none 0.5)
		(connect_pads
			(clearance 0)
		)
		(min_thickness 0.25)
		(keepout
			(tracks not_allowed)
			(vias allowed)
			(pads allowed)
			(copperpour not_allowed)
			(footprints allowed)
		)
		(placement
			(enabled no)
			(sheetname "")
		)
		(fill
			(thermal_gap 0.5)
			(thermal_bridge_width 0.5)
			(island_removal_mode 0)
		)
		(polygon
			(pts
				(xy 250.520454 -146.576542) (xy 251.079254 -146.576542) (xy 251.079254 -148.379942) (xy 250.520454 -148.379942)
			)
		)
	)
	(zone
		(layer "In12.Cu")
		(hatch none 0.5)
		(connect_pads
			(clearance 0)
		)
		(min_thickness 0.25)
		(keepout
			(tracks not_allowed)
			(vias allowed)
			(pads allowed)
			(copperpour not_allowed)
			(footprints allowed)
		)
		(placement
			(enabled no)
			(sheetname "")
		)
		(fill
			(thermal_gap 0.5)
			(thermal_bridge_width 0.5)
			(island_removal_mode 0)
		)
		(polygon
			(pts
				(xy 206.32039 -146.576542) (xy 206.87919 -146.576542) (xy 206.87919 -148.379942) (xy 206.32039 -148.379942)
			)
		)
	)
	(zone
		(layer "In12.Cu")
		(hatch none 0.5)
		(connect_pads
			(clearance 0)
		)
		(min_thickness 0.25)
		(keepout
			(tracks not_allowed)
			(vias allowed)
			(pads allowed)
			(copperpour not_allowed)
			(footprints allowed)
		)
		(placement
			(enabled no)
			(sheetname "")
		)
		(fill
			(thermal_gap 0.5)
			(thermal_bridge_width 0.5)
			(island_removal_mode 0)
		)
		(polygon
			(pts
				(xy 17.58442 -103.09352) (xy 18.98142 -103.09352) (xy 18.98142 -103.60152) (xy 17.58442 -103.60152)
			)
		)
	)
	(zone
		(layer "In12.Cu")
		(hatch none 0.5)
		(connect_pads
			(clearance 0)
		)
		(min_thickness 0.25)
		(keepout
			(tracks not_allowed)
			(vias allowed)
			(pads allowed)
			(copperpour not_allowed)
			(footprints allowed)
		)
		(placement
			(enabled no)
			(sheetname "")
		)
		(fill
			(thermal_gap 0.5)
			(thermal_bridge_width 0.5)
			(island_removal_mode 0)
		)
		(polygon
			(pts
				(xy 312.570368 -146.576542) (xy 313.129168 -146.576542) (xy 313.129168 -148.379942) (xy 312.570368 -148.379942)
			)
		)
	)
	(zone
		(layer "In12.Cu")
		(hatch none 0.5)
		(connect_pads
			(clearance 0)
		)
		(min_thickness 0.25)
		(keepout
			(tracks not_allowed)
			(vias allowed)
			(pads allowed)
			(copperpour not_allowed)
			(footprints allowed)
		)
		(placement
			(enabled no)
			(sheetname "")
		)
		(fill
			(thermal_gap 0.5)
			(thermal_bridge_width 0.5)
			(island_removal_mode 0)
		)
		(polygon
			(pts
				(xy 46.420024 -131.974082) (xy 46.978824 -131.974082) (xy 46.978824 -133.777482) (xy 46.420024 -133.777482)
			)
		)
	)
	(zone
		(layer "In12.Cu")
		(hatch none 0.5)
		(connect_pads
			(clearance 0)
		)
		(min_thickness 0.25)
		(keepout
			(tracks not_allowed)
			(vias allowed)
			(pads allowed)
			(copperpour not_allowed)
			(footprints allowed)
		)
		(placement
			(enabled no)
			(sheetname "")
		)
		(fill
			(thermal_gap 0.5)
			(thermal_bridge_width 0.5)
			(island_removal_mode 0)
		)
		(polygon
			(pts
				(xy 84.670138 -151.176482) (xy 85.228938 -151.176482) (xy 85.228938 -152.979882) (xy 84.670138 -152.979882)
			)
		)
	)
	(zone
		(layer "In12.Cu")
		(hatch none 0.5)
		(connect_pads
			(clearance 0)
		)
		(min_thickness 0.25)
		(keepout
			(tracks not_allowed)
			(vias allowed)
			(pads allowed)
			(copperpour not_allowed)
			(footprints allowed)
		)
		(placement
			(enabled no)
			(sheetname "")
		)
		(fill
			(thermal_gap 0.5)
			(thermal_bridge_width 0.5)
			(island_removal_mode 0)
		)
		(polygon
			(pts
				(xy 64.270128 -136.975342) (xy 64.828928 -136.975342) (xy 64.828928 -138.778742) (xy 64.270128 -138.778742)
			)
		)
	)
	(zone
		(layer "In12.Cu")
		(hatch none 0.5)
		(connect_pads
			(clearance 0)
		)
		(min_thickness 0.25)
		(keepout
			(tracks not_allowed)
			(vias allowed)
			(pads allowed)
			(copperpour not_allowed)
			(footprints allowed)
		)
		(placement
			(enabled no)
			(sheetname "")
		)
		(fill
			(thermal_gap 0.5)
			(thermal_bridge_width 0.5)
			(island_removal_mode 0)
		)
		(polygon
			(pts
				(xy 38.770052 -14.321282) (xy 39.328852 -14.321282) (xy 39.328852 -16.124682) (xy 38.770052 -16.124682)
			)
		)
	)
	(zone
		(layer "In12.Cu")
		(hatch none 0.5)
		(connect_pads
			(clearance 0)
		)
		(min_thickness 0.25)
		(keepout
			(tracks not_allowed)
			(vias allowed)
			(pads allowed)
			(copperpour not_allowed)
			(footprints allowed)
		)
		(placement
			(enabled no)
			(sheetname "")
		)
		(fill
			(thermal_gap 0.5)
			(thermal_bridge_width 0.5)
			(island_removal_mode 0)
		)
		(polygon
			(pts
				(xy 239.470438 -14.321282) (xy 240.029238 -14.321282) (xy 240.029238 -16.124682) (xy 239.470438 -16.124682)
			)
		)
	)
	(zone
		(layer "In12.Cu")
		(hatch none 0.5)
		(connect_pads
			(clearance 0)
		)
		(min_thickness 0.25)
		(keepout
			(tracks not_allowed)
			(vias allowed)
			(pads allowed)
			(copperpour not_allowed)
			(footprints allowed)
		)
		(placement
			(enabled no)
			(sheetname "")
		)
		(fill
			(thermal_gap 0.5)
			(thermal_bridge_width 0.5)
			(island_removal_mode 0)
		)
		(polygon
			(pts
				(xy 69.36994 -136.975342) (xy 69.92874 -136.975342) (xy 69.92874 -138.778742) (xy 69.36994 -138.778742)
			)
		)
	)
	(zone
		(layer "In12.Cu")
		(hatch none 0.5)
		(connect_pads
			(clearance 0)
		)
		(min_thickness 0.25)
		(keepout
			(tracks not_allowed)
			(vias allowed)
			(pads allowed)
			(copperpour not_allowed)
			(footprints allowed)
		)
		(placement
			(enabled no)
			(sheetname "")
		)
		(fill
			(thermal_gap 0.5)
			(thermal_bridge_width 0.5)
			(island_removal_mode 0)
		)
		(polygon
			(pts
				(xy 133.970014 -9.721342) (xy 134.528814 -9.721342) (xy 134.528814 -11.524742) (xy 133.970014 -11.524742)
			)
		)
	)
	(zone
		(layer "In12.Cu")
		(hatch none 0.5)
		(connect_pads
			(clearance 0)
		)
		(min_thickness 0.25)
		(keepout
			(tracks not_allowed)
			(vias allowed)
			(pads allowed)
			(copperpour not_allowed)
			(footprints allowed)
		)
		(placement
			(enabled no)
			(sheetname "")
		)
		(fill
			(thermal_gap 0.5)
			(thermal_bridge_width 0.5)
			(island_removal_mode 0)
		)
		(polygon
			(pts
				(xy 71.9201 -14.321282) (xy 72.4789 -14.321282) (xy 72.4789 -16.124682) (xy 71.9201 -16.124682)
			)
		)
	)
	(zone
		(layer "In12.Cu")
		(hatch none 0.5)
		(connect_pads
			(clearance 0)
		)
		(min_thickness 0.25)
		(keepout
			(tracks not_allowed)
			(vias allowed)
			(pads allowed)
			(copperpour not_allowed)
			(footprints allowed)
		)
		(placement
			(enabled no)
			(sheetname "")
		)
		(fill
			(thermal_gap 0.5)
			(thermal_bridge_width 0.5)
			(island_removal_mode 0)
		)
		(polygon
			(pts
				(xy 35.370008 -9.721342) (xy 35.928808 -9.721342) (xy 35.928808 -11.524742) (xy 35.370008 -11.524742)
			)
		)
	)
	(zone
		(layer "In12.Cu")
		(hatch none 0.5)
		(connect_pads
			(clearance 0)
		)
		(min_thickness 0.25)
		(keepout
			(tracks not_allowed)
			(vias allowed)
			(pads allowed)
			(copperpour not_allowed)
			(footprints allowed)
		)
		(placement
			(enabled no)
			(sheetname "")
		)
		(fill
			(thermal_gap 0.5)
			(thermal_bridge_width 0.5)
			(island_removal_mode 0)
		)
		(polygon
			(pts
				(xy 84.670138 -23.922482) (xy 85.228938 -23.922482) (xy 85.228938 -25.725882) (xy 84.670138 -25.725882)
			)
		)
	)
	(zone
		(layer "In12.Cu")
		(hatch none 0.5)
		(connect_pads
			(clearance 0)
		)
		(min_thickness 0.25)
		(keepout
			(tracks not_allowed)
			(vias allowed)
			(pads allowed)
			(copperpour not_allowed)
			(footprints allowed)
		)
		(placement
			(enabled no)
			(sheetname "")
		)
		(fill
			(thermal_gap 0.5)
			(thermal_bridge_width 0.5)
			(island_removal_mode 0)
		)
		(polygon
			(pts
				(xy 343.317068 -76.551536) (xy 343.317068 -78.837536) (xy 342.809068 -78.837536) (xy 342.809068 -76.551536)
			)
		)
	)
	(zone
		(layer "In12.Cu")
		(hatch none 0.5)
		(connect_pads
			(clearance 0)
		)
		(min_thickness 0.25)
		(keepout
			(tracks not_allowed)
			(vias allowed)
			(pads allowed)
			(copperpour not_allowed)
			(footprints allowed)
		)
		(placement
			(enabled no)
			(sheetname "")
		)
		(fill
			(thermal_gap 0.5)
			(thermal_bridge_width 0.5)
			(island_removal_mode 0)
		)
		(polygon
			(pts
				(xy 130.56997 -19.322542) (xy 131.12877 -19.322542) (xy 131.12877 -21.125942) (xy 130.56997 -21.125942)
			)
		)
	)
	(zone
		(layer "In12.Cu")
		(hatch none 0.5)
		(connect_pads
			(clearance 0)
		)
		(min_thickness 0.25)
		(keepout
			(tracks not_allowed)
			(vias allowed)
			(pads allowed)
			(copperpour not_allowed)
			(footprints allowed)
		)
		(placement
			(enabled no)
			(sheetname "")
		)
		(fill
			(thermal_gap 0.5)
			(thermal_bridge_width 0.5)
			(island_removal_mode 0)
		)
		(polygon
			(pts
				(xy 74.470006 -23.922482) (xy 75.028806 -23.922482) (xy 75.028806 -25.725882) (xy 74.470006 -25.725882)
			)
		)
	)
	(zone
		(layer "In12.Cu")
		(hatch none 0.5)
		(connect_pads
			(clearance 0)
		)
		(min_thickness 0.25)
		(keepout
			(tracks not_allowed)
			(vias allowed)
			(pads allowed)
			(copperpour not_allowed)
			(footprints allowed)
		)
		(placement
			(enabled no)
			(sheetname "")
		)
		(fill
			(thermal_gap 0.5)
			(thermal_bridge_width 0.5)
			(island_removal_mode 0)
		)
		(polygon
			(pts
				(xy 68.520056 -23.922482) (xy 69.078856 -23.922482) (xy 69.078856 -25.725882) (xy 68.520056 -25.725882)
			)
		)
	)
	(zone
		(layer "In12.Cu")
		(hatch none 0.5)
		(connect_pads
			(clearance 0)
		)
		(min_thickness 0.25)
		(keepout
			(tracks not_allowed)
			(vias allowed)
			(pads allowed)
			(copperpour not_allowed)
			(footprints allowed)
		)
		(placement
			(enabled no)
			(sheetname "")
		)
		(fill
			(thermal_gap 0.5)
			(thermal_bridge_width 0.5)
			(island_removal_mode 0)
		)
		(polygon
			(pts
				(xy 206.32039 -127.374142) (xy 206.87919 -127.374142) (xy 206.87919 -129.177542) (xy 206.32039 -129.177542)
			)
		)
	)
	(zone
		(layer "In12.Cu")
		(hatch none 0.5)
		(connect_pads
			(clearance 0)
		)
		(min_thickness 0.25)
		(keepout
			(tracks not_allowed)
			(vias allowed)
			(pads allowed)
			(copperpour not_allowed)
			(footprints allowed)
		)
		(placement
			(enabled no)
			(sheetname "")
		)
		(fill
			(thermal_gap 0.5)
			(thermal_bridge_width 0.5)
			(island_removal_mode 0)
		)
		(polygon
			(pts
				(xy 88.070182 -0.120142) (xy 88.628982 -0.120142) (xy 88.628982 -1.923542) (xy 88.070182 -1.923542)
			)
		)
	)
	(zone
		(layer "In12.Cu")
		(hatch none 0.5)
		(connect_pads
			(clearance 0)
		)
		(min_thickness 0.25)
		(keepout
			(tracks not_allowed)
			(vias allowed)
			(pads allowed)
			(copperpour not_allowed)
			(footprints allowed)
		)
		(placement
			(enabled no)
			(sheetname "")
		)
		(fill
			(thermal_gap 0.5)
			(thermal_bridge_width 0.5)
			(island_removal_mode 0)
		)
		(polygon
			(pts
				(xy 139.07008 -23.922482) (xy 139.62888 -23.922482) (xy 139.62888 -25.725882) (xy 139.07008 -25.725882)
			)
		)
	)
	(zone
		(layer "In12.Cu")
		(hatch none 0.5)
		(connect_pads
			(clearance 0)
		)
		(min_thickness 0.25)
		(keepout
			(tracks not_allowed)
			(vias allowed)
			(pads allowed)
			(copperpour not_allowed)
			(footprints allowed)
		)
		(placement
			(enabled no)
			(sheetname "")
		)
		(fill
			(thermal_gap 0.5)
			(thermal_bridge_width 0.5)
			(island_removal_mode 0)
		)
		(polygon
			(pts
				(xy 274.320508 -141.575282) (xy 274.879308 -141.575282) (xy 274.879308 -143.378682) (xy 274.320508 -143.378682)
			)
		)
	)
	(zone
		(layer "In12.Cu")
		(hatch none 0.5)
		(connect_pads
			(clearance 0)
		)
		(min_thickness 0.25)
		(keepout
			(tracks not_allowed)
			(vias allowed)
			(pads allowed)
			(copperpour not_allowed)
			(footprints allowed)
		)
		(placement
			(enabled no)
			(sheetname "")
		)
		(fill
			(thermal_gap 0.5)
			(thermal_bridge_width 0.5)
			(island_removal_mode 0)
		)
		(polygon
			(pts
				(xy 279.42032 -4.720082) (xy 279.97912 -4.720082) (xy 279.97912 -6.523482) (xy 279.42032 -6.523482)
			)
		)
	)
	(zone
		(layer "In12.Cu")
		(hatch none 0.5)
		(connect_pads
			(clearance 0)
		)
		(min_thickness 0.25)
		(keepout
			(tracks not_allowed)
			(vias allowed)
			(pads allowed)
			(copperpour not_allowed)
			(footprints allowed)
		)
		(placement
			(enabled no)
			(sheetname "")
		)
		(fill
			(thermal_gap 0.5)
			(thermal_bridge_width 0.5)
			(island_removal_mode 0)
		)
		(polygon
			(pts
				(xy 107.620054 -131.974082) (xy 108.178854 -131.974082) (xy 108.178854 -133.777482) (xy 107.620054 -133.777482)
			)
		)
	)
	(zone
		(layer "In12.Cu")
		(hatch none 0.5)
		(connect_pads
			(clearance 0)
		)
		(min_thickness 0.25)
		(keepout
			(tracks not_allowed)
			(vias allowed)
			(pads allowed)
			(copperpour not_allowed)
			(footprints allowed)
		)
		(placement
			(enabled no)
			(sheetname "")
		)
		(fill
			(thermal_gap 0.5)
			(thermal_bridge_width 0.5)
			(island_removal_mode 0)
		)
		(polygon
			(pts
				(xy 277.720552 -23.922482) (xy 278.279352 -23.922482) (xy 278.279352 -25.725882) (xy 277.720552 -25.725882)
			)
		)
	)
	(zone
		(layer "In12.Cu")
		(hatch none 0.5)
		(connect_pads
			(clearance 0)
		)
		(min_thickness 0.25)
		(keepout
			(tracks not_allowed)
			(vias allowed)
			(pads allowed)
			(copperpour not_allowed)
			(footprints allowed)
		)
		(placement
			(enabled no)
			(sheetname "")
		)
		(fill
			(thermal_gap 0.5)
			(thermal_bridge_width 0.5)
			(island_removal_mode 0)
		)
		(polygon
			(pts
				(xy 271.770602 -131.974082) (xy 272.329402 -131.974082) (xy 272.329402 -133.777482) (xy 271.770602 -133.777482)
			)
		)
	)
	(zone
		(layer "In12.Cu")
		(hatch none 0.5)
		(connect_pads
			(clearance 0)
		)
		(min_thickness 0.25)
		(keepout
			(tracks not_allowed)
			(vias allowed)
			(pads allowed)
			(copperpour not_allowed)
			(footprints allowed)
		)
		(placement
			(enabled no)
			(sheetname "")
		)
		(fill
			(thermal_gap 0.5)
			(thermal_bridge_width 0.5)
			(island_removal_mode 0)
		)
		(polygon
			(pts
				(xy 45.57014 -146.576542) (xy 46.12894 -146.576542) (xy 46.12894 -148.379942) (xy 45.57014 -148.379942)
			)
		)
	)
	(zone
		(layer "In12.Cu")
		(hatch none 0.5)
		(connect_pads
			(clearance 0)
		)
		(min_thickness 0.25)
		(keepout
			(tracks not_allowed)
			(vias allowed)
			(pads allowed)
			(copperpour not_allowed)
			(footprints allowed)
		)
		(placement
			(enabled no)
			(sheetname "")
		)
		(fill
			(thermal_gap 0.5)
			(thermal_bridge_width 0.5)
			(island_removal_mode 0)
		)
		(polygon
			(pts
				(xy 125.469904 -151.176482) (xy 126.028704 -151.176482) (xy 126.028704 -152.979882) (xy 125.469904 -152.979882)
			)
		)
	)
	(zone
		(layer "In12.Cu")
		(hatch none 0.5)
		(connect_pads
			(clearance 0)
		)
		(min_thickness 0.25)
		(keepout
			(tracks not_allowed)
			(vias allowed)
			(pads allowed)
			(copperpour not_allowed)
			(footprints allowed)
		)
		(placement
			(enabled no)
			(sheetname "")
		)
		(fill
			(thermal_gap 0.5)
			(thermal_bridge_width 0.5)
			(island_removal_mode 0)
		)
		(polygon
			(pts
				(xy 213.120478 -14.321282) (xy 213.679278 -14.321282) (xy 213.679278 -16.124682) (xy 213.120478 -16.124682)
			)
		)
	)
	(zone
		(layer "In12.Cu")
		(hatch none 0.5)
		(connect_pads
			(clearance 0)
		)
		(min_thickness 0.25)
		(keepout
			(tracks not_allowed)
			(vias allowed)
			(pads allowed)
			(copperpour not_allowed)
			(footprints allowed)
		)
		(placement
			(enabled no)
			(sheetname "")
		)
		(fill
			(thermal_gap 0.5)
			(thermal_bridge_width 0.5)
			(island_removal_mode 0)
		)
		(polygon
			(pts
				(xy 236.920532 -131.974082) (xy 237.479332 -131.974082) (xy 237.479332 -133.777482) (xy 236.920532 -133.777482)
			)
		)
	)
	(zone
		(layer "In12.Cu")
		(hatch none 0.5)
		(connect_pads
			(clearance 0)
		)
		(min_thickness 0.25)
		(keepout
			(tracks not_allowed)
			(vias allowed)
			(pads allowed)
			(copperpour not_allowed)
			(footprints allowed)
		)
		(placement
			(enabled no)
			(sheetname "")
		)
		(fill
			(thermal_gap 0.5)
			(thermal_bridge_width 0.5)
			(island_removal_mode 0)
		)
		(polygon
			(pts
				(xy 66.820034 -141.575282) (xy 67.378834 -141.575282) (xy 67.378834 -143.378682) (xy 66.820034 -143.378682)
			)
		)
	)
	(zone
		(layer "In12.Cu")
		(hatch none 0.5)
		(connect_pads
			(clearance 0)
		)
		(min_thickness 0.25)
		(keepout
			(tracks not_allowed)
			(vias allowed)
			(pads allowed)
			(copperpour not_allowed)
			(footprints allowed)
		)
		(placement
			(enabled no)
			(sheetname "")
		)
		(fill
			(thermal_gap 0.5)
			(thermal_bridge_width 0.5)
			(island_removal_mode 0)
		)
		(polygon
			(pts
				(xy 304.920396 -0.120142) (xy 305.479196 -0.120142) (xy 305.479196 -1.923542) (xy 304.920396 -1.923542)
			)
		)
	)
	(zone
		(layer "In12.Cu")
		(hatch none 0.5)
		(connect_pads
			(clearance 0)
		)
		(min_thickness 0.25)
		(keepout
			(tracks not_allowed)
			(vias allowed)
			(pads allowed)
			(copperpour not_allowed)
			(footprints allowed)
		)
		(placement
			(enabled no)
			(sheetname "")
		)
		(fill
			(thermal_gap 0.5)
			(thermal_bridge_width 0.5)
			(island_removal_mode 0)
		)
		(polygon
			(pts
				(xy 72.769984 -146.576542) (xy 73.328784 -146.576542) (xy 73.328784 -148.379942) (xy 72.769984 -148.379942)
			)
		)
	)
	(zone
		(layer "In12.Cu")
		(hatch none 0.5)
		(connect_pads
			(clearance 0)
		)
		(min_thickness 0.25)
		(keepout
			(tracks not_allowed)
			(vias allowed)
			(pads allowed)
			(copperpour not_allowed)
			(footprints allowed)
		)
		(placement
			(enabled no)
			(sheetname "")
		)
		(fill
			(thermal_gap 0.5)
			(thermal_bridge_width 0.5)
			(island_removal_mode 0)
		)
		(polygon
			(pts
				(xy 82.970116 -9.721342) (xy 83.528916 -9.721342) (xy 83.528916 -11.524742) (xy 82.970116 -11.524742)
			)
		)
	)
	(zone
		(layer "In12.Cu")
		(hatch none 0.5)
		(connect_pads
			(clearance 0)
		)
		(min_thickness 0.25)
		(keepout
			(tracks not_allowed)
			(vias allowed)
			(pads allowed)
			(copperpour not_allowed)
			(footprints allowed)
		)
		(placement
			(enabled no)
			(sheetname "")
		)
		(fill
			(thermal_gap 0.5)
			(thermal_bridge_width 0.5)
			(island_removal_mode 0)
		)
		(polygon
			(pts
				(xy 111.020098 -23.922482) (xy 111.578898 -23.922482) (xy 111.578898 -25.725882) (xy 111.020098 -25.725882)
			)
		)
	)
	(zone
		(layer "In12.Cu")
		(hatch none 0.5)
		(connect_pads
			(clearance 0)
		)
		(min_thickness 0.25)
		(keepout
			(tracks not_allowed)
			(vias allowed)
			(pads allowed)
			(copperpour not_allowed)
			(footprints allowed)
		)
		(placement
			(enabled no)
			(sheetname "")
		)
		(fill
			(thermal_gap 0.5)
			(thermal_bridge_width 0.5)
			(island_removal_mode 0)
		)
		(polygon
			(pts
				(xy 295.570402 -127.374142) (xy 296.129202 -127.374142) (xy 296.129202 -129.177542) (xy 295.570402 -129.177542)
			)
		)
	)
	(zone
		(layer "In12.Cu")
		(hatch none 0.5)
		(connect_pads
			(clearance 0)
		)
		(min_thickness 0.25)
		(keepout
			(tracks not_allowed)
			(vias allowed)
			(pads allowed)
			(copperpour not_allowed)
			(footprints allowed)
		)
		(placement
			(enabled no)
			(sheetname "")
		)
		(fill
			(thermal_gap 0.5)
			(thermal_bridge_width 0.5)
			(island_removal_mode 0)
		)
		(polygon
			(pts
				(xy 59.170062 -151.176482) (xy 59.728862 -151.176482) (xy 59.728862 -152.979882) (xy 59.170062 -152.979882)
			)
		)
	)
	(zone
		(layer "In12.Cu")
		(hatch none 0.5)
		(connect_pads
			(clearance 0)
		)
		(min_thickness 0.25)
		(keepout
			(tracks not_allowed)
			(vias allowed)
			(pads allowed)
			(copperpour not_allowed)
			(footprints allowed)
		)
		(placement
			(enabled no)
			(sheetname "")
		)
		(fill
			(thermal_gap 0.5)
			(thermal_bridge_width 0.5)
			(island_removal_mode 0)
		)
		(polygon
			(pts
				(xy 230.120444 -23.922482) (xy 230.679244 -23.922482) (xy 230.679244 -25.725882) (xy 230.120444 -25.725882)
			)
		)
	)
	(zone
		(layer "In12.Cu")
		(hatch none 0.5)
		(connect_pads
			(clearance 0)
		)
		(min_thickness 0.25)
		(keepout
			(tracks not_allowed)
			(vias allowed)
			(pads allowed)
			(copperpour not_allowed)
			(footprints allowed)
		)
		(placement
			(enabled no)
			(sheetname "")
		)
		(fill
			(thermal_gap 0.5)
			(thermal_bridge_width 0.5)
			(island_removal_mode 0)
		)
		(polygon
			(pts
				(xy 254.770382 -146.576542) (xy 255.329182 -146.576542) (xy 255.329182 -148.379942) (xy 254.770382 -148.379942)
			)
		)
	)
	(zone
		(layer "In12.Cu")
		(hatch none 0.5)
		(connect_pads
			(clearance 0)
		)
		(min_thickness 0.25)
		(keepout
			(tracks not_allowed)
			(vias allowed)
			(pads allowed)
			(copperpour not_allowed)
			(footprints allowed)
		)
		(placement
			(enabled no)
			(sheetname "")
		)
		(fill
			(thermal_gap 0.5)
			(thermal_bridge_width 0.5)
			(island_removal_mode 0)
		)
		(polygon
			(pts
				(xy 256.470404 -23.922482) (xy 257.029204 -23.922482) (xy 257.029204 -25.725882) (xy 256.470404 -25.725882)
			)
		)
	)
	(zone
		(layer "In12.Cu")
		(hatch none 0.5)
		(connect_pads
			(clearance 0)
		)
		(min_thickness 0.25)
		(keepout
			(tracks not_allowed)
			(vias allowed)
			(pads allowed)
			(copperpour not_allowed)
			(footprints allowed)
		)
		(placement
			(enabled no)
			(sheetname "")
		)
		(fill
			(thermal_gap 0.5)
			(thermal_bridge_width 0.5)
			(island_removal_mode 0)
		)
		(polygon
			(pts
				(xy 115.270026 -19.322542) (xy 115.828826 -19.322542) (xy 115.828826 -21.125942) (xy 115.270026 -21.125942)
			)
		)
	)
	(zone
		(layer "In12.Cu")
		(hatch none 0.5)
		(connect_pads
			(clearance 0)
		)
		(min_thickness 0.25)
		(keepout
			(tracks not_allowed)
			(vias allowed)
			(pads allowed)
			(copperpour not_allowed)
			(footprints allowed)
		)
		(placement
			(enabled no)
			(sheetname "")
		)
		(fill
			(thermal_gap 0.5)
			(thermal_bridge_width 0.5)
			(island_removal_mode 0)
		)
		(polygon
			(pts
				(xy 304.920396 -136.975342) (xy 305.479196 -136.975342) (xy 305.479196 -138.778742) (xy 304.920396 -138.778742)
			)
		)
	)
	(zone
		(layer "In12.Cu")
		(hatch none 0.5)
		(connect_pads
			(clearance 0)
		)
		(min_thickness 0.25)
		(keepout
			(tracks not_allowed)
			(vias allowed)
			(pads allowed)
			(copperpour not_allowed)
			(footprints allowed)
		)
		(placement
			(enabled no)
			(sheetname "")
		)
		(fill
			(thermal_gap 0.5)
			(thermal_bridge_width 0.5)
			(island_removal_mode 0)
		)
		(polygon
			(pts
				(xy 129.720086 -23.922482) (xy 130.278886 -23.922482) (xy 130.278886 -25.725882) (xy 129.720086 -25.725882)
			)
		)
	)
	(zone
		(layer "In12.Cu")
		(hatch none 0.5)
		(connect_pads
			(clearance 0)
		)
		(min_thickness 0.25)
		(keepout
			(tracks not_allowed)
			(vias allowed)
			(pads allowed)
			(copperpour not_allowed)
			(footprints allowed)
		)
		(placement
			(enabled no)
			(sheetname "")
		)
		(fill
			(thermal_gap 0.5)
			(thermal_bridge_width 0.5)
			(island_removal_mode 0)
		)
		(polygon
			(pts
				(xy 106.77017 -141.575282) (xy 107.32897 -141.575282) (xy 107.32897 -143.378682) (xy 106.77017 -143.378682)
			)
		)
	)
	(zone
		(layer "In12.Cu")
		(hatch none 0.5)
		(connect_pads
			(clearance 0)
		)
		(min_thickness 0.25)
		(keepout
			(tracks not_allowed)
			(vias allowed)
			(pads allowed)
			(copperpour not_allowed)
			(footprints allowed)
		)
		(placement
			(enabled no)
			(sheetname "")
		)
		(fill
			(thermal_gap 0.5)
			(thermal_bridge_width 0.5)
			(island_removal_mode 0)
		)
		(polygon
			(pts
				(xy 443.379606 -51.199034) (xy 443.887606 -51.199034) (xy 443.887606 -52.596034) (xy 443.379606 -52.596034)
			)
		)
	)
	(zone
		(layer "In12.Cu")
		(hatch none 0.5)
		(connect_pads
			(clearance 0)
		)
		(min_thickness 0.25)
		(keepout
			(tracks not_allowed)
			(vias allowed)
			(pads allowed)
			(copperpour not_allowed)
			(footprints allowed)
		)
		(placement
			(enabled no)
			(sheetname "")
		)
		(fill
			(thermal_gap 0.5)
			(thermal_bridge_width 0.5)
			(island_removal_mode 0)
		)
		(polygon
			(pts
				(xy 276.02053 -136.975342) (xy 276.57933 -136.975342) (xy 276.57933 -138.778742) (xy 276.02053 -138.778742)
			)
		)
	)
	(zone
		(layer "In12.Cu")
		(hatch none 0.5)
		(connect_pads
			(clearance 0)
		)
		(min_thickness 0.25)
		(keepout
			(tracks not_allowed)
			(vias allowed)
			(pads allowed)
			(copperpour not_allowed)
			(footprints allowed)
		)
		(placement
			(enabled no)
			(sheetname "")
		)
		(fill
			(thermal_gap 0.5)
			(thermal_bridge_width 0.5)
			(island_removal_mode 0)
		)
		(polygon
			(pts
				(xy 222.470472 -151.176482) (xy 223.029272 -151.176482) (xy 223.029272 -152.979882) (xy 222.470472 -152.979882)
			)
		)
	)
	(zone
		(layer "In12.Cu")
		(hatch none 0.5)
		(connect_pads
			(clearance 0)
		)
		(min_thickness 0.25)
		(keepout
			(tracks not_allowed)
			(vias allowed)
			(pads allowed)
			(copperpour not_allowed)
			(footprints allowed)
		)
		(placement
			(enabled no)
			(sheetname "")
		)
		(fill
			(thermal_gap 0.5)
			(thermal_bridge_width 0.5)
			(island_removal_mode 0)
		)
		(polygon
			(pts
				(xy 294.720518 -151.176482) (xy 295.279318 -151.176482) (xy 295.279318 -152.979882) (xy 294.720518 -152.979882)
			)
		)
	)
	(zone
		(layer "In12.Cu")
		(hatch none 0.5)
		(connect_pads
			(clearance 0)
		)
		(min_thickness 0.25)
		(keepout
			(tracks not_allowed)
			(vias allowed)
			(pads allowed)
			(copperpour not_allowed)
			(footprints allowed)
		)
		(placement
			(enabled no)
			(sheetname "")
		)
		(fill
			(thermal_gap 0.5)
			(thermal_bridge_width 0.5)
			(island_removal_mode 0)
		)
		(polygon
			(pts
				(xy 149.269958 -136.975342) (xy 149.828758 -136.975342) (xy 149.828758 -138.778742) (xy 149.269958 -138.778742)
			)
		)
	)
	(zone
		(layer "In12.Cu")
		(hatch none 0.5)
		(connect_pads
			(clearance 0)
		)
		(min_thickness 0.25)
		(keepout
			(tracks not_allowed)
			(vias allowed)
			(pads allowed)
			(copperpour not_allowed)
			(footprints allowed)
		)
		(placement
			(enabled no)
			(sheetname "")
		)
		(fill
			(thermal_gap 0.5)
			(thermal_bridge_width 0.5)
			(island_removal_mode 0)
		)
		(polygon
			(pts
				(xy 466.09 -115.34902) (xy 466.598 -115.34902) (xy 466.598 -116.74602) (xy 466.09 -116.74602)
			)
		)
	)
	(zone
		(layer "In12.Cu")
		(hatch none 0.5)
		(connect_pads
			(clearance 0)
		)
		(min_thickness 0.25)
		(keepout
			(tracks not_allowed)
			(vias allowed)
			(pads allowed)
			(copperpour not_allowed)
			(footprints allowed)
		)
		(placement
			(enabled no)
			(sheetname "")
		)
		(fill
			(thermal_gap 0.5)
			(thermal_bridge_width 0.5)
			(island_removal_mode 0)
		)
		(polygon
			(pts
				(xy 143.320008 -136.975342) (xy 143.878808 -136.975342) (xy 143.878808 -138.778742) (xy 143.320008 -138.778742)
			)
		)
	)
	(zone
		(layer "In12.Cu")
		(hatch none 0.5)
		(connect_pads
			(clearance 0)
		)
		(min_thickness 0.25)
		(keepout
			(tracks not_allowed)
			(vias allowed)
			(pads allowed)
			(copperpour not_allowed)
			(footprints allowed)
		)
		(placement
			(enabled no)
			(sheetname "")
		)
		(fill
			(thermal_gap 0.5)
			(thermal_bridge_width 0.5)
			(island_removal_mode 0)
		)
		(polygon
			(pts
				(xy 115.270026 -9.721342) (xy 115.828826 -9.721342) (xy 115.828826 -11.524742) (xy 115.270026 -11.524742)
			)
		)
	)
	(zone
		(layer "In12.Cu")
		(hatch none 0.5)
		(connect_pads
			(clearance 0)
		)
		(min_thickness 0.25)
		(keepout
			(tracks not_allowed)
			(vias allowed)
			(pads allowed)
			(copperpour not_allowed)
			(footprints allowed)
		)
		(placement
			(enabled no)
			(sheetname "")
		)
		(fill
			(thermal_gap 0.5)
			(thermal_bridge_width 0.5)
			(island_removal_mode 0)
		)
		(polygon
			(pts
				(xy 55.770018 -14.321282) (xy 56.328818 -14.321282) (xy 56.328818 -16.124682) (xy 55.770018 -16.124682)
			)
		)
	)
	(zone
		(layer "In12.Cu")
		(hatch none 0.5)
		(connect_pads
			(clearance 0)
		)
		(min_thickness 0.25)
		(keepout
			(tracks not_allowed)
			(vias allowed)
			(pads allowed)
			(copperpour not_allowed)
			(footprints allowed)
		)
		(placement
			(enabled no)
			(sheetname "")
		)
		(fill
			(thermal_gap 0.5)
			(thermal_bridge_width 0.5)
			(island_removal_mode 0)
		)
		(polygon
			(pts
				(xy 252.220476 -4.720082) (xy 252.779276 -4.720082) (xy 252.779276 -6.523482) (xy 252.220476 -6.523482)
			)
		)
	)
	(zone
		(layer "In12.Cu")
		(hatch none 0.5)
		(connect_pads
			(clearance 0)
		)
		(min_thickness 0.25)
		(keepout
			(tracks not_allowed)
			(vias allowed)
			(pads allowed)
			(copperpour not_allowed)
			(footprints allowed)
		)
		(placement
			(enabled no)
			(sheetname "")
		)
		(fill
			(thermal_gap 0.5)
			(thermal_bridge_width 0.5)
			(island_removal_mode 0)
		)
		(polygon
			(pts
				(xy 287.070546 -23.922482) (xy 287.629346 -23.922482) (xy 287.629346 -25.725882) (xy 287.070546 -25.725882)
			)
		)
	)
	(zone
		(layer "In12.Cu")
		(hatch none 0.5)
		(connect_pads
			(clearance 0)
		)
		(min_thickness 0.25)
		(keepout
			(tracks not_allowed)
			(vias allowed)
			(pads allowed)
			(copperpour not_allowed)
			(footprints allowed)
		)
		(placement
			(enabled no)
			(sheetname "")
		)
		(fill
			(thermal_gap 0.5)
			(thermal_bridge_width 0.5)
			(island_removal_mode 0)
		)
		(polygon
			(pts
				(xy 196.120512 -4.720082) (xy 196.679312 -4.720082) (xy 196.679312 -6.523482) (xy 196.120512 -6.523482)
			)
		)
	)
	(zone
		(layer "In12.Cu")
		(hatch none 0.5)
		(connect_pads
			(clearance 0)
		)
		(min_thickness 0.25)
		(keepout
			(tracks not_allowed)
			(vias allowed)
			(pads allowed)
			(copperpour not_allowed)
			(footprints allowed)
		)
		(placement
			(enabled no)
			(sheetname "")
		)
		(fill
			(thermal_gap 0.5)
			(thermal_bridge_width 0.5)
			(island_removal_mode 0)
		)
		(polygon
			(pts
				(xy 272.620486 -151.176482) (xy 273.179286 -151.176482) (xy 273.179286 -152.979882) (xy 272.620486 -152.979882)
			)
		)
	)
	(zone
		(layer "In12.Cu")
		(hatch none 0.5)
		(connect_pads
			(clearance 0)
		)
		(min_thickness 0.25)
		(keepout
			(tracks not_allowed)
			(vias allowed)
			(pads allowed)
			(copperpour not_allowed)
			(footprints allowed)
		)
		(placement
			(enabled no)
			(sheetname "")
		)
		(fill
			(thermal_gap 0.5)
			(thermal_bridge_width 0.5)
			(island_removal_mode 0)
		)
		(polygon
			(pts
				(xy 307.470302 -131.974082) (xy 308.029102 -131.974082) (xy 308.029102 -133.777482) (xy 307.470302 -133.777482)
			)
		)
	)
	(zone
		(layer "In12.Cu")
		(hatch none 0.5)
		(connect_pads
			(clearance 0)
		)
		(min_thickness 0.25)
		(keepout
			(tracks not_allowed)
			(vias allowed)
			(pads allowed)
			(copperpour not_allowed)
			(footprints allowed)
		)
		(placement
			(enabled no)
			(sheetname "")
		)
		(fill
			(thermal_gap 0.5)
			(thermal_bridge_width 0.5)
			(island_removal_mode 0)
		)
		(polygon
			(pts
				(xy 56.620156 -146.576542) (xy 57.178956 -146.576542) (xy 57.178956 -148.379942) (xy 56.620156 -148.379942)
			)
		)
	)
	(zone
		(layer "In12.Cu")
		(hatch none 0.5)
		(connect_pads
			(clearance 0)
		)
		(min_thickness 0.25)
		(keepout
			(tracks not_allowed)
			(vias allowed)
			(pads allowed)
			(copperpour not_allowed)
			(footprints allowed)
		)
		(placement
			(enabled no)
			(sheetname "")
		)
		(fill
			(thermal_gap 0.5)
			(thermal_bridge_width 0.5)
			(island_removal_mode 0)
		)
		(polygon
			(pts
				(xy 249.67057 -4.720082) (xy 250.22937 -4.720082) (xy 250.22937 -6.523482) (xy 249.67057 -6.523482)
			)
		)
	)
	(zone
		(layer "In12.Cu")
		(hatch none 0.5)
		(connect_pads
			(clearance 0)
		)
		(min_thickness 0.25)
		(keepout
			(tracks not_allowed)
			(vias allowed)
			(pads allowed)
			(copperpour not_allowed)
			(footprints allowed)
		)
		(placement
			(enabled no)
			(sheetname "")
		)
		(fill
			(thermal_gap 0.5)
			(thermal_bridge_width 0.5)
			(island_removal_mode 0)
		)
		(polygon
			(pts
				(xy 146.720052 -136.975342) (xy 147.278852 -136.975342) (xy 147.278852 -138.778742) (xy 146.720052 -138.778742)
			)
		)
	)
	(zone
		(layer "In12.Cu")
		(hatch none 0.5)
		(connect_pads
			(clearance 0)
		)
		(min_thickness 0.25)
		(keepout
			(tracks not_allowed)
			(vias allowed)
			(pads allowed)
			(copperpour not_allowed)
			(footprints allowed)
		)
		(placement
			(enabled no)
			(sheetname "")
		)
		(fill
			(thermal_gap 0.5)
			(thermal_bridge_width 0.5)
			(island_removal_mode 0)
		)
		(polygon
			(pts
				(xy 71.069962 -136.975342) (xy 71.628762 -136.975342) (xy 71.628762 -138.778742) (xy 71.069962 -138.778742)
			)
		)
	)
	(zone
		(layer "In12.Cu")
		(hatch none 0.5)
		(connect_pads
			(clearance 0)
		)
		(min_thickness 0.25)
		(keepout
			(tracks not_allowed)
			(vias allowed)
			(pads allowed)
			(copperpour not_allowed)
			(footprints allowed)
		)
		(placement
			(enabled no)
			(sheetname "")
		)
		(fill
			(thermal_gap 0.5)
			(thermal_bridge_width 0.5)
			(island_removal_mode 0)
		)
		(polygon
			(pts
				(xy 348.82836 -76.645516) (xy 348.82836 -78.931516) (xy 348.32036 -78.931516) (xy 348.32036 -76.645516)
			)
		)
	)
	(zone
		(layer "In12.Cu")
		(hatch none 0.5)
		(connect_pads
			(clearance 0)
		)
		(min_thickness 0.25)
		(keepout
			(tracks not_allowed)
			(vias allowed)
			(pads allowed)
			(copperpour not_allowed)
			(footprints allowed)
		)
		(placement
			(enabled no)
			(sheetname "")
		)
		(fill
			(thermal_gap 0.5)
			(thermal_bridge_width 0.5)
			(island_removal_mode 0)
		)
		(polygon
			(pts
				(xy 118.67007 -131.974082) (xy 119.22887 -131.974082) (xy 119.22887 -133.777482) (xy 118.67007 -133.777482)
			)
		)
	)
	(zone
		(layer "In12.Cu")
		(hatch none 0.5)
		(connect_pads
			(clearance 0)
		)
		(min_thickness 0.25)
		(keepout
			(tracks not_allowed)
			(vias allowed)
			(pads allowed)
			(copperpour not_allowed)
			(footprints allowed)
		)
		(placement
			(enabled no)
			(sheetname "")
		)
		(fill
			(thermal_gap 0.5)
			(thermal_bridge_width 0.5)
			(island_removal_mode 0)
		)
		(polygon
			(pts
				(xy 277.720552 -19.322542) (xy 278.279352 -19.322542) (xy 278.279352 -21.125942) (xy 277.720552 -21.125942)
			)
		)
	)
	(zone
		(layer "In12.Cu")
		(hatch none 0.5)
		(connect_pads
			(clearance 0)
		)
		(min_thickness 0.25)
		(keepout
			(tracks not_allowed)
			(vias allowed)
			(pads allowed)
			(copperpour not_allowed)
			(footprints allowed)
		)
		(placement
			(enabled no)
			(sheetname "")
		)
		(fill
			(thermal_gap 0.5)
			(thermal_bridge_width 0.5)
			(island_removal_mode 0)
		)
		(polygon
			(pts
				(xy 70.220078 -14.321282) (xy 70.778878 -14.321282) (xy 70.778878 -16.124682) (xy 70.220078 -16.124682)
			)
		)
	)
	(zone
		(layer "In12.Cu")
		(hatch none 0.5)
		(connect_pads
			(clearance 0)
		)
		(min_thickness 0.25)
		(keepout
			(tracks not_allowed)
			(vias allowed)
			(pads allowed)
			(copperpour not_allowed)
			(footprints allowed)
		)
		(placement
			(enabled no)
			(sheetname "")
		)
		(fill
			(thermal_gap 0.5)
			(thermal_bridge_width 0.5)
			(island_removal_mode 0)
		)
		(polygon
			(pts
				(xy 270.07058 -4.720082) (xy 270.62938 -4.720082) (xy 270.62938 -6.523482) (xy 270.07058 -6.523482)
			)
		)
	)
	(zone
		(layer "In12.Cu")
		(hatch none 0.5)
		(connect_pads
			(clearance 0)
		)
		(min_thickness 0.25)
		(keepout
			(tracks not_allowed)
			(vias allowed)
			(pads allowed)
			(copperpour not_allowed)
			(footprints allowed)
		)
		(placement
			(enabled no)
			(sheetname "")
		)
		(fill
			(thermal_gap 0.5)
			(thermal_bridge_width 0.5)
			(island_removal_mode 0)
		)
		(polygon
			(pts
				(xy 105.070148 -19.322542) (xy 105.628948 -19.322542) (xy 105.628948 -21.125942) (xy 105.070148 -21.125942)
			)
		)
	)
	(zone
		(layer "In12.Cu")
		(hatch none 0.5)
		(connect_pads
			(clearance 0)
		)
		(min_thickness 0.25)
		(keepout
			(tracks not_allowed)
			(vias allowed)
			(pads allowed)
			(copperpour not_allowed)
			(footprints allowed)
		)
		(placement
			(enabled no)
			(sheetname "")
		)
		(fill
			(thermal_gap 0.5)
			(thermal_bridge_width 0.5)
			(island_removal_mode 0)
		)
		(polygon
			(pts
				(xy 204.620368 -127.374142) (xy 205.179168 -127.374142) (xy 205.179168 -129.177542) (xy 204.620368 -129.177542)
			)
		)
	)
	(zone
		(layer "In12.Cu")
		(hatch none 0.5)
		(connect_pads
			(clearance 0)
		)
		(min_thickness 0.25)
		(keepout
			(tracks not_allowed)
			(vias allowed)
			(pads allowed)
			(copperpour not_allowed)
			(footprints allowed)
		)
		(placement
			(enabled no)
			(sheetname "")
		)
		(fill
			(thermal_gap 0.5)
			(thermal_bridge_width 0.5)
			(island_removal_mode 0)
		)
		(polygon
			(pts
				(xy 234.370372 -136.975342) (xy 234.929172 -136.975342) (xy 234.929172 -138.778742) (xy 234.370372 -138.778742)
			)
		)
	)
	(zone
		(layer "In12.Cu")
		(hatch none 0.5)
		(connect_pads
			(clearance 0)
		)
		(min_thickness 0.25)
		(keepout
			(tracks not_allowed)
			(vias allowed)
			(pads allowed)
			(copperpour not_allowed)
			(footprints allowed)
		)
		(placement
			(enabled no)
			(sheetname "")
		)
		(fill
			(thermal_gap 0.5)
			(thermal_bridge_width 0.5)
			(island_removal_mode 0)
		)
		(polygon
			(pts
				(xy 145.02003 -127.374142) (xy 145.57883 -127.374142) (xy 145.57883 -129.177542) (xy 145.02003 -129.177542)
			)
		)
	)
	(zone
		(layer "In12.Cu")
		(hatch none 0.5)
		(connect_pads
			(clearance 0)
		)
		(min_thickness 0.25)
		(keepout
			(tracks not_allowed)
			(vias allowed)
			(pads allowed)
			(copperpour not_allowed)
			(footprints allowed)
		)
		(placement
			(enabled no)
			(sheetname "")
		)
		(fill
			(thermal_gap 0.5)
			(thermal_bridge_width 0.5)
			(island_removal_mode 0)
		)
		(polygon
			(pts
				(xy 78.719934 -19.322542) (xy 79.278734 -19.322542) (xy 79.278734 -21.125942) (xy 78.719934 -21.125942)
			)
		)
	)
	(zone
		(layer "In12.Cu")
		(hatch none 0.5)
		(connect_pads
			(clearance 0)
		)
		(min_thickness 0.25)
		(keepout
			(tracks not_allowed)
			(vias allowed)
			(pads allowed)
			(copperpour not_allowed)
			(footprints allowed)
		)
		(placement
			(enabled no)
			(sheetname "")
		)
		(fill
			(thermal_gap 0.5)
			(thermal_bridge_width 0.5)
			(island_removal_mode 0)
		)
		(polygon
			(pts
				(xy 124.62002 -146.576542) (xy 125.17882 -146.576542) (xy 125.17882 -148.379942) (xy 124.62002 -148.379942)
			)
		)
	)
	(zone
		(layer "In12.Cu")
		(hatch none 0.5)
		(connect_pads
			(clearance 0)
		)
		(min_thickness 0.25)
		(keepout
			(tracks not_allowed)
			(vias allowed)
			(pads allowed)
			(copperpour not_allowed)
			(footprints allowed)
		)
		(placement
			(enabled no)
			(sheetname "")
		)
		(fill
			(thermal_gap 0.5)
			(thermal_bridge_width 0.5)
			(island_removal_mode 0)
		)
		(polygon
			(pts
				(xy 48.96993 -9.721342) (xy 49.52873 -9.721342) (xy 49.52873 -11.524742) (xy 48.96993 -11.524742)
			)
		)
	)
	(zone
		(layer "In12.Cu")
		(hatch none 0.5)
		(connect_pads
			(clearance 0)
		)
		(min_thickness 0.25)
		(keepout
			(tracks not_allowed)
			(vias allowed)
			(pads allowed)
			(copperpour not_allowed)
			(footprints allowed)
		)
		(placement
			(enabled no)
			(sheetname "")
		)
		(fill
			(thermal_gap 0.5)
			(thermal_bridge_width 0.5)
			(island_removal_mode 0)
		)
		(polygon
			(pts
				(xy 118.67007 -136.975342) (xy 119.22887 -136.975342) (xy 119.22887 -138.778742) (xy 118.67007 -138.778742)
			)
		)
	)
	(zone
		(layer "In12.Cu")
		(hatch none 0.5)
		(connect_pads
			(clearance 0)
		)
		(min_thickness 0.25)
		(keepout
			(tracks not_allowed)
			(vias allowed)
			(pads allowed)
			(copperpour not_allowed)
			(footprints allowed)
		)
		(placement
			(enabled no)
			(sheetname "")
		)
		(fill
			(thermal_gap 0.5)
			(thermal_bridge_width 0.5)
			(island_removal_mode 0)
		)
		(polygon
			(pts
				(xy 267.52042 -4.720082) (xy 268.07922 -4.720082) (xy 268.07922 -6.523482) (xy 267.52042 -6.523482)
			)
		)
	)
	(zone
		(layer "In12.Cu")
		(hatch none 0.5)
		(connect_pads
			(clearance 0)
		)
		(min_thickness 0.25)
		(keepout
			(tracks not_allowed)
			(vias allowed)
			(pads allowed)
			(copperpour not_allowed)
			(footprints allowed)
		)
		(placement
			(enabled no)
			(sheetname "")
		)
		(fill
			(thermal_gap 0.5)
			(thermal_bridge_width 0.5)
			(island_removal_mode 0)
		)
		(polygon
			(pts
				(xy 247.12041 -23.922482) (xy 247.67921 -23.922482) (xy 247.67921 -25.725882) (xy 247.12041 -25.725882)
			)
		)
	)
	(zone
		(layer "In12.Cu")
		(hatch none 0.5)
		(connect_pads
			(clearance 0)
		)
		(min_thickness 0.25)
		(keepout
			(tracks not_allowed)
			(vias allowed)
			(pads allowed)
			(copperpour not_allowed)
			(footprints allowed)
		)
		(placement
			(enabled no)
			(sheetname "")
		)
		(fill
			(thermal_gap 0.5)
			(thermal_bridge_width 0.5)
			(island_removal_mode 0)
		)
		(polygon
			(pts
				(xy 282.820364 -4.720082) (xy 283.379164 -4.720082) (xy 283.379164 -6.523482) (xy 282.820364 -6.523482)
			)
		)
	)
	(zone
		(layer "In12.Cu")
		(hatch none 0.5)
		(connect_pads
			(clearance 0)
		)
		(min_thickness 0.25)
		(keepout
			(tracks not_allowed)
			(vias allowed)
			(pads allowed)
			(copperpour not_allowed)
			(footprints allowed)
		)
		(placement
			(enabled no)
			(sheetname "")
		)
		(fill
			(thermal_gap 0.5)
			(thermal_bridge_width 0.5)
			(island_removal_mode 0)
		)
		(polygon
			(pts
				(xy 62.570106 -14.321282) (xy 63.128906 -14.321282) (xy 63.128906 -16.124682) (xy 62.570106 -16.124682)
			)
		)
	)
	(zone
		(layer "In12.Cu")
		(hatch none 0.5)
		(connect_pads
			(clearance 0)
		)
		(min_thickness 0.25)
		(keepout
			(tracks not_allowed)
			(vias allowed)
			(pads allowed)
			(copperpour not_allowed)
			(footprints allowed)
		)
		(placement
			(enabled no)
			(sheetname "")
		)
		(fill
			(thermal_gap 0.5)
			(thermal_bridge_width 0.5)
			(island_removal_mode 0)
		)
		(polygon
			(pts
				(xy 256.470404 -14.321282) (xy 257.029204 -14.321282) (xy 257.029204 -16.124682) (xy 256.470404 -16.124682)
			)
		)
	)
	(zone
		(layer "In12.Cu")
		(hatch none 0.5)
		(connect_pads
			(clearance 0)
		)
		(min_thickness 0.25)
		(keepout
			(tracks not_allowed)
			(vias allowed)
			(pads allowed)
			(copperpour not_allowed)
			(footprints allowed)
		)
		(placement
			(enabled no)
			(sheetname "")
		)
		(fill
			(thermal_gap 0.5)
			(thermal_bridge_width 0.5)
			(island_removal_mode 0)
		)
		(polygon
			(pts
				(xy 70.220078 -131.974082) (xy 70.778878 -131.974082) (xy 70.778878 -133.777482) (xy 70.220078 -133.777482)
			)
		)
	)
	(zone
		(layer "In12.Cu")
		(hatch none 0.5)
		(connect_pads
			(clearance 0)
		)
		(min_thickness 0.25)
		(keepout
			(tracks not_allowed)
			(vias allowed)
			(pads allowed)
			(copperpour not_allowed)
			(footprints allowed)
		)
		(placement
			(enabled no)
			(sheetname "")
		)
		(fill
			(thermal_gap 0.5)
			(thermal_bridge_width 0.5)
			(island_removal_mode 0)
		)
		(polygon
			(pts
				(xy 55.770018 -23.922482) (xy 56.328818 -23.922482) (xy 56.328818 -25.725882) (xy 55.770018 -25.725882)
			)
		)
	)
	(zone
		(layer "In12.Cu")
		(hatch none 0.5)
		(connect_pads
			(clearance 0)
		)
		(min_thickness 0.25)
		(keepout
			(tracks not_allowed)
			(vias allowed)
			(pads allowed)
			(copperpour not_allowed)
			(footprints allowed)
		)
		(placement
			(enabled no)
			(sheetname "")
		)
		(fill
			(thermal_gap 0.5)
			(thermal_bridge_width 0.5)
			(island_removal_mode 0)
		)
		(polygon
			(pts
				(xy 91.469972 -0.120142) (xy 92.028772 -0.120142) (xy 92.028772 -1.923542) (xy 91.469972 -1.923542)
			)
		)
	)
	(zone
		(layer "In12.Cu")
		(hatch none 0.5)
		(connect_pads
			(clearance 0)
		)
		(min_thickness 0.25)
		(keepout
			(tracks not_allowed)
			(vias allowed)
			(pads allowed)
			(copperpour not_allowed)
			(footprints allowed)
		)
		(placement
			(enabled no)
			(sheetname "")
		)
		(fill
			(thermal_gap 0.5)
			(thermal_bridge_width 0.5)
			(island_removal_mode 0)
		)
		(polygon
			(pts
				(xy 288.770314 -23.922482) (xy 289.329114 -23.922482) (xy 289.329114 -25.725882) (xy 288.770314 -25.725882)
			)
		)
	)
	(zone
		(layer "In12.Cu")
		(hatch none 0.5)
		(connect_pads
			(clearance 0)
		)
		(min_thickness 0.25)
		(keepout
			(tracks not_allowed)
			(vias allowed)
			(pads allowed)
			(copperpour not_allowed)
			(footprints allowed)
		)
		(placement
			(enabled no)
			(sheetname "")
		)
		(fill
			(thermal_gap 0.5)
			(thermal_bridge_width 0.5)
			(island_removal_mode 0)
		)
		(polygon
			(pts
				(xy 130.56997 -136.975342) (xy 131.12877 -136.975342) (xy 131.12877 -138.778742) (xy 130.56997 -138.778742)
			)
		)
	)
	(zone
		(layer "In12.Cu")
		(hatch none 0.5)
		(connect_pads
			(clearance 0)
		)
		(min_thickness 0.25)
		(keepout
			(tracks not_allowed)
			(vias allowed)
			(pads allowed)
			(copperpour not_allowed)
			(footprints allowed)
		)
		(placement
			(enabled no)
			(sheetname "")
		)
		(fill
			(thermal_gap 0.5)
			(thermal_bridge_width 0.5)
			(island_removal_mode 0)
		)
		(polygon
			(pts
				(xy 217.370406 -146.576542) (xy 217.929206 -146.576542) (xy 217.929206 -148.379942) (xy 217.370406 -148.379942)
			)
		)
	)
	(zone
		(layer "In12.Cu")
		(hatch none 0.5)
		(connect_pads
			(clearance 0)
		)
		(min_thickness 0.25)
		(keepout
			(tracks not_allowed)
			(vias allowed)
			(pads allowed)
			(copperpour not_allowed)
			(footprints allowed)
		)
		(placement
			(enabled no)
			(sheetname "")
		)
		(fill
			(thermal_gap 0.5)
			(thermal_bridge_width 0.5)
			(island_removal_mode 0)
		)
		(polygon
			(pts
				(xy 124.62002 -9.721342) (xy 125.17882 -9.721342) (xy 125.17882 -11.524742) (xy 124.62002 -11.524742)
			)
		)
	)
	(zone
		(layer "In12.Cu")
		(hatch none 0.5)
		(connect_pads
			(clearance 0)
		)
		(min_thickness 0.25)
		(keepout
			(tracks not_allowed)
			(vias allowed)
			(pads allowed)
			(copperpour not_allowed)
			(footprints allowed)
		)
		(placement
			(enabled no)
			(sheetname "")
		)
		(fill
			(thermal_gap 0.5)
			(thermal_bridge_width 0.5)
			(island_removal_mode 0)
		)
		(polygon
			(pts
				(xy 112.72012 -4.720082) (xy 113.27892 -4.720082) (xy 113.27892 -6.523482) (xy 112.72012 -6.523482)
			)
		)
	)
	(zone
		(layer "In12.Cu")
		(hatch none 0.5)
		(connect_pads
			(clearance 0)
		)
		(min_thickness 0.25)
		(keepout
			(tracks not_allowed)
			(vias allowed)
			(pads allowed)
			(copperpour not_allowed)
			(footprints allowed)
		)
		(placement
			(enabled no)
			(sheetname "")
		)
		(fill
			(thermal_gap 0.5)
			(thermal_bridge_width 0.5)
			(island_removal_mode 0)
		)
		(polygon
			(pts
				(xy 252.220476 -9.721342) (xy 252.779276 -9.721342) (xy 252.779276 -11.524742) (xy 252.220476 -11.524742)
			)
		)
	)
	(zone
		(layer "In12.Cu")
		(hatch none 0.5)
		(connect_pads
			(clearance 0)
		)
		(min_thickness 0.25)
		(keepout
			(tracks not_allowed)
			(vias allowed)
			(pads allowed)
			(copperpour not_allowed)
			(footprints allowed)
		)
		(placement
			(enabled no)
			(sheetname "")
		)
		(fill
			(thermal_gap 0.5)
			(thermal_bridge_width 0.5)
			(island_removal_mode 0)
		)
		(polygon
			(pts
				(xy 228.420422 -19.322542) (xy 228.979222 -19.322542) (xy 228.979222 -21.125942) (xy 228.420422 -21.125942)
			)
		)
	)
	(zone
		(layer "In12.Cu")
		(hatch none 0.5)
		(connect_pads
			(clearance 0)
		)
		(min_thickness 0.25)
		(keepout
			(tracks not_allowed)
			(vias allowed)
			(pads allowed)
			(copperpour not_allowed)
			(footprints allowed)
		)
		(placement
			(enabled no)
			(sheetname "")
		)
		(fill
			(thermal_gap 0.5)
			(thermal_bridge_width 0.5)
			(island_removal_mode 0)
		)
		(polygon
			(pts
				(xy 142.46987 -151.176482) (xy 143.02867 -151.176482) (xy 143.02867 -152.979882) (xy 142.46987 -152.979882)
			)
		)
	)
	(zone
		(layer "In12.Cu")
		(hatch none 0.5)
		(connect_pads
			(clearance 0)
		)
		(min_thickness 0.25)
		(keepout
			(tracks not_allowed)
			(vias allowed)
			(pads allowed)
			(copperpour not_allowed)
			(footprints allowed)
		)
		(placement
			(enabled no)
			(sheetname "")
		)
		(fill
			(thermal_gap 0.5)
			(thermal_bridge_width 0.5)
			(island_removal_mode 0)
		)
		(polygon
			(pts
				(xy 82.119978 -136.975342) (xy 82.678778 -136.975342) (xy 82.678778 -138.778742) (xy 82.119978 -138.778742)
			)
		)
	)
	(zone
		(layer "In12.Cu")
		(hatch none 0.5)
		(connect_pads
			(clearance 0)
		)
		(min_thickness 0.25)
		(keepout
			(tracks not_allowed)
			(vias allowed)
			(pads allowed)
			(copperpour not_allowed)
			(footprints allowed)
		)
		(placement
			(enabled no)
			(sheetname "")
		)
		(fill
			(thermal_gap 0.5)
			(thermal_bridge_width 0.5)
			(island_removal_mode 0)
		)
		(polygon
			(pts
				(xy 273.47037 -19.322542) (xy 274.02917 -19.322542) (xy 274.02917 -21.125942) (xy 273.47037 -21.125942)
			)
		)
	)
	(zone
		(layer "In12.Cu")
		(hatch none 0.5)
		(connect_pads
			(clearance 0)
		)
		(min_thickness 0.25)
		(keepout
			(tracks not_allowed)
			(vias allowed)
			(pads allowed)
			(copperpour not_allowed)
			(footprints allowed)
		)
		(placement
			(enabled no)
			(sheetname "")
		)
		(fill
			(thermal_gap 0.5)
			(thermal_bridge_width 0.5)
			(island_removal_mode 0)
		)
		(polygon
			(pts
				(xy 239.470438 -23.922482) (xy 240.029238 -23.922482) (xy 240.029238 -25.725882) (xy 239.470438 -25.725882)
			)
		)
	)
	(zone
		(layer "In12.Cu")
		(hatch none 0.5)
		(connect_pads
			(clearance 0)
		)
		(min_thickness 0.25)
		(keepout
			(tracks not_allowed)
			(vias allowed)
			(pads allowed)
			(copperpour not_allowed)
			(footprints allowed)
		)
		(placement
			(enabled no)
			(sheetname "")
		)
		(fill
			(thermal_gap 0.5)
			(thermal_bridge_width 0.5)
			(island_removal_mode 0)
		)
		(polygon
			(pts
				(xy 143.320008 -9.721342) (xy 143.878808 -9.721342) (xy 143.878808 -11.524742) (xy 143.320008 -11.524742)
			)
		)
	)
	(zone
		(layer "In12.Cu")
		(hatch none 0.5)
		(connect_pads
			(clearance 0)
		)
		(min_thickness 0.25)
		(keepout
			(tracks not_allowed)
			(vias allowed)
			(pads allowed)
			(copperpour not_allowed)
			(footprints allowed)
		)
		(placement
			(enabled no)
			(sheetname "")
		)
		(fill
			(thermal_gap 0.5)
			(thermal_bridge_width 0.5)
			(island_removal_mode 0)
		)
		(polygon
			(pts
				(xy 443.611 -115.34902) (xy 444.119 -115.34902) (xy 444.119 -116.74602) (xy 443.611 -116.74602)
			)
		)
	)
	(zone
		(layer "In12.Cu")
		(hatch none 0.5)
		(connect_pads
			(clearance 0)
		)
		(min_thickness 0.25)
		(keepout
			(tracks not_allowed)
			(vias allowed)
			(pads allowed)
			(copperpour not_allowed)
			(footprints allowed)
		)
		(placement
			(enabled no)
			(sheetname "")
		)
		(fill
			(thermal_gap 0.5)
			(thermal_bridge_width 0.5)
			(island_removal_mode 0)
		)
		(polygon
			(pts
				(xy 54.069996 -146.576542) (xy 54.628796 -146.576542) (xy 54.628796 -148.379942) (xy 54.069996 -148.379942)
			)
		)
	)
	(zone
		(layer "In12.Cu")
		(hatch none 0.5)
		(connect_pads
			(clearance 0)
		)
		(min_thickness 0.25)
		(keepout
			(tracks not_allowed)
			(vias allowed)
			(pads allowed)
			(copperpour not_allowed)
			(footprints allowed)
		)
		(placement
			(enabled no)
			(sheetname "")
		)
		(fill
			(thermal_gap 0.5)
			(thermal_bridge_width 0.5)
			(island_removal_mode 0)
		)
		(polygon
			(pts
				(xy 145.02003 -146.576542) (xy 145.57883 -146.576542) (xy 145.57883 -148.379942) (xy 145.02003 -148.379942)
			)
		)
	)
	(zone
		(layer "In12.Cu")
		(hatch none 0.5)
		(connect_pads
			(clearance 0)
		)
		(min_thickness 0.25)
		(keepout
			(tracks not_allowed)
			(vias allowed)
			(pads allowed)
			(copperpour not_allowed)
			(footprints allowed)
		)
		(placement
			(enabled no)
			(sheetname "")
		)
		(fill
			(thermal_gap 0.5)
			(thermal_bridge_width 0.5)
			(island_removal_mode 0)
		)
		(polygon
			(pts
				(xy 63.41999 -4.720082) (xy 63.97879 -4.720082) (xy 63.97879 -6.523482) (xy 63.41999 -6.523482)
			)
		)
	)
	(zone
		(layer "In12.Cu")
		(hatch none 0.5)
		(connect_pads
			(clearance 0)
		)
		(min_thickness 0.25)
		(keepout
			(tracks not_allowed)
			(vias allowed)
			(pads allowed)
			(copperpour not_allowed)
			(footprints allowed)
		)
		(placement
			(enabled no)
			(sheetname "")
		)
		(fill
			(thermal_gap 0.5)
			(thermal_bridge_width 0.5)
			(island_removal_mode 0)
		)
		(polygon
			(pts
				(xy 44.720002 -19.322542) (xy 45.278802 -19.322542) (xy 45.278802 -21.125942) (xy 44.720002 -21.125942)
			)
		)
	)
	(zone
		(layer "In12.Cu")
		(hatch none 0.5)
		(connect_pads
			(clearance 0)
		)
		(min_thickness 0.25)
		(keepout
			(tracks not_allowed)
			(vias allowed)
			(pads allowed)
			(copperpour not_allowed)
			(footprints allowed)
		)
		(placement
			(enabled no)
			(sheetname "")
		)
		(fill
			(thermal_gap 0.5)
			(thermal_bridge_width 0.5)
			(island_removal_mode 0)
		)
		(polygon
			(pts
				(xy 60.870084 -131.974082) (xy 61.428884 -131.974082) (xy 61.428884 -133.777482) (xy 60.870084 -133.777482)
			)
		)
	)
	(zone
		(layer "In12.Cu")
		(hatch none 0.5)
		(connect_pads
			(clearance 0)
		)
		(min_thickness 0.25)
		(keepout
			(tracks not_allowed)
			(vias allowed)
			(pads allowed)
			(copperpour not_allowed)
			(footprints allowed)
		)
		(placement
			(enabled no)
			(sheetname "")
		)
		(fill
			(thermal_gap 0.5)
			(thermal_bridge_width 0.5)
			(island_removal_mode 0)
		)
		(polygon
			(pts
				(xy 82.119978 -141.575282) (xy 82.678778 -141.575282) (xy 82.678778 -143.378682) (xy 82.119978 -143.378682)
			)
		)
	)
	(zone
		(layer "In12.Cu")
		(hatch none 0.5)
		(connect_pads
			(clearance 0)
		)
		(min_thickness 0.25)
		(keepout
			(tracks not_allowed)
			(vias allowed)
			(pads allowed)
			(copperpour not_allowed)
			(footprints allowed)
		)
		(placement
			(enabled no)
			(sheetname "")
		)
		(fill
			(thermal_gap 0.5)
			(thermal_bridge_width 0.5)
			(island_removal_mode 0)
		)
		(polygon
			(pts
				(xy 224.170494 -131.974082) (xy 224.729294 -131.974082) (xy 224.729294 -133.777482) (xy 224.170494 -133.777482)
			)
		)
	)
	(zone
		(layer "In12.Cu")
		(hatch none 0.5)
		(connect_pads
			(clearance 0)
		)
		(min_thickness 0.25)
		(keepout
			(tracks not_allowed)
			(vias allowed)
			(pads allowed)
			(copperpour not_allowed)
			(footprints allowed)
		)
		(placement
			(enabled no)
			(sheetname "")
		)
		(fill
			(thermal_gap 0.5)
			(thermal_bridge_width 0.5)
			(island_removal_mode 0)
		)
		(polygon
			(pts
				(xy 247.12041 -146.576542) (xy 247.67921 -146.576542) (xy 247.67921 -148.379942) (xy 247.12041 -148.379942)
			)
		)
	)
	(zone
		(layer "In12.Cu")
		(hatch none 0.5)
		(connect_pads
			(clearance 0)
		)
		(min_thickness 0.25)
		(keepout
			(tracks not_allowed)
			(vias allowed)
			(pads allowed)
			(copperpour not_allowed)
			(footprints allowed)
		)
		(placement
			(enabled no)
			(sheetname "")
		)
		(fill
			(thermal_gap 0.5)
			(thermal_bridge_width 0.5)
			(island_removal_mode 0)
		)
		(polygon
			(pts
				(xy 54.069996 -23.922482) (xy 54.628796 -23.922482) (xy 54.628796 -25.725882) (xy 54.069996 -25.725882)
			)
		)
	)
	(zone
		(layer "In12.Cu")
		(hatch none 0.5)
		(connect_pads
			(clearance 0)
		)
		(min_thickness 0.25)
		(keepout
			(tracks not_allowed)
			(vias allowed)
			(pads allowed)
			(copperpour not_allowed)
			(footprints allowed)
		)
		(placement
			(enabled no)
			(sheetname "")
		)
		(fill
			(thermal_gap 0.5)
			(thermal_bridge_width 0.5)
			(island_removal_mode 0)
		)
		(polygon
			(pts
				(xy 87.220044 -4.720082) (xy 87.778844 -4.720082) (xy 87.778844 -6.523482) (xy 87.220044 -6.523482)
			)
		)
	)
	(zone
		(layer "In12.Cu")
		(hatch none 0.5)
		(connect_pads
			(clearance 0)
		)
		(min_thickness 0.25)
		(keepout
			(tracks not_allowed)
			(vias allowed)
			(pads allowed)
			(copperpour not_allowed)
			(footprints allowed)
		)
		(placement
			(enabled no)
			(sheetname "")
		)
		(fill
			(thermal_gap 0.5)
			(thermal_bridge_width 0.5)
			(island_removal_mode 0)
		)
		(polygon
			(pts
				(xy 139.919964 -0.120142) (xy 140.478764 -0.120142) (xy 140.478764 -1.923542) (xy 139.919964 -1.923542)
			)
		)
	)
	(zone
		(layer "In12.Cu")
		(hatch none 0.5)
		(connect_pads
			(clearance 0)
		)
		(min_thickness 0.25)
		(keepout
			(tracks not_allowed)
			(vias allowed)
			(pads allowed)
			(copperpour not_allowed)
			(footprints allowed)
		)
		(placement
			(enabled no)
			(sheetname "")
		)
		(fill
			(thermal_gap 0.5)
			(thermal_bridge_width 0.5)
			(island_removal_mode 0)
		)
		(polygon
			(pts
				(xy 122.070114 -151.176482) (xy 122.628914 -151.176482) (xy 122.628914 -152.979882) (xy 122.070114 -152.979882)
			)
		)
	)
	(zone
		(layer "In12.Cu")
		(hatch none 0.5)
		(connect_pads
			(clearance 0)
		)
		(min_thickness 0.25)
		(keepout
			(tracks not_allowed)
			(vias allowed)
			(pads allowed)
			(copperpour not_allowed)
			(footprints allowed)
		)
		(placement
			(enabled no)
			(sheetname "")
		)
		(fill
			(thermal_gap 0.5)
			(thermal_bridge_width 0.5)
			(island_removal_mode 0)
		)
		(polygon
			(pts
				(xy 111.020098 -9.721342) (xy 111.578898 -9.721342) (xy 111.578898 -11.524742) (xy 111.020098 -11.524742)
			)
		)
	)
	(zone
		(layer "In12.Cu")
		(hatch none 0.5)
		(connect_pads
			(clearance 0)
		)
		(min_thickness 0.25)
		(keepout
			(tracks not_allowed)
			(vias allowed)
			(pads allowed)
			(copperpour not_allowed)
			(footprints allowed)
		)
		(placement
			(enabled no)
			(sheetname "")
		)
		(fill
			(thermal_gap 0.5)
			(thermal_bridge_width 0.5)
			(island_removal_mode 0)
		)
		(polygon
			(pts
				(xy 131.420108 -14.321282) (xy 131.978908 -14.321282) (xy 131.978908 -16.124682) (xy 131.420108 -16.124682)
			)
		)
	)
	(zone
		(layer "In12.Cu")
		(hatch none 0.5)
		(connect_pads
			(clearance 0)
		)
		(min_thickness 0.25)
		(keepout
			(tracks not_allowed)
			(vias allowed)
			(pads allowed)
			(copperpour not_allowed)
			(footprints allowed)
		)
		(placement
			(enabled no)
			(sheetname "")
		)
		(fill
			(thermal_gap 0.5)
			(thermal_bridge_width 0.5)
			(island_removal_mode 0)
		)
		(polygon
			(pts
				(xy 254.770382 -151.176482) (xy 255.329182 -151.176482) (xy 255.329182 -152.979882) (xy 254.770382 -152.979882)
			)
		)
	)
	(zone
		(layer "In12.Cu")
		(hatch none 0.5)
		(connect_pads
			(clearance 0)
		)
		(min_thickness 0.25)
		(keepout
			(tracks not_allowed)
			(vias allowed)
			(pads allowed)
			(copperpour not_allowed)
			(footprints allowed)
		)
		(placement
			(enabled no)
			(sheetname "")
		)
		(fill
			(thermal_gap 0.5)
			(thermal_bridge_width 0.5)
			(island_removal_mode 0)
		)
		(polygon
			(pts
				(xy 228.420422 -127.374142) (xy 228.979222 -127.374142) (xy 228.979222 -129.177542) (xy 228.420422 -129.177542)
			)
		)
	)
	(zone
		(layer "In12.Cu")
		(hatch none 0.5)
		(connect_pads
			(clearance 0)
		)
		(min_thickness 0.25)
		(keepout
			(tracks not_allowed)
			(vias allowed)
			(pads allowed)
			(copperpour not_allowed)
			(footprints allowed)
		)
		(placement
			(enabled no)
			(sheetname "")
		)
		(fill
			(thermal_gap 0.5)
			(thermal_bridge_width 0.5)
			(island_removal_mode 0)
		)
		(polygon
			(pts
				(xy 145.02003 -136.975342) (xy 145.57883 -136.975342) (xy 145.57883 -138.778742) (xy 145.02003 -138.778742)
			)
		)
	)
	(zone
		(layer "In12.Cu")
		(hatch none 0.5)
		(connect_pads
			(clearance 0)
		)
		(min_thickness 0.25)
		(keepout
			(tracks not_allowed)
			(vias allowed)
			(pads allowed)
			(copperpour not_allowed)
			(footprints allowed)
		)
		(placement
			(enabled no)
			(sheetname "")
		)
		(fill
			(thermal_gap 0.5)
			(thermal_bridge_width 0.5)
			(island_removal_mode 0)
		)
		(polygon
			(pts
				(xy 265.820398 -131.974082) (xy 266.379198 -131.974082) (xy 266.379198 -133.777482) (xy 265.820398 -133.777482)
			)
		)
	)
	(zone
		(layer "In12.Cu")
		(hatch none 0.5)
		(connect_pads
			(clearance 0)
		)
		(min_thickness 0.25)
		(keepout
			(tracks not_allowed)
			(vias allowed)
			(pads allowed)
			(copperpour not_allowed)
			(footprints allowed)
		)
		(placement
			(enabled no)
			(sheetname "")
		)
		(fill
			(thermal_gap 0.5)
			(thermal_bridge_width 0.5)
			(island_removal_mode 0)
		)
		(polygon
			(pts
				(xy 145.869914 -14.321282) (xy 146.428714 -14.321282) (xy 146.428714 -16.124682) (xy 145.869914 -16.124682)
			)
		)
	)
	(zone
		(layer "In12.Cu")
		(hatch none 0.5)
		(connect_pads
			(clearance 0)
		)
		(min_thickness 0.25)
		(keepout
			(tracks not_allowed)
			(vias allowed)
			(pads allowed)
			(copperpour not_allowed)
			(footprints allowed)
		)
		(placement
			(enabled no)
			(sheetname "")
		)
		(fill
			(thermal_gap 0.5)
			(thermal_bridge_width 0.5)
			(island_removal_mode 0)
		)
		(polygon
			(pts
				(xy 275.170392 -9.721342) (xy 275.729192 -9.721342) (xy 275.729192 -11.524742) (xy 275.170392 -11.524742)
			)
		)
	)
	(zone
		(layer "In12.Cu")
		(hatch none 0.5)
		(connect_pads
			(clearance 0)
		)
		(min_thickness 0.25)
		(keepout
			(tracks not_allowed)
			(vias allowed)
			(pads allowed)
			(copperpour not_allowed)
			(footprints allowed)
		)
		(placement
			(enabled no)
			(sheetname "")
		)
		(fill
			(thermal_gap 0.5)
			(thermal_bridge_width 0.5)
			(island_removal_mode 0)
		)
		(polygon
			(pts
				(xy 78.719934 -127.374142) (xy 79.278734 -127.374142) (xy 79.278734 -129.177542) (xy 78.719934 -129.177542)
			)
		)
	)
	(zone
		(layer "In12.Cu")
		(hatch none 0.5)
		(connect_pads
			(clearance 0)
		)
		(min_thickness 0.25)
		(keepout
			(tracks not_allowed)
			(vias allowed)
			(pads allowed)
			(copperpour not_allowed)
			(footprints allowed)
		)
		(placement
			(enabled no)
			(sheetname "")
		)
		(fill
			(thermal_gap 0.5)
			(thermal_bridge_width 0.5)
			(island_removal_mode 0)
		)
		(polygon
			(pts
				(xy 202.070462 -14.321282) (xy 202.629262 -14.321282) (xy 202.629262 -16.124682) (xy 202.070462 -16.124682)
			)
		)
	)
	(zone
		(layer "In12.Cu")
		(hatch none 0.5)
		(connect_pads
			(clearance 0)
		)
		(min_thickness 0.25)
		(keepout
			(tracks not_allowed)
			(vias allowed)
			(pads allowed)
			(copperpour not_allowed)
			(footprints allowed)
		)
		(placement
			(enabled no)
			(sheetname "")
		)
		(fill
			(thermal_gap 0.5)
			(thermal_bridge_width 0.5)
			(island_removal_mode 0)
		)
		(polygon
			(pts
				(xy 109.320076 -23.922482) (xy 109.878876 -23.922482) (xy 109.878876 -25.725882) (xy 109.320076 -25.725882)
			)
		)
	)
	(zone
		(layer "In12.Cu")
		(hatch none 0.5)
		(connect_pads
			(clearance 0)
		)
		(min_thickness 0.25)
		(keepout
			(tracks not_allowed)
			(vias allowed)
			(pads allowed)
			(copperpour not_allowed)
			(footprints allowed)
		)
		(placement
			(enabled no)
			(sheetname "")
		)
		(fill
			(thermal_gap 0.5)
			(thermal_bridge_width 0.5)
			(island_removal_mode 0)
		)
		(polygon
			(pts
				(xy 227.570538 -131.974082) (xy 228.129338 -131.974082) (xy 228.129338 -133.777482) (xy 227.570538 -133.777482)
			)
		)
	)
	(zone
		(layer "In12.Cu")
		(hatch none 0.5)
		(connect_pads
			(clearance 0)
		)
		(min_thickness 0.25)
		(keepout
			(tracks not_allowed)
			(vias allowed)
			(pads allowed)
			(copperpour not_allowed)
			(footprints allowed)
		)
		(placement
			(enabled no)
			(sheetname "")
		)
		(fill
			(thermal_gap 0.5)
			(thermal_bridge_width 0.5)
			(island_removal_mode 0)
		)
		(polygon
			(pts
				(xy 75.320144 -136.975342) (xy 75.878944 -136.975342) (xy 75.878944 -138.778742) (xy 75.320144 -138.778742)
			)
		)
	)
	(zone
		(layer "In12.Cu")
		(hatch none 0.5)
		(connect_pads
			(clearance 0)
		)
		(min_thickness 0.25)
		(keepout
			(tracks not_allowed)
			(vias allowed)
			(pads allowed)
			(copperpour not_allowed)
			(footprints allowed)
		)
		(placement
			(enabled no)
			(sheetname "")
		)
		(fill
			(thermal_gap 0.5)
			(thermal_bridge_width 0.5)
			(island_removal_mode 0)
		)
		(polygon
			(pts
				(xy 267.52042 -23.922482) (xy 268.07922 -23.922482) (xy 268.07922 -25.725882) (xy 267.52042 -25.725882)
			)
		)
	)
	(zone
		(layer "In12.Cu")
		(hatch none 0.5)
		(connect_pads
			(clearance 0)
		)
		(min_thickness 0.25)
		(keepout
			(tracks not_allowed)
			(vias allowed)
			(pads allowed)
			(copperpour not_allowed)
			(footprints allowed)
		)
		(placement
			(enabled no)
			(sheetname "")
		)
		(fill
			(thermal_gap 0.5)
			(thermal_bridge_width 0.5)
			(island_removal_mode 0)
		)
		(polygon
			(pts
				(xy 413.6136 -140.6398) (xy 413.6136 -141.4018) (xy 414.6042 -141.4018) (xy 414.6042 -140.6398)
			)
		)
	)
	(zone
		(layer "In12.Cu")
		(hatch none 0.5)
		(connect_pads
			(clearance 0)
		)
		(min_thickness 0.25)
		(keepout
			(tracks not_allowed)
			(vias allowed)
			(pads allowed)
			(copperpour not_allowed)
			(footprints allowed)
		)
		(placement
			(enabled no)
			(sheetname "")
		)
		(fill
			(thermal_gap 0.5)
			(thermal_bridge_width 0.5)
			(island_removal_mode 0)
		)
		(polygon
			(pts
				(xy 275.170392 -146.576542) (xy 275.729192 -146.576542) (xy 275.729192 -148.379942) (xy 275.170392 -148.379942)
			)
		)
	)
	(zone
		(layer "In12.Cu")
		(hatch none 0.5)
		(connect_pads
			(clearance 0)
		)
		(min_thickness 0.25)
		(keepout
			(tracks not_allowed)
			(vias allowed)
			(pads allowed)
			(copperpour not_allowed)
			(footprints allowed)
		)
		(placement
			(enabled no)
			(sheetname "")
		)
		(fill
			(thermal_gap 0.5)
			(thermal_bridge_width 0.5)
			(island_removal_mode 0)
		)
		(polygon
			(pts
				(xy 48.96993 -0.120142) (xy 49.52873 -0.120142) (xy 49.52873 -1.923542) (xy 48.96993 -1.923542)
			)
		)
	)
	(zone
		(layer "In12.Cu")
		(hatch none 0.5)
		(connect_pads
			(clearance 0)
		)
		(min_thickness 0.25)
		(keepout
			(tracks not_allowed)
			(vias allowed)
			(pads allowed)
			(copperpour not_allowed)
			(footprints allowed)
		)
		(placement
			(enabled no)
			(sheetname "")
		)
		(fill
			(thermal_gap 0.5)
			(thermal_bridge_width 0.5)
			(island_removal_mode 0)
		)
		(polygon
			(pts
				(xy 228.420422 -136.975342) (xy 228.979222 -136.975342) (xy 228.979222 -138.778742) (xy 228.420422 -138.778742)
			)
		)
	)
	(zone
		(layer "In12.Cu")
		(hatch none 0.5)
		(connect_pads
			(clearance 0)
		)
		(min_thickness 0.25)
		(keepout
			(tracks not_allowed)
			(vias allowed)
			(pads allowed)
			(copperpour not_allowed)
			(footprints allowed)
		)
		(placement
			(enabled no)
			(sheetname "")
		)
		(fill
			(thermal_gap 0.5)
			(thermal_bridge_width 0.5)
			(island_removal_mode 0)
		)
		(polygon
			(pts
				(xy 43.870118 -131.974082) (xy 44.428918 -131.974082) (xy 44.428918 -133.777482) (xy 43.870118 -133.777482)
			)
		)
	)
	(zone
		(layer "In12.Cu")
		(hatch none 0.5)
		(connect_pads
			(clearance 0)
		)
		(min_thickness 0.25)
		(keepout
			(tracks not_allowed)
			(vias allowed)
			(pads allowed)
			(copperpour not_allowed)
			(footprints allowed)
		)
		(placement
			(enabled no)
			(sheetname "")
		)
		(fill
			(thermal_gap 0.5)
			(thermal_bridge_width 0.5)
			(island_removal_mode 0)
		)
		(polygon
			(pts
				(xy 86.37016 -14.321282) (xy 86.92896 -14.321282) (xy 86.92896 -16.124682) (xy 86.37016 -16.124682)
			)
		)
	)
	(zone
		(layer "In12.Cu")
		(hatch none 0.5)
		(connect_pads
			(clearance 0)
		)
		(min_thickness 0.25)
		(keepout
			(tracks not_allowed)
			(vias allowed)
			(pads allowed)
			(copperpour not_allowed)
			(footprints allowed)
		)
		(placement
			(enabled no)
			(sheetname "")
		)
		(fill
			(thermal_gap 0.5)
			(thermal_bridge_width 0.5)
			(island_removal_mode 0)
		)
		(polygon
			(pts
				(xy 252.220476 -19.322542) (xy 252.779276 -19.322542) (xy 252.779276 -21.125942) (xy 252.220476 -21.125942)
			)
		)
	)
	(zone
		(layer "In12.Cu")
		(hatch none 0.5)
		(connect_pads
			(clearance 0)
		)
		(min_thickness 0.25)
		(keepout
			(tracks not_allowed)
			(vias allowed)
			(pads allowed)
			(copperpour not_allowed)
			(footprints allowed)
		)
		(placement
			(enabled no)
			(sheetname "")
		)
		(fill
			(thermal_gap 0.5)
			(thermal_bridge_width 0.5)
			(island_removal_mode 0)
		)
		(polygon
			(pts
				(xy 54.920134 -19.322542) (xy 55.478934 -19.322542) (xy 55.478934 -21.125942) (xy 54.920134 -21.125942)
			)
		)
	)
	(zone
		(layer "In12.Cu")
		(hatch none 0.5)
		(connect_pads
			(clearance 0)
		)
		(min_thickness 0.25)
		(keepout
			(tracks not_allowed)
			(vias allowed)
			(pads allowed)
			(copperpour not_allowed)
			(footprints allowed)
		)
		(placement
			(enabled no)
			(sheetname "")
		)
		(fill
			(thermal_gap 0.5)
			(thermal_bridge_width 0.5)
			(island_removal_mode 0)
		)
		(polygon
			(pts
				(xy 230.120444 -4.720082) (xy 230.679244 -4.720082) (xy 230.679244 -6.523482) (xy 230.120444 -6.523482)
			)
		)
	)
	(zone
		(layer "In12.Cu")
		(hatch none 0.5)
		(connect_pads
			(clearance 0)
		)
		(min_thickness 0.25)
		(keepout
			(tracks not_allowed)
			(vias allowed)
			(pads allowed)
			(copperpour not_allowed)
			(footprints allowed)
		)
		(placement
			(enabled no)
			(sheetname "")
		)
		(fill
			(thermal_gap 0.5)
			(thermal_bridge_width 0.5)
			(island_removal_mode 0)
		)
		(polygon
			(pts
				(xy 120.370092 -23.922482) (xy 120.928892 -23.922482) (xy 120.928892 -25.725882) (xy 120.370092 -25.725882)
			)
		)
	)
	(zone
		(layer "In12.Cu")
		(hatch none 0.5)
		(connect_pads
			(clearance 0)
		)
		(min_thickness 0.25)
		(keepout
			(tracks not_allowed)
			(vias allowed)
			(pads allowed)
			(copperpour not_allowed)
			(footprints allowed)
		)
		(placement
			(enabled no)
			(sheetname "")
		)
		(fill
			(thermal_gap 0.5)
			(thermal_bridge_width 0.5)
			(island_removal_mode 0)
		)
		(polygon
			(pts
				(xy 62.570106 -141.575282) (xy 63.128906 -141.575282) (xy 63.128906 -143.378682) (xy 62.570106 -143.378682)
			)
		)
	)
	(zone
		(layer "In12.Cu")
		(hatch none 0.5)
		(connect_pads
			(clearance 0)
		)
		(min_thickness 0.25)
		(keepout
			(tracks not_allowed)
			(vias allowed)
			(pads allowed)
			(copperpour not_allowed)
			(footprints allowed)
		)
		(placement
			(enabled no)
			(sheetname "")
		)
		(fill
			(thermal_gap 0.5)
			(thermal_bridge_width 0.5)
			(island_removal_mode 0)
		)
		(polygon
			(pts
				(xy 309.170324 -151.176482) (xy 309.729124 -151.176482) (xy 309.729124 -152.979882) (xy 309.170324 -152.979882)
			)
		)
	)
	(zone
		(layer "In12.Cu")
		(hatch none 0.5)
		(connect_pads
			(clearance 0)
		)
		(min_thickness 0.25)
		(keepout
			(tracks not_allowed)
			(vias allowed)
			(pads allowed)
			(copperpour not_allowed)
			(footprints allowed)
		)
		(placement
			(enabled no)
			(sheetname "")
		)
		(fill
			(thermal_gap 0.5)
			(thermal_bridge_width 0.5)
			(island_removal_mode 0)
		)
		(polygon
			(pts
				(xy 229.27056 -136.975342) (xy 229.82936 -136.975342) (xy 229.82936 -138.778742) (xy 229.27056 -138.778742)
			)
		)
	)
	(zone
		(layer "In12.Cu")
		(hatch none 0.5)
		(connect_pads
			(clearance 0)
		)
		(min_thickness 0.25)
		(keepout
			(tracks not_allowed)
			(vias allowed)
			(pads allowed)
			(copperpour not_allowed)
			(footprints allowed)
		)
		(placement
			(enabled no)
			(sheetname "")
		)
		(fill
			(thermal_gap 0.5)
			(thermal_bridge_width 0.5)
			(island_removal_mode 0)
		)
		(polygon
			(pts
				(xy 89.76995 -141.575282) (xy 90.32875 -141.575282) (xy 90.32875 -143.378682) (xy 89.76995 -143.378682)
			)
		)
	)
	(zone
		(layer "In12.Cu")
		(hatch none 0.5)
		(connect_pads
			(clearance 0)
		)
		(min_thickness 0.25)
		(keepout
			(tracks not_allowed)
			(vias allowed)
			(pads allowed)
			(copperpour not_allowed)
			(footprints allowed)
		)
		(placement
			(enabled no)
			(sheetname "")
		)
		(fill
			(thermal_gap 0.5)
			(thermal_bridge_width 0.5)
			(island_removal_mode 0)
		)
		(polygon
			(pts
				(xy 119.519954 -0.120142) (xy 120.078754 -0.120142) (xy 120.078754 -1.923542) (xy 119.519954 -1.923542)
			)
		)
	)
	(zone
		(layer "In12.Cu")
		(hatch none 0.5)
		(connect_pads
			(clearance 0)
		)
		(min_thickness 0.25)
		(keepout
			(tracks not_allowed)
			(vias allowed)
			(pads allowed)
			(copperpour not_allowed)
			(footprints allowed)
		)
		(placement
			(enabled no)
			(sheetname "")
		)
		(fill
			(thermal_gap 0.5)
			(thermal_bridge_width 0.5)
			(island_removal_mode 0)
		)
		(polygon
			(pts
				(xy 87.220044 -141.575282) (xy 87.778844 -141.575282) (xy 87.778844 -143.378682) (xy 87.220044 -143.378682)
			)
		)
	)
	(zone
		(layer "In12.Cu")
		(hatch none 0.5)
		(connect_pads
			(clearance 0)
		)
		(min_thickness 0.25)
		(keepout
			(tracks not_allowed)
			(vias allowed)
			(pads allowed)
			(copperpour not_allowed)
			(footprints allowed)
		)
		(placement
			(enabled no)
			(sheetname "")
		)
		(fill
			(thermal_gap 0.5)
			(thermal_bridge_width 0.5)
			(island_removal_mode 0)
		)
		(polygon
			(pts
				(xy 423.799 -142.0368) (xy 424.561 -142.0368) (xy 424.561 -141.0462) (xy 423.799 -141.0462)
			)
		)
	)
	(zone
		(layer "In12.Cu")
		(hatch none 0.5)
		(connect_pads
			(clearance 0)
		)
		(min_thickness 0.25)
		(keepout
			(tracks not_allowed)
			(vias allowed)
			(pads allowed)
			(copperpour not_allowed)
			(footprints allowed)
		)
		(placement
			(enabled no)
			(sheetname "")
		)
		(fill
			(thermal_gap 0.5)
			(thermal_bridge_width 0.5)
			(island_removal_mode 0)
		)
		(polygon
			(pts
				(xy 139.919964 -19.322542) (xy 140.478764 -19.322542) (xy 140.478764 -21.125942) (xy 139.919964 -21.125942)
			)
		)
	)
	(zone
		(layer "In12.Cu")
		(hatch none 0.5)
		(connect_pads
			(clearance 0)
		)
		(min_thickness 0.25)
		(keepout
			(tracks not_allowed)
			(vias allowed)
			(pads allowed)
			(copperpour not_allowed)
			(footprints allowed)
		)
		(placement
			(enabled no)
			(sheetname "")
		)
		(fill
			(thermal_gap 0.5)
			(thermal_bridge_width 0.5)
			(island_removal_mode 0)
		)
		(polygon
			(pts
				(xy 254.770382 -4.720082) (xy 255.329182 -4.720082) (xy 255.329182 -6.523482) (xy 254.770382 -6.523482)
			)
		)
	)
	(zone
		(layer "In12.Cu")
		(hatch none 0.5)
		(connect_pads
			(clearance 0)
		)
		(min_thickness 0.25)
		(keepout
			(tracks not_allowed)
			(vias allowed)
			(pads allowed)
			(copperpour not_allowed)
			(footprints allowed)
		)
		(placement
			(enabled no)
			(sheetname "")
		)
		(fill
			(thermal_gap 0.5)
			(thermal_bridge_width 0.5)
			(island_removal_mode 0)
		)
		(polygon
			(pts
				(xy 422.6052 -153.543) (xy 422.6052 -154.305) (xy 423.5958 -154.305) (xy 423.5958 -153.543)
			)
		)
	)
	(zone
		(layer "In12.Cu")
		(hatch none 0.5)
		(connect_pads
			(clearance 0)
		)
		(min_thickness 0.25)
		(keepout
			(tracks not_allowed)
			(vias allowed)
			(pads allowed)
			(copperpour not_allowed)
			(footprints allowed)
		)
		(placement
			(enabled no)
			(sheetname "")
		)
		(fill
			(thermal_gap 0.5)
			(thermal_bridge_width 0.5)
			(island_removal_mode 0)
		)
		(polygon
			(pts
				(xy 72.769984 -14.321282) (xy 73.328784 -14.321282) (xy 73.328784 -16.124682) (xy 72.769984 -16.124682)
			)
		)
	)
	(zone
		(layer "In12.Cu")
		(hatch none 0.5)
		(connect_pads
			(clearance 0)
		)
		(min_thickness 0.25)
		(keepout
			(tracks not_allowed)
			(vias allowed)
			(pads allowed)
			(copperpour not_allowed)
			(footprints allowed)
		)
		(placement
			(enabled no)
			(sheetname "")
		)
		(fill
			(thermal_gap 0.5)
			(thermal_bridge_width 0.5)
			(island_removal_mode 0)
		)
		(polygon
			(pts
				(xy 214.8205 -131.974082) (xy 215.3793 -131.974082) (xy 215.3793 -133.777482) (xy 214.8205 -133.777482)
			)
		)
	)
	(zone
		(layer "In12.Cu")
		(hatch none 0.5)
		(connect_pads
			(clearance 0)
		)
		(min_thickness 0.25)
		(keepout
			(tracks not_allowed)
			(vias allowed)
			(pads allowed)
			(copperpour not_allowed)
			(footprints allowed)
		)
		(placement
			(enabled no)
			(sheetname "")
		)
		(fill
			(thermal_gap 0.5)
			(thermal_bridge_width 0.5)
			(island_removal_mode 0)
		)
		(polygon
			(pts
				(xy 283.670502 -141.575282) (xy 284.229302 -141.575282) (xy 284.229302 -143.378682) (xy 283.670502 -143.378682)
			)
		)
	)
	(zone
		(layer "In12.Cu")
		(hatch none 0.5)
		(connect_pads
			(clearance 0)
		)
		(min_thickness 0.25)
		(keepout
			(tracks not_allowed)
			(vias allowed)
			(pads allowed)
			(copperpour not_allowed)
			(footprints allowed)
		)
		(placement
			(enabled no)
			(sheetname "")
		)
		(fill
			(thermal_gap 0.5)
			(thermal_bridge_width 0.5)
			(island_removal_mode 0)
		)
		(polygon
			(pts
				(xy 226.7204 -0.120142) (xy 227.2792 -0.120142) (xy 227.2792 -1.923542) (xy 226.7204 -1.923542)
			)
		)
	)
	(zone
		(layer "In12.Cu")
		(hatch none 0.5)
		(connect_pads
			(clearance 0)
		)
		(min_thickness 0.25)
		(keepout
			(tracks not_allowed)
			(vias allowed)
			(pads allowed)
			(copperpour not_allowed)
			(footprints allowed)
		)
		(placement
			(enabled no)
			(sheetname "")
		)
		(fill
			(thermal_gap 0.5)
			(thermal_bridge_width 0.5)
			(island_removal_mode 0)
		)
		(polygon
			(pts
				(xy 298.970446 -136.975342) (xy 299.529246 -136.975342) (xy 299.529246 -138.778742) (xy 298.970446 -138.778742)
			)
		)
	)
	(zone
		(layer "In12.Cu")
		(hatch none 0.5)
		(connect_pads
			(clearance 0)
		)
		(min_thickness 0.25)
		(keepout
			(tracks not_allowed)
			(vias allowed)
			(pads allowed)
			(copperpour not_allowed)
			(footprints allowed)
		)
		(placement
			(enabled no)
			(sheetname "")
		)
		(fill
			(thermal_gap 0.5)
			(thermal_bridge_width 0.5)
			(island_removal_mode 0)
		)
		(polygon
			(pts
				(xy 244.570504 -151.176482) (xy 245.129304 -151.176482) (xy 245.129304 -152.979882) (xy 244.570504 -152.979882)
			)
		)
	)
	(zone
		(layer "In12.Cu")
		(hatch none 0.5)
		(connect_pads
			(clearance 0)
		)
		(min_thickness 0.25)
		(keepout
			(tracks not_allowed)
			(vias allowed)
			(pads allowed)
			(copperpour not_allowed)
			(footprints allowed)
		)
		(placement
			(enabled no)
			(sheetname "")
		)
		(fill
			(thermal_gap 0.5)
			(thermal_bridge_width 0.5)
			(island_removal_mode 0)
		)
		(polygon
			(pts
				(xy 224.170494 -14.321282) (xy 224.729294 -14.321282) (xy 224.729294 -16.124682) (xy 224.170494 -16.124682)
			)
		)
	)
	(zone
		(layer "In12.Cu")
		(hatch none 0.5)
		(connect_pads
			(clearance 0)
		)
		(min_thickness 0.25)
		(keepout
			(tracks not_allowed)
			(vias allowed)
			(pads allowed)
			(copperpour not_allowed)
			(footprints allowed)
		)
		(placement
			(enabled no)
			(sheetname "")
		)
		(fill
			(thermal_gap 0.5)
			(thermal_bridge_width 0.5)
			(island_removal_mode 0)
		)
		(polygon
			(pts
				(xy 226.7204 -127.374142) (xy 227.2792 -127.374142) (xy 227.2792 -129.177542) (xy 226.7204 -129.177542)
			)
		)
	)
	(zone
		(layer "In12.Cu")
		(hatch none 0.5)
		(connect_pads
			(clearance 0)
		)
		(min_thickness 0.25)
		(keepout
			(tracks not_allowed)
			(vias allowed)
			(pads allowed)
			(copperpour not_allowed)
			(footprints allowed)
		)
		(placement
			(enabled no)
			(sheetname "")
		)
		(fill
			(thermal_gap 0.5)
			(thermal_bridge_width 0.5)
			(island_removal_mode 0)
		)
		(polygon
			(pts
				(xy 47.270162 -146.576542) (xy 47.828962 -146.576542) (xy 47.828962 -148.379942) (xy 47.270162 -148.379942)
			)
		)
	)
	(zone
		(layer "In12.Cu")
		(hatch none 0.5)
		(connect_pads
			(clearance 0)
		)
		(min_thickness 0.25)
		(keepout
			(tracks not_allowed)
			(vias allowed)
			(pads allowed)
			(copperpour not_allowed)
			(footprints allowed)
		)
		(placement
			(enabled no)
			(sheetname "")
		)
		(fill
			(thermal_gap 0.5)
			(thermal_bridge_width 0.5)
			(island_removal_mode 0)
		)
		(polygon
			(pts
				(xy 41.319958 -136.975342) (xy 41.878758 -136.975342) (xy 41.878758 -138.778742) (xy 41.319958 -138.778742)
			)
		)
	)
	(zone
		(layer "In12.Cu")
		(hatch none 0.5)
		(connect_pads
			(clearance 0)
		)
		(min_thickness 0.25)
		(keepout
			(tracks not_allowed)
			(vias allowed)
			(pads allowed)
			(copperpour not_allowed)
			(footprints allowed)
		)
		(placement
			(enabled no)
			(sheetname "")
		)
		(fill
			(thermal_gap 0.5)
			(thermal_bridge_width 0.5)
			(island_removal_mode 0)
		)
		(polygon
			(pts
				(xy 208.020412 -136.975342) (xy 208.579212 -136.975342) (xy 208.579212 -138.778742) (xy 208.020412 -138.778742)
			)
		)
	)
	(zone
		(layer "In12.Cu")
		(hatch none 0.5)
		(connect_pads
			(clearance 0)
		)
		(min_thickness 0.25)
		(keepout
			(tracks not_allowed)
			(vias allowed)
			(pads allowed)
			(copperpour not_allowed)
			(footprints allowed)
		)
		(placement
			(enabled no)
			(sheetname "")
		)
		(fill
			(thermal_gap 0.5)
			(thermal_bridge_width 0.5)
			(island_removal_mode 0)
		)
		(polygon
			(pts
				(xy 225.020378 -19.322542) (xy 225.579178 -19.322542) (xy 225.579178 -21.125942) (xy 225.020378 -21.125942)
			)
		)
	)
	(zone
		(layer "In12.Cu")
		(hatch none 0.5)
		(connect_pads
			(clearance 0)
		)
		(min_thickness 0.25)
		(keepout
			(tracks not_allowed)
			(vias allowed)
			(pads allowed)
			(copperpour not_allowed)
			(footprints allowed)
		)
		(placement
			(enabled no)
			(sheetname "")
		)
		(fill
			(thermal_gap 0.5)
			(thermal_bridge_width 0.5)
			(island_removal_mode 0)
		)
		(polygon
			(pts
				(xy 83.82 -4.720082) (xy 84.3788 -4.720082) (xy 84.3788 -6.523482) (xy 83.82 -6.523482)
			)
		)
	)
	(zone
		(layer "In12.Cu")
		(hatch none 0.5)
		(connect_pads
			(clearance 0)
		)
		(min_thickness 0.25)
		(keepout
			(tracks not_allowed)
			(vias allowed)
			(pads allowed)
			(copperpour not_allowed)
			(footprints allowed)
		)
		(placement
			(enabled no)
			(sheetname "")
		)
		(fill
			(thermal_gap 0.5)
			(thermal_bridge_width 0.5)
			(island_removal_mode 0)
		)
		(polygon
			(pts
				(xy 75.320144 -19.322542) (xy 75.878944 -19.322542) (xy 75.878944 -21.125942) (xy 75.320144 -21.125942)
			)
		)
	)
	(zone
		(layer "In12.Cu")
		(hatch none 0.5)
		(connect_pads
			(clearance 0)
		)
		(min_thickness 0.25)
		(keepout
			(tracks not_allowed)
			(vias allowed)
			(pads allowed)
			(copperpour not_allowed)
			(footprints allowed)
		)
		(placement
			(enabled no)
			(sheetname "")
		)
		(fill
			(thermal_gap 0.5)
			(thermal_bridge_width 0.5)
			(island_removal_mode 0)
		)
		(polygon
			(pts
				(xy 74.470006 -141.575282) (xy 75.028806 -141.575282) (xy 75.028806 -143.378682) (xy 74.470006 -143.378682)
			)
		)
	)
	(zone
		(layer "In12.Cu")
		(hatch none 0.5)
		(connect_pads
			(clearance 0)
		)
		(min_thickness 0.25)
		(keepout
			(tracks not_allowed)
			(vias allowed)
			(pads allowed)
			(copperpour not_allowed)
			(footprints allowed)
		)
		(placement
			(enabled no)
			(sheetname "")
		)
		(fill
			(thermal_gap 0.5)
			(thermal_bridge_width 0.5)
			(island_removal_mode 0)
		)
		(polygon
			(pts
				(xy 249.67057 -131.974082) (xy 250.22937 -131.974082) (xy 250.22937 -133.777482) (xy 249.67057 -133.777482)
			)
		)
	)
	(zone
		(layer "In12.Cu")
		(hatch none 0.5)
		(connect_pads
			(clearance 0)
		)
		(min_thickness 0.25)
		(keepout
			(tracks not_allowed)
			(vias allowed)
			(pads allowed)
			(copperpour not_allowed)
			(footprints allowed)
		)
		(placement
			(enabled no)
			(sheetname "")
		)
		(fill
			(thermal_gap 0.5)
			(thermal_bridge_width 0.5)
			(island_removal_mode 0)
		)
		(polygon
			(pts
				(xy 283.670502 -4.720082) (xy 284.229302 -4.720082) (xy 284.229302 -6.523482) (xy 283.670502 -6.523482)
			)
		)
	)
	(zone
		(layer "In12.Cu")
		(hatch none 0.5)
		(connect_pads
			(clearance 0)
		)
		(min_thickness 0.25)
		(keepout
			(tracks not_allowed)
			(vias allowed)
			(pads allowed)
			(copperpour not_allowed)
			(footprints allowed)
		)
		(placement
			(enabled no)
			(sheetname "")
		)
		(fill
			(thermal_gap 0.5)
			(thermal_bridge_width 0.5)
			(island_removal_mode 0)
		)
		(polygon
			(pts
				(xy 136.51992 -23.922482) (xy 137.07872 -23.922482) (xy 137.07872 -25.725882) (xy 136.51992 -25.725882)
			)
		)
	)
	(zone
		(layer "In12.Cu")
		(hatch none 0.5)
		(connect_pads
			(clearance 0)
		)
		(min_thickness 0.25)
		(keepout
			(tracks not_allowed)
			(vias allowed)
			(pads allowed)
			(copperpour not_allowed)
			(footprints allowed)
		)
		(placement
			(enabled no)
			(sheetname "")
		)
		(fill
			(thermal_gap 0.5)
			(thermal_bridge_width 0.5)
			(island_removal_mode 0)
		)
		(polygon
			(pts
				(xy 219.920566 -136.975342) (xy 220.479366 -136.975342) (xy 220.479366 -138.778742) (xy 219.920566 -138.778742)
			)
		)
	)
	(zone
		(layer "In12.Cu")
		(hatch none 0.5)
		(connect_pads
			(clearance 0)
		)
		(min_thickness 0.25)
		(keepout
			(tracks not_allowed)
			(vias allowed)
			(pads allowed)
			(copperpour not_allowed)
			(footprints allowed)
		)
		(placement
			(enabled no)
			(sheetname "")
		)
		(fill
			(thermal_gap 0.5)
			(thermal_bridge_width 0.5)
			(island_removal_mode 0)
		)
		(polygon
			(pts
				(xy 81.270094 -14.321282) (xy 81.828894 -14.321282) (xy 81.828894 -16.124682) (xy 81.270094 -16.124682)
			)
		)
	)
	(zone
		(layer "In12.Cu")
		(hatch none 0.5)
		(connect_pads
			(clearance 0)
		)
		(min_thickness 0.25)
		(keepout
			(tracks not_allowed)
			(vias allowed)
			(pads allowed)
			(copperpour not_allowed)
			(footprints allowed)
		)
		(placement
			(enabled no)
			(sheetname "")
		)
		(fill
			(thermal_gap 0.5)
			(thermal_bridge_width 0.5)
			(island_removal_mode 0)
		)
		(polygon
			(pts
				(xy 12.86002 -99.31908) (xy 14.25702 -99.31908) (xy 14.25702 -99.82708) (xy 12.86002 -99.82708)
			)
		)
	)
	(zone
		(layer "In12.Cu")
		(hatch none 0.5)
		(connect_pads
			(clearance 0)
		)
		(min_thickness 0.25)
		(keepout
			(tracks not_allowed)
			(vias allowed)
			(pads allowed)
			(copperpour not_allowed)
			(footprints allowed)
		)
		(placement
			(enabled no)
			(sheetname "")
		)
		(fill
			(thermal_gap 0.5)
			(thermal_bridge_width 0.5)
			(island_removal_mode 0)
		)
		(polygon
			(pts
				(xy 264.970514 -146.576542) (xy 265.529314 -146.576542) (xy 265.529314 -148.379942) (xy 264.970514 -148.379942)
			)
		)
	)
	(zone
		(layer "In12.Cu")
		(hatch none 0.5)
		(connect_pads
			(clearance 0)
		)
		(min_thickness 0.25)
		(keepout
			(tracks not_allowed)
			(vias allowed)
			(pads allowed)
			(copperpour not_allowed)
			(footprints allowed)
		)
		(placement
			(enabled no)
			(sheetname "")
		)
		(fill
			(thermal_gap 0.5)
			(thermal_bridge_width 0.5)
			(island_removal_mode 0)
		)
		(polygon
			(pts
				(xy 362.925614 -124.694442) (xy 360.639614 -124.694442) (xy 360.639614 -124.186442) (xy 362.925614 -124.186442)
			)
		)
	)
	(zone
		(net "AGND_PVPP_ABC")
		(layer "In12.Cu")
		(hatch none 0.5)
		(connect_pads
			(clearance 0.5)
		)
		(min_thickness 0.25)
		(fill yes
			(thermal_gap 0.5)
			(thermal_bridge_width 0.5)
			(island_removal_mode 0)
		)
		(polygon
			(pts
				(xy 340.338156 -21.59) (xy 340.233 -21.695156) (xy 340.233 -22.119844) (xy 340.338156 -22.225) (xy 340.592156 -22.225)
				(xy 340.995 -22.627844) (xy 340.995 -23.346156) (xy 340.719156 -23.622) (xy 338.365846 -23.622)
				(xy 337.730846 -23.114) (xy 336.55 -23.114) (xy 336.55 -25.040844) (xy 337.798156 -26.289) (xy 340.254844 -26.289)
				(xy 340.635844 -25.908) (xy 345.207844 -25.908) (xy 346.075 -25.040844) (xy 346.075 -23.727156)
				(xy 345.948 -23.600156) (xy 345.948 -21.949156) (xy 345.715844 -21.717) (xy 345.44 -21.717) (xy 345.44 -22.330156)
				(xy 345.164156 -22.606) (xy 343.175844 -22.606) (xy 342.540844 -21.971) (xy 341.270844 -21.971)
				(xy 340.889844 -21.59)
			)
		)
	)
	(zone
		(layer "In12.Cu")
		(hatch none 0.5)
		(connect_pads
			(clearance 0)
		)
		(min_thickness 0.25)
		(keepout
			(tracks not_allowed)
			(vias allowed)
			(pads allowed)
			(copperpour not_allowed)
			(footprints allowed)
		)
		(placement
			(enabled no)
			(sheetname "")
		)
		(fill
			(thermal_gap 0.5)
			(thermal_bridge_width 0.5)
			(island_removal_mode 0)
		)
		(polygon
			(pts
				(xy 410.4132 -152.781) (xy 410.4132 -153.543) (xy 411.4038 -153.543) (xy 411.4038 -152.781)
			)
		)
	)
	(zone
		(layer "In12.Cu")
		(hatch none 0.5)
		(connect_pads
			(clearance 0)
		)
		(min_thickness 0.25)
		(keepout
			(tracks not_allowed)
			(vias allowed)
			(pads allowed)
			(copperpour not_allowed)
			(footprints allowed)
		)
		(placement
			(enabled no)
			(sheetname "")
		)
		(fill
			(thermal_gap 0.5)
			(thermal_bridge_width 0.5)
			(island_removal_mode 0)
		)
		(polygon
			(pts
				(xy 205.470506 -14.321282) (xy 206.029306 -14.321282) (xy 206.029306 -16.124682) (xy 205.470506 -16.124682)
			)
		)
	)
	(zone
		(layer "In12.Cu")
		(hatch none 0.5)
		(connect_pads
			(clearance 0)
		)
		(min_thickness 0.25)
		(keepout
			(tracks not_allowed)
			(vias allowed)
			(pads allowed)
			(copperpour not_allowed)
			(footprints allowed)
		)
		(placement
			(enabled no)
			(sheetname "")
		)
		(fill
			(thermal_gap 0.5)
			(thermal_bridge_width 0.5)
			(island_removal_mode 0)
		)
		(polygon
			(pts
				(xy 149.269958 -0.120142) (xy 149.828758 -0.120142) (xy 149.828758 -1.923542) (xy 149.269958 -1.923542)
			)
		)
	)
	(zone
		(layer "In12.Cu")
		(hatch none 0.5)
		(connect_pads
			(clearance 0)
		)
		(min_thickness 0.25)
		(keepout
			(tracks not_allowed)
			(vias allowed)
			(pads allowed)
			(copperpour not_allowed)
			(footprints allowed)
		)
		(placement
			(enabled no)
			(sheetname "")
		)
		(fill
			(thermal_gap 0.5)
			(thermal_bridge_width 0.5)
			(island_removal_mode 0)
		)
		(polygon
			(pts
				(xy 208.020412 -127.374142) (xy 208.579212 -127.374142) (xy 208.579212 -129.177542) (xy 208.020412 -129.177542)
			)
		)
	)
	(zone
		(layer "In12.Cu")
		(hatch none 0.5)
		(connect_pads
			(clearance 0)
		)
		(min_thickness 0.25)
		(keepout
			(tracks not_allowed)
			(vias allowed)
			(pads allowed)
			(copperpour not_allowed)
			(footprints allowed)
		)
		(placement
			(enabled no)
			(sheetname "")
		)
		(fill
			(thermal_gap 0.5)
			(thermal_bridge_width 0.5)
			(island_removal_mode 0)
		)
		(polygon
			(pts
				(xy 33.669986 -146.576542) (xy 34.228786 -146.576542) (xy 34.228786 -148.379942) (xy 33.669986 -148.379942)
			)
		)
	)
	(zone
		(layer "In12.Cu")
		(hatch none 0.5)
		(connect_pads
			(clearance 0)
		)
		(min_thickness 0.25)
		(keepout
			(tracks not_allowed)
			(vias allowed)
			(pads allowed)
			(copperpour not_allowed)
			(footprints allowed)
		)
		(placement
			(enabled no)
			(sheetname "")
		)
		(fill
			(thermal_gap 0.5)
			(thermal_bridge_width 0.5)
			(island_removal_mode 0)
		)
		(polygon
			(pts
				(xy 213.120478 -23.922482) (xy 213.679278 -23.922482) (xy 213.679278 -25.725882) (xy 213.120478 -25.725882)
			)
		)
	)
	(zone
		(layer "In12.Cu")
		(hatch none 0.5)
		(connect_pads
			(clearance 0)
		)
		(min_thickness 0.25)
		(keepout
			(tracks not_allowed)
			(vias allowed)
			(pads allowed)
			(copperpour not_allowed)
			(footprints allowed)
		)
		(placement
			(enabled no)
			(sheetname "")
		)
		(fill
			(thermal_gap 0.5)
			(thermal_bridge_width 0.5)
			(island_removal_mode 0)
		)
		(polygon
			(pts
				(xy 120.370092 -4.720082) (xy 120.928892 -4.720082) (xy 120.928892 -6.523482) (xy 120.370092 -6.523482)
			)
		)
	)
	(zone
		(layer "In12.Cu")
		(hatch none 0.5)
		(connect_pads
			(clearance 0)
		)
		(min_thickness 0.25)
		(keepout
			(tracks not_allowed)
			(vias allowed)
			(pads allowed)
			(copperpour not_allowed)
			(footprints allowed)
		)
		(placement
			(enabled no)
			(sheetname "")
		)
		(fill
			(thermal_gap 0.5)
			(thermal_bridge_width 0.5)
			(island_removal_mode 0)
		)
		(polygon
			(pts
				(xy 207.170528 -141.575282) (xy 207.729328 -141.575282) (xy 207.729328 -143.378682) (xy 207.170528 -143.378682)
			)
		)
	)
	(zone
		(layer "In12.Cu")
		(hatch none 0.5)
		(connect_pads
			(clearance 0)
		)
		(min_thickness 0.25)
		(keepout
			(tracks not_allowed)
			(vias allowed)
			(pads allowed)
			(copperpour not_allowed)
			(footprints allowed)
		)
		(placement
			(enabled no)
			(sheetname "")
		)
		(fill
			(thermal_gap 0.5)
			(thermal_bridge_width 0.5)
			(island_removal_mode 0)
		)
		(polygon
			(pts
				(xy 30.269942 -136.975342) (xy 30.828742 -136.975342) (xy 30.828742 -138.778742) (xy 30.269942 -138.778742)
			)
		)
	)
	(zone
		(layer "In12.Cu")
		(hatch none 0.5)
		(connect_pads
			(clearance 0)
		)
		(min_thickness 0.25)
		(keepout
			(tracks not_allowed)
			(vias allowed)
			(pads allowed)
			(copperpour not_allowed)
			(footprints allowed)
		)
		(placement
			(enabled no)
			(sheetname "")
		)
		(fill
			(thermal_gap 0.5)
			(thermal_bridge_width 0.5)
			(island_removal_mode 0)
		)
		(polygon
			(pts
				(xy 289.620452 -127.374142) (xy 290.179252 -127.374142) (xy 290.179252 -129.177542) (xy 289.620452 -129.177542)
			)
		)
	)
	(zone
		(layer "In12.Cu")
		(hatch none 0.5)
		(connect_pads
			(clearance 0)
		)
		(min_thickness 0.25)
		(keepout
			(tracks not_allowed)
			(vias allowed)
			(pads allowed)
			(copperpour not_allowed)
			(footprints allowed)
		)
		(placement
			(enabled no)
			(sheetname "")
		)
		(fill
			(thermal_gap 0.5)
			(thermal_bridge_width 0.5)
			(island_removal_mode 0)
		)
		(polygon
			(pts
				(xy 59.170062 -141.575282) (xy 59.728862 -141.575282) (xy 59.728862 -143.378682) (xy 59.170062 -143.378682)
			)
		)
	)
	(zone
		(layer "In12.Cu")
		(hatch none 0.5)
		(connect_pads
			(clearance 0)
		)
		(min_thickness 0.25)
		(keepout
			(tracks not_allowed)
			(vias allowed)
			(pads allowed)
			(copperpour not_allowed)
			(footprints allowed)
		)
		(placement
			(enabled no)
			(sheetname "")
		)
		(fill
			(thermal_gap 0.5)
			(thermal_bridge_width 0.5)
			(island_removal_mode 0)
		)
		(polygon
			(pts
				(xy 118.67007 -146.576542) (xy 119.22887 -146.576542) (xy 119.22887 -148.379942) (xy 118.67007 -148.379942)
			)
		)
	)
	(zone
		(layer "In12.Cu")
		(hatch none 0.5)
		(connect_pads
			(clearance 0)
		)
		(min_thickness 0.25)
		(keepout
			(tracks not_allowed)
			(vias allowed)
			(pads allowed)
			(copperpour not_allowed)
			(footprints allowed)
		)
		(placement
			(enabled no)
			(sheetname "")
		)
		(fill
			(thermal_gap 0.5)
			(thermal_bridge_width 0.5)
			(island_removal_mode 0)
		)
		(polygon
			(pts
				(xy 34.520124 -14.321282) (xy 35.078924 -14.321282) (xy 35.078924 -16.124682) (xy 34.520124 -16.124682)
			)
		)
	)
	(zone
		(layer "In12.Cu")
		(hatch none 0.5)
		(connect_pads
			(clearance 0)
		)
		(min_thickness 0.25)
		(keepout
			(tracks not_allowed)
			(vias allowed)
			(pads allowed)
			(copperpour not_allowed)
			(footprints allowed)
		)
		(placement
			(enabled no)
			(sheetname "")
		)
		(fill
			(thermal_gap 0.5)
			(thermal_bridge_width 0.5)
			(island_removal_mode 0)
		)
		(polygon
			(pts
				(xy 69.36994 -9.721342) (xy 69.92874 -9.721342) (xy 69.92874 -11.524742) (xy 69.36994 -11.524742)
			)
		)
	)
	(zone
		(layer "In12.Cu")
		(hatch none 0.5)
		(connect_pads
			(clearance 0)
		)
		(min_thickness 0.25)
		(keepout
			(tracks not_allowed)
			(vias allowed)
			(pads allowed)
			(copperpour not_allowed)
			(footprints allowed)
		)
		(placement
			(enabled no)
			(sheetname "")
		)
		(fill
			(thermal_gap 0.5)
			(thermal_bridge_width 0.5)
			(island_removal_mode 0)
		)
		(polygon
			(pts
				(xy 308.32044 -127.374142) (xy 308.87924 -127.374142) (xy 308.87924 -129.177542) (xy 308.32044 -129.177542)
			)
		)
	)
	(zone
		(layer "In12.Cu")
		(hatch none 0.5)
		(connect_pads
			(clearance 0)
		)
		(min_thickness 0.25)
		(keepout
			(tracks not_allowed)
			(vias allowed)
			(pads allowed)
			(copperpour not_allowed)
			(footprints allowed)
		)
		(placement
			(enabled no)
			(sheetname "")
		)
		(fill
			(thermal_gap 0.5)
			(thermal_bridge_width 0.5)
			(island_removal_mode 0)
		)
		(polygon
			(pts
				(xy 57.47004 -131.974082) (xy 58.02884 -131.974082) (xy 58.02884 -133.777482) (xy 57.47004 -133.777482)
			)
		)
	)
	(zone
		(layer "In12.Cu")
		(hatch none 0.5)
		(connect_pads
			(clearance 0)
		)
		(min_thickness 0.25)
		(keepout
			(tracks not_allowed)
			(vias allowed)
			(pads allowed)
			(copperpour not_allowed)
			(footprints allowed)
		)
		(placement
			(enabled no)
			(sheetname "")
		)
		(fill
			(thermal_gap 0.5)
			(thermal_bridge_width 0.5)
			(island_removal_mode 0)
		)
		(polygon
			(pts
				(xy 77.02042 -136.975342) (xy 77.57922 -136.975342) (xy 77.57922 -138.778742) (xy 77.02042 -138.778742)
			)
		)
	)
	(zone
		(layer "In12.Cu")
		(hatch none 0.5)
		(connect_pads
			(clearance 0)
		)
		(min_thickness 0.25)
		(keepout
			(tracks not_allowed)
			(vias allowed)
			(pads allowed)
			(copperpour not_allowed)
			(footprints allowed)
		)
		(placement
			(enabled no)
			(sheetname "")
		)
		(fill
			(thermal_gap 0.5)
			(thermal_bridge_width 0.5)
			(island_removal_mode 0)
		)
		(polygon
			(pts
				(xy 249.67057 -19.322542) (xy 250.22937 -19.322542) (xy 250.22937 -21.125942) (xy 249.67057 -21.125942)
			)
		)
	)
	(zone
		(layer "In12.Cu")
		(hatch none 0.5)
		(connect_pads
			(clearance 0)
		)
		(min_thickness 0.25)
		(keepout
			(tracks not_allowed)
			(vias allowed)
			(pads allowed)
			(copperpour not_allowed)
			(footprints allowed)
		)
		(placement
			(enabled no)
			(sheetname "")
		)
		(fill
			(thermal_gap 0.5)
			(thermal_bridge_width 0.5)
			(island_removal_mode 0)
		)
		(polygon
			(pts
				(xy 107.620054 -4.720082) (xy 108.178854 -4.720082) (xy 108.178854 -6.523482) (xy 107.620054 -6.523482)
			)
		)
	)
	(zone
		(layer "In12.Cu")
		(hatch none 0.5)
		(connect_pads
			(clearance 0)
		)
		(min_thickness 0.25)
		(keepout
			(tracks not_allowed)
			(vias allowed)
			(pads allowed)
			(copperpour not_allowed)
			(footprints allowed)
		)
		(placement
			(enabled no)
			(sheetname "")
		)
		(fill
			(thermal_gap 0.5)
			(thermal_bridge_width 0.5)
			(island_removal_mode 0)
		)
		(polygon
			(pts
				(xy 133.119876 -23.922482) (xy 133.678676 -23.922482) (xy 133.678676 -25.725882) (xy 133.119876 -25.725882)
			)
		)
	)
	(zone
		(layer "In12.Cu")
		(hatch none 0.5)
		(connect_pads
			(clearance 0)
		)
		(min_thickness 0.25)
		(keepout
			(tracks not_allowed)
			(vias allowed)
			(pads allowed)
			(copperpour not_allowed)
			(footprints allowed)
		)
		(placement
			(enabled no)
			(sheetname "")
		)
		(fill
			(thermal_gap 0.5)
			(thermal_bridge_width 0.5)
			(island_removal_mode 0)
		)
		(polygon
			(pts
				(xy 83.82 -14.321282) (xy 84.3788 -14.321282) (xy 84.3788 -16.124682) (xy 83.82 -16.124682)
			)
		)
	)
	(zone
		(layer "In12.Cu")
		(hatch none 0.5)
		(connect_pads
			(clearance 0)
		)
		(min_thickness 0.25)
		(keepout
			(tracks not_allowed)
			(vias allowed)
			(pads allowed)
			(copperpour not_allowed)
			(footprints allowed)
		)
		(placement
			(enabled no)
			(sheetname "")
		)
		(fill
			(thermal_gap 0.5)
			(thermal_bridge_width 0.5)
			(island_removal_mode 0)
		)
		(polygon
			(pts
				(xy 282.820364 -131.974082) (xy 283.379164 -131.974082) (xy 283.379164 -133.777482) (xy 282.820364 -133.777482)
			)
		)
	)
	(zone
		(layer "In12.Cu")
		(hatch none 0.5)
		(connect_pads
			(clearance 0)
		)
		(min_thickness 0.25)
		(keepout
			(tracks not_allowed)
			(vias allowed)
			(pads allowed)
			(copperpour not_allowed)
			(footprints allowed)
		)
		(placement
			(enabled no)
			(sheetname "")
		)
		(fill
			(thermal_gap 0.5)
			(thermal_bridge_width 0.5)
			(island_removal_mode 0)
		)
		(polygon
			(pts
				(xy 39.619936 -136.975342) (xy 40.178736 -136.975342) (xy 40.178736 -138.778742) (xy 39.619936 -138.778742)
			)
		)
	)
	(zone
		(layer "In12.Cu")
		(hatch none 0.5)
		(connect_pads
			(clearance 0)
		)
		(min_thickness 0.25)
		(keepout
			(tracks not_allowed)
			(vias allowed)
			(pads allowed)
			(copperpour not_allowed)
			(footprints allowed)
		)
		(placement
			(enabled no)
			(sheetname "")
		)
		(fill
			(thermal_gap 0.5)
			(thermal_bridge_width 0.5)
			(island_removal_mode 0)
		)
		(polygon
			(pts
				(xy 254.770382 -141.575282) (xy 255.329182 -141.575282) (xy 255.329182 -143.378682) (xy 254.770382 -143.378682)
			)
		)
	)
	(zone
		(layer "In12.Cu")
		(hatch none 0.5)
		(connect_pads
			(clearance 0)
		)
		(min_thickness 0.25)
		(keepout
			(tracks not_allowed)
			(vias allowed)
			(pads allowed)
			(copperpour not_allowed)
			(footprints allowed)
		)
		(placement
			(enabled no)
			(sheetname "")
		)
		(fill
			(thermal_gap 0.5)
			(thermal_bridge_width 0.5)
			(island_removal_mode 0)
		)
		(polygon
			(pts
				(xy 108.469938 -127.374142) (xy 109.028738 -127.374142) (xy 109.028738 -129.177542) (xy 108.469938 -129.177542)
			)
		)
	)
	(zone
		(layer "In12.Cu")
		(hatch none 0.5)
		(connect_pads
			(clearance 0)
		)
		(min_thickness 0.25)
		(keepout
			(tracks not_allowed)
			(vias allowed)
			(pads allowed)
			(copperpour not_allowed)
			(footprints allowed)
		)
		(placement
			(enabled no)
			(sheetname "")
		)
		(fill
			(thermal_gap 0.5)
			(thermal_bridge_width 0.5)
			(island_removal_mode 0)
		)
		(polygon
			(pts
				(xy 277.720552 -127.374142) (xy 278.279352 -127.374142) (xy 278.279352 -129.177542) (xy 277.720552 -129.177542)
			)
		)
	)
	(zone
		(layer "In12.Cu")
		(hatch none 0.5)
		(connect_pads
			(clearance 0)
		)
		(min_thickness 0.25)
		(keepout
			(tracks not_allowed)
			(vias allowed)
			(pads allowed)
			(copperpour not_allowed)
			(footprints allowed)
		)
		(placement
			(enabled no)
			(sheetname "")
		)
		(fill
			(thermal_gap 0.5)
			(thermal_bridge_width 0.5)
			(island_removal_mode 0)
		)
		(polygon
			(pts
				(xy 119.519954 -9.721342) (xy 120.078754 -9.721342) (xy 120.078754 -11.524742) (xy 119.519954 -11.524742)
			)
		)
	)
	(zone
		(layer "In12.Cu")
		(hatch none 0.5)
		(connect_pads
			(clearance 0)
		)
		(min_thickness 0.25)
		(keepout
			(tracks not_allowed)
			(vias allowed)
			(pads allowed)
			(copperpour not_allowed)
			(footprints allowed)
		)
		(placement
			(enabled no)
			(sheetname "")
		)
		(fill
			(thermal_gap 0.5)
			(thermal_bridge_width 0.5)
			(island_removal_mode 0)
		)
		(polygon
			(pts
				(xy 89.76995 -14.321282) (xy 90.32875 -14.321282) (xy 90.32875 -16.124682) (xy 89.76995 -16.124682)
			)
		)
	)
	(zone
		(layer "In12.Cu")
		(hatch none 0.5)
		(connect_pads
			(clearance 0)
		)
		(min_thickness 0.25)
		(keepout
			(tracks not_allowed)
			(vias allowed)
			(pads allowed)
			(copperpour not_allowed)
			(footprints allowed)
		)
		(placement
			(enabled no)
			(sheetname "")
		)
		(fill
			(thermal_gap 0.5)
			(thermal_bridge_width 0.5)
			(island_removal_mode 0)
		)
		(polygon
			(pts
				(xy 224.170494 -151.176482) (xy 224.729294 -151.176482) (xy 224.729294 -152.979882) (xy 224.170494 -152.979882)
			)
		)
	)
	(zone
		(layer "In12.Cu")
		(hatch none 0.5)
		(connect_pads
			(clearance 0)
		)
		(min_thickness 0.25)
		(keepout
			(tracks not_allowed)
			(vias allowed)
			(pads allowed)
			(copperpour not_allowed)
			(footprints allowed)
		)
		(placement
			(enabled no)
			(sheetname "")
		)
		(fill
			(thermal_gap 0.5)
			(thermal_bridge_width 0.5)
			(island_removal_mode 0)
		)
		(polygon
			(pts
				(xy 276.02053 -23.922482) (xy 276.57933 -23.922482) (xy 276.57933 -25.725882) (xy 276.02053 -25.725882)
			)
		)
	)
	(zone
		(layer "In12.Cu")
		(hatch none 0.5)
		(connect_pads
			(clearance 0)
		)
		(min_thickness 0.25)
		(keepout
			(tracks not_allowed)
			(vias allowed)
			(pads allowed)
			(copperpour not_allowed)
			(footprints allowed)
		)
		(placement
			(enabled no)
			(sheetname "")
		)
		(fill
			(thermal_gap 0.5)
			(thermal_bridge_width 0.5)
			(island_removal_mode 0)
		)
		(polygon
			(pts
				(xy 420.5732 -150.495) (xy 420.5732 -151.257) (xy 421.5638 -151.257) (xy 421.5638 -150.495)
			)
		)
	)
	(zone
		(layer "In12.Cu")
		(hatch none 0.5)
		(connect_pads
			(clearance 0)
		)
		(min_thickness 0.25)
		(keepout
			(tracks not_allowed)
			(vias allowed)
			(pads allowed)
			(copperpour not_allowed)
			(footprints allowed)
		)
		(placement
			(enabled no)
			(sheetname "")
		)
		(fill
			(thermal_gap 0.5)
			(thermal_bridge_width 0.5)
			(island_removal_mode 0)
		)
		(polygon
			(pts
				(xy 140.770102 -151.176482) (xy 141.328902 -151.176482) (xy 141.328902 -152.979882) (xy 140.770102 -152.979882)
			)
		)
	)
	(zone
		(layer "In12.Cu")
		(hatch none 0.5)
		(connect_pads
			(clearance 0)
		)
		(min_thickness 0.25)
		(keepout
			(tracks not_allowed)
			(vias allowed)
			(pads allowed)
			(copperpour not_allowed)
			(footprints allowed)
		)
		(placement
			(enabled no)
			(sheetname "")
		)
		(fill
			(thermal_gap 0.5)
			(thermal_bridge_width 0.5)
			(island_removal_mode 0)
		)
		(polygon
			(pts
				(xy 208.87055 -131.974082) (xy 209.42935 -131.974082) (xy 209.42935 -133.777482) (xy 208.87055 -133.777482)
			)
		)
	)
	(zone
		(layer "In12.Cu")
		(hatch none 0.5)
		(connect_pads
			(clearance 0)
		)
		(min_thickness 0.25)
		(keepout
			(tracks not_allowed)
			(vias allowed)
			(pads allowed)
			(copperpour not_allowed)
			(footprints allowed)
		)
		(placement
			(enabled no)
			(sheetname "")
		)
		(fill
			(thermal_gap 0.5)
			(thermal_bridge_width 0.5)
			(island_removal_mode 0)
		)
		(polygon
			(pts
				(xy 85.520022 -19.322542) (xy 86.078822 -19.322542) (xy 86.078822 -21.125942) (xy 85.520022 -21.125942)
			)
		)
	)
	(zone
		(layer "In12.Cu")
		(hatch none 0.5)
		(connect_pads
			(clearance 0)
		)
		(min_thickness 0.25)
		(keepout
			(tracks not_allowed)
			(vias allowed)
			(pads allowed)
			(copperpour not_allowed)
			(footprints allowed)
		)
		(placement
			(enabled no)
			(sheetname "")
		)
		(fill
			(thermal_gap 0.5)
			(thermal_bridge_width 0.5)
			(island_removal_mode 0)
		)
		(polygon
			(pts
				(xy 293.020496 -4.720082) (xy 293.579296 -4.720082) (xy 293.579296 -6.523482) (xy 293.020496 -6.523482)
			)
		)
	)
	(zone
		(layer "In12.Cu")
		(hatch none 0.5)
		(connect_pads
			(clearance 0)
		)
		(min_thickness 0.25)
		(keepout
			(tracks not_allowed)
			(vias allowed)
			(pads allowed)
			(copperpour not_allowed)
			(footprints allowed)
		)
		(placement
			(enabled no)
			(sheetname "")
		)
		(fill
			(thermal_gap 0.5)
			(thermal_bridge_width 0.5)
			(island_removal_mode 0)
		)
		(polygon
			(pts
				(xy 83.82 -141.575282) (xy 84.3788 -141.575282) (xy 84.3788 -143.378682) (xy 83.82 -143.378682)
			)
		)
	)
	(zone
		(layer "In12.Cu")
		(hatch none 0.5)
		(connect_pads
			(clearance 0)
		)
		(min_thickness 0.25)
		(keepout
			(tracks not_allowed)
			(vias allowed)
			(pads allowed)
			(copperpour not_allowed)
			(footprints allowed)
		)
		(placement
			(enabled no)
			(sheetname "")
		)
		(fill
			(thermal_gap 0.5)
			(thermal_bridge_width 0.5)
			(island_removal_mode 0)
		)
		(polygon
			(pts
				(xy 31.969964 -9.721342) (xy 32.528764 -9.721342) (xy 32.528764 -11.524742) (xy 31.969964 -11.524742)
			)
		)
	)
	(zone
		(layer "In12.Cu")
		(hatch none 0.5)
		(connect_pads
			(clearance 0)
		)
		(min_thickness 0.25)
		(keepout
			(tracks not_allowed)
			(vias allowed)
			(pads allowed)
			(copperpour not_allowed)
			(footprints allowed)
		)
		(placement
			(enabled no)
			(sheetname "")
		)
		(fill
			(thermal_gap 0.5)
			(thermal_bridge_width 0.5)
			(island_removal_mode 0)
		)
		(polygon
			(pts
				(xy 285.370524 -151.176482) (xy 285.929324 -151.176482) (xy 285.929324 -152.979882) (xy 285.370524 -152.979882)
			)
		)
	)
	(zone
		(layer "In12.Cu")
		(hatch none 0.5)
		(connect_pads
			(clearance 0)
		)
		(min_thickness 0.25)
		(keepout
			(tracks not_allowed)
			(vias allowed)
			(pads allowed)
			(copperpour not_allowed)
			(footprints allowed)
		)
		(placement
			(enabled no)
			(sheetname "")
		)
		(fill
			(thermal_gap 0.5)
			(thermal_bridge_width 0.5)
			(island_removal_mode 0)
		)
		(polygon
			(pts
				(xy 237.770416 -0.120142) (xy 238.329216 -0.120142) (xy 238.329216 -1.923542) (xy 237.770416 -1.923542)
			)
		)
	)
	(zone
		(layer "In12.Cu")
		(hatch none 0.5)
		(connect_pads
			(clearance 0)
		)
		(min_thickness 0.25)
		(keepout
			(tracks not_allowed)
			(vias allowed)
			(pads allowed)
			(copperpour not_allowed)
			(footprints allowed)
		)
		(placement
			(enabled no)
			(sheetname "")
		)
		(fill
			(thermal_gap 0.5)
			(thermal_bridge_width 0.5)
			(island_removal_mode 0)
		)
		(polygon
			(pts
				(xy 37.920168 -127.374142) (xy 38.478968 -127.374142) (xy 38.478968 -129.177542) (xy 37.920168 -129.177542)
			)
		)
	)
	(zone
		(layer "In12.Cu")
		(hatch none 0.5)
		(connect_pads
			(clearance 0)
		)
		(min_thickness 0.25)
		(keepout
			(tracks not_allowed)
			(vias allowed)
			(pads allowed)
			(copperpour not_allowed)
			(footprints allowed)
		)
		(placement
			(enabled no)
			(sheetname "")
		)
		(fill
			(thermal_gap 0.5)
			(thermal_bridge_width 0.5)
			(island_removal_mode 0)
		)
		(polygon
			(pts
				(xy 91.469972 -151.176482) (xy 92.028772 -151.176482) (xy 92.028772 -152.979882) (xy 91.469972 -152.979882)
			)
		)
	)
	(zone
		(layer "In12.Cu")
		(hatch none 0.5)
		(connect_pads
			(clearance 0)
		)
		(min_thickness 0.25)
		(keepout
			(tracks not_allowed)
			(vias allowed)
			(pads allowed)
			(copperpour not_allowed)
			(footprints allowed)
		)
		(placement
			(enabled no)
			(sheetname "")
		)
		(fill
			(thermal_gap 0.5)
			(thermal_bridge_width 0.5)
			(island_removal_mode 0)
		)
		(polygon
			(pts
				(xy 226.7204 -19.322542) (xy 227.2792 -19.322542) (xy 227.2792 -21.125942) (xy 226.7204 -21.125942)
			)
		)
	)
	(zone
		(layer "In12.Cu")
		(hatch none 0.5)
		(connect_pads
			(clearance 0)
		)
		(min_thickness 0.25)
		(keepout
			(tracks not_allowed)
			(vias allowed)
			(pads allowed)
			(copperpour not_allowed)
			(footprints allowed)
		)
		(placement
			(enabled no)
			(sheetname "")
		)
		(fill
			(thermal_gap 0.5)
			(thermal_bridge_width 0.5)
			(island_removal_mode 0)
		)
		(polygon
			(pts
				(xy 38.770052 -141.575282) (xy 39.328852 -141.575282) (xy 39.328852 -143.378682) (xy 38.770052 -143.378682)
			)
		)
	)
	(zone
		(layer "In12.Cu")
		(hatch none 0.5)
		(connect_pads
			(clearance 0)
		)
		(min_thickness 0.25)
		(keepout
			(tracks not_allowed)
			(vias allowed)
			(pads allowed)
			(copperpour not_allowed)
			(footprints allowed)
		)
		(placement
			(enabled no)
			(sheetname "")
		)
		(fill
			(thermal_gap 0.5)
			(thermal_bridge_width 0.5)
			(island_removal_mode 0)
		)
		(polygon
			(pts
				(xy 126.320042 -0.120142) (xy 126.878842 -0.120142) (xy 126.878842 -1.923542) (xy 126.320042 -1.923542)
			)
		)
	)
	(zone
		(layer "In12.Cu")
		(hatch none 0.5)
		(connect_pads
			(clearance 0)
		)
		(min_thickness 0.25)
		(keepout
			(tracks not_allowed)
			(vias allowed)
			(pads allowed)
			(copperpour not_allowed)
			(footprints allowed)
		)
		(placement
			(enabled no)
			(sheetname "")
		)
		(fill
			(thermal_gap 0.5)
			(thermal_bridge_width 0.5)
			(island_removal_mode 0)
		)
		(polygon
			(pts
				(xy 146.720052 -131.974082) (xy 147.278852 -131.974082) (xy 147.278852 -133.777482) (xy 146.720052 -133.777482)
			)
		)
	)
	(zone
		(layer "In12.Cu")
		(hatch none 0.5)
		(connect_pads
			(clearance 0)
		)
		(min_thickness 0.25)
		(keepout
			(tracks not_allowed)
			(vias allowed)
			(pads allowed)
			(copperpour not_allowed)
			(footprints allowed)
		)
		(placement
			(enabled no)
			(sheetname "")
		)
		(fill
			(thermal_gap 0.5)
			(thermal_bridge_width 0.5)
			(island_removal_mode 0)
		)
		(polygon
			(pts
				(xy 144.169892 -141.575282) (xy 144.728692 -141.575282) (xy 144.728692 -143.378682) (xy 144.169892 -143.378682)
			)
		)
	)
	(zone
		(layer "In12.Cu")
		(hatch none 0.5)
		(connect_pads
			(clearance 0)
		)
		(min_thickness 0.25)
		(keepout
			(tracks not_allowed)
			(vias allowed)
			(pads allowed)
			(copperpour not_allowed)
			(footprints allowed)
		)
		(placement
			(enabled no)
			(sheetname "")
		)
		(fill
			(thermal_gap 0.5)
			(thermal_bridge_width 0.5)
			(island_removal_mode 0)
		)
		(polygon
			(pts
				(xy 354.797614 -124.034042) (xy 352.511614 -124.034042) (xy 352.511614 -123.526042) (xy 354.797614 -123.526042)
			)
		)
	)
	(zone
		(layer "In12.Cu")
		(hatch none 0.5)
		(connect_pads
			(clearance 0)
		)
		(min_thickness 0.25)
		(keepout
			(tracks not_allowed)
			(vias allowed)
			(pads allowed)
			(copperpour not_allowed)
			(footprints allowed)
		)
		(placement
			(enabled no)
			(sheetname "")
		)
		(fill
			(thermal_gap 0.5)
			(thermal_bridge_width 0.5)
			(island_removal_mode 0)
		)
		(polygon
			(pts
				(xy 297.270424 -0.120142) (xy 297.829224 -0.120142) (xy 297.829224 -1.923542) (xy 297.270424 -1.923542)
			)
		)
	)
	(zone
		(layer "In12.Cu")
		(hatch none 0.5)
		(connect_pads
			(clearance 0)
		)
		(min_thickness 0.25)
		(keepout
			(tracks not_allowed)
			(vias allowed)
			(pads allowed)
			(copperpour not_allowed)
			(footprints allowed)
		)
		(placement
			(enabled no)
			(sheetname "")
		)
		(fill
			(thermal_gap 0.5)
			(thermal_bridge_width 0.5)
			(island_removal_mode 0)
		)
		(polygon
			(pts
				(xy 351.675192 -76.691236) (xy 351.675192 -78.977236) (xy 351.167192 -78.977236) (xy 351.167192 -76.691236)
			)
		)
	)
	(zone
		(layer "In12.Cu")
		(hatch none 0.5)
		(connect_pads
			(clearance 0)
		)
		(min_thickness 0.25)
		(keepout
			(tracks not_allowed)
			(vias allowed)
			(pads allowed)
			(copperpour not_allowed)
			(footprints allowed)
		)
		(placement
			(enabled no)
			(sheetname "")
		)
		(fill
			(thermal_gap 0.5)
			(thermal_bridge_width 0.5)
			(island_removal_mode 0)
		)
		(polygon
			(pts
				(xy 302.37049 -131.974082) (xy 302.92929 -131.974082) (xy 302.92929 -133.777482) (xy 302.37049 -133.777482)
			)
		)
	)
	(zone
		(layer "In12.Cu")
		(hatch none 0.5)
		(connect_pads
			(clearance 0)
		)
		(min_thickness 0.25)
		(keepout
			(tracks not_allowed)
			(vias allowed)
			(pads allowed)
			(copperpour not_allowed)
			(footprints allowed)
		)
		(placement
			(enabled no)
			(sheetname "")
		)
		(fill
			(thermal_gap 0.5)
			(thermal_bridge_width 0.5)
			(island_removal_mode 0)
		)
		(polygon
			(pts
				(xy 227.570538 -151.176482) (xy 228.129338 -151.176482) (xy 228.129338 -152.979882) (xy 227.570538 -152.979882)
			)
		)
	)
	(zone
		(layer "In12.Cu")
		(hatch none 0.5)
		(connect_pads
			(clearance 0)
		)
		(min_thickness 0.25)
		(keepout
			(tracks not_allowed)
			(vias allowed)
			(pads allowed)
			(copperpour not_allowed)
			(footprints allowed)
		)
		(placement
			(enabled no)
			(sheetname "")
		)
		(fill
			(thermal_gap 0.5)
			(thermal_bridge_width 0.5)
			(island_removal_mode 0)
		)
		(polygon
			(pts
				(xy 271.770602 -14.321282) (xy 272.329402 -14.321282) (xy 272.329402 -16.124682) (xy 271.770602 -16.124682)
			)
		)
	)
	(zone
		(layer "In12.Cu")
		(hatch none 0.5)
		(connect_pads
			(clearance 0)
		)
		(min_thickness 0.25)
		(keepout
			(tracks not_allowed)
			(vias allowed)
			(pads allowed)
			(copperpour not_allowed)
			(footprints allowed)
		)
		(placement
			(enabled no)
			(sheetname "")
		)
		(fill
			(thermal_gap 0.5)
			(thermal_bridge_width 0.5)
			(island_removal_mode 0)
		)
		(polygon
			(pts
				(xy 229.27056 -146.576542) (xy 229.82936 -146.576542) (xy 229.82936 -148.379942) (xy 229.27056 -148.379942)
			)
		)
	)
	(zone
		(layer "In12.Cu")
		(hatch none 0.5)
		(connect_pads
			(clearance 0)
		)
		(min_thickness 0.25)
		(keepout
			(tracks not_allowed)
			(vias allowed)
			(pads allowed)
			(copperpour not_allowed)
			(footprints allowed)
		)
		(placement
			(enabled no)
			(sheetname "")
		)
		(fill
			(thermal_gap 0.5)
			(thermal_bridge_width 0.5)
			(island_removal_mode 0)
		)
		(polygon
			(pts
				(xy 244.570504 -14.321282) (xy 245.129304 -14.321282) (xy 245.129304 -16.124682) (xy 244.570504 -16.124682)
			)
		)
	)
	(zone
		(layer "In12.Cu")
		(hatch none 0.5)
		(connect_pads
			(clearance 0)
		)
		(min_thickness 0.25)
		(keepout
			(tracks not_allowed)
			(vias allowed)
			(pads allowed)
			(copperpour not_allowed)
			(footprints allowed)
		)
		(placement
			(enabled no)
			(sheetname "")
		)
		(fill
			(thermal_gap 0.5)
			(thermal_bridge_width 0.5)
			(island_removal_mode 0)
		)
		(polygon
			(pts
				(xy 207.170528 -4.720082) (xy 207.729328 -4.720082) (xy 207.729328 -6.523482) (xy 207.170528 -6.523482)
			)
		)
	)
	(zone
		(layer "In12.Cu")
		(hatch none 0.5)
		(connect_pads
			(clearance 0)
		)
		(min_thickness 0.25)
		(keepout
			(tracks not_allowed)
			(vias allowed)
			(pads allowed)
			(copperpour not_allowed)
			(footprints allowed)
		)
		(placement
			(enabled no)
			(sheetname "")
		)
		(fill
			(thermal_gap 0.5)
			(thermal_bridge_width 0.5)
			(island_removal_mode 0)
		)
		(polygon
			(pts
				(xy 138.219942 -146.576542) (xy 138.778742 -146.576542) (xy 138.778742 -148.379942) (xy 138.219942 -148.379942)
			)
		)
	)
	(zone
		(layer "In12.Cu")
		(hatch none 0.5)
		(connect_pads
			(clearance 0)
		)
		(min_thickness 0.25)
		(keepout
			(tracks not_allowed)
			(vias allowed)
			(pads allowed)
			(copperpour not_allowed)
			(footprints allowed)
		)
		(placement
			(enabled no)
			(sheetname "")
		)
		(fill
			(thermal_gap 0.5)
			(thermal_bridge_width 0.5)
			(island_removal_mode 0)
		)
		(polygon
			(pts
				(xy 283.670502 -131.974082) (xy 284.229302 -131.974082) (xy 284.229302 -133.777482) (xy 283.670502 -133.777482)
			)
		)
	)
	(zone
		(layer "In12.Cu")
		(hatch none 0.5)
		(connect_pads
			(clearance 0)
		)
		(min_thickness 0.25)
		(keepout
			(tracks not_allowed)
			(vias allowed)
			(pads allowed)
			(copperpour not_allowed)
			(footprints allowed)
		)
		(placement
			(enabled no)
			(sheetname "")
		)
		(fill
			(thermal_gap 0.5)
			(thermal_bridge_width 0.5)
			(island_removal_mode 0)
		)
		(polygon
			(pts
				(xy 281.97048 -9.721342) (xy 282.52928 -9.721342) (xy 282.52928 -11.524742) (xy 281.97048 -11.524742)
			)
		)
	)
	(zone
		(layer "In12.Cu")
		(hatch none 0.5)
		(connect_pads
			(clearance 0)
		)
		(min_thickness 0.25)
		(keepout
			(tracks not_allowed)
			(vias allowed)
			(pads allowed)
			(copperpour not_allowed)
			(footprints allowed)
		)
		(placement
			(enabled no)
			(sheetname "")
		)
		(fill
			(thermal_gap 0.5)
			(thermal_bridge_width 0.5)
			(island_removal_mode 0)
		)
		(polygon
			(pts
				(xy 53.220112 -4.720082) (xy 53.778912 -4.720082) (xy 53.778912 -6.523482) (xy 53.220112 -6.523482)
			)
		)
	)
	(zone
		(layer "In12.Cu")
		(hatch none 0.5)
		(connect_pads
			(clearance 0)
		)
		(min_thickness 0.25)
		(keepout
			(tracks not_allowed)
			(vias allowed)
			(pads allowed)
			(copperpour not_allowed)
			(footprints allowed)
		)
		(placement
			(enabled no)
			(sheetname "")
		)
		(fill
			(thermal_gap 0.5)
			(thermal_bridge_width 0.5)
			(island_removal_mode 0)
		)
		(polygon
			(pts
				(xy 77.02042 -146.576542) (xy 77.57922 -146.576542) (xy 77.57922 -148.379942) (xy 77.02042 -148.379942)
			)
		)
	)
	(zone
		(layer "In12.Cu")
		(hatch none 0.5)
		(connect_pads
			(clearance 0)
		)
		(min_thickness 0.25)
		(keepout
			(tracks not_allowed)
			(vias allowed)
			(pads allowed)
			(copperpour not_allowed)
			(footprints allowed)
		)
		(placement
			(enabled no)
			(sheetname "")
		)
		(fill
			(thermal_gap 0.5)
			(thermal_bridge_width 0.5)
			(island_removal_mode 0)
		)
		(polygon
			(pts
				(xy 267.52042 -141.575282) (xy 268.07922 -141.575282) (xy 268.07922 -143.378682) (xy 267.52042 -143.378682)
			)
		)
	)
	(zone
		(layer "In12.Cu")
		(hatch none 0.5)
		(connect_pads
			(clearance 0)
		)
		(min_thickness 0.25)
		(keepout
			(tracks not_allowed)
			(vias allowed)
			(pads allowed)
			(copperpour not_allowed)
			(footprints allowed)
		)
		(placement
			(enabled no)
			(sheetname "")
		)
		(fill
			(thermal_gap 0.5)
			(thermal_bridge_width 0.5)
			(island_removal_mode 0)
		)
		(polygon
			(pts
				(xy 204.620368 -136.975342) (xy 205.179168 -136.975342) (xy 205.179168 -138.778742) (xy 204.620368 -138.778742)
			)
		)
	)
	(zone
		(layer "In12.Cu")
		(hatch none 0.5)
		(connect_pads
			(clearance 0)
		)
		(min_thickness 0.25)
		(keepout
			(tracks not_allowed)
			(vias allowed)
			(pads allowed)
			(copperpour not_allowed)
			(footprints allowed)
		)
		(placement
			(enabled no)
			(sheetname "")
		)
		(fill
			(thermal_gap 0.5)
			(thermal_bridge_width 0.5)
			(island_removal_mode 0)
		)
		(polygon
			(pts
				(xy 71.9201 -141.575282) (xy 72.4789 -141.575282) (xy 72.4789 -143.378682) (xy 71.9201 -143.378682)
			)
		)
	)
	(zone
		(layer "In12.Cu")
		(hatch none 0.5)
		(connect_pads
			(clearance 0)
		)
		(min_thickness 0.25)
		(keepout
			(tracks not_allowed)
			(vias allowed)
			(pads allowed)
			(copperpour not_allowed)
			(footprints allowed)
		)
		(placement
			(enabled no)
			(sheetname "")
		)
		(fill
			(thermal_gap 0.5)
			(thermal_bridge_width 0.5)
			(island_removal_mode 0)
		)
		(polygon
			(pts
				(xy 103.370126 -131.974082) (xy 103.928926 -131.974082) (xy 103.928926 -133.777482) (xy 103.370126 -133.777482)
			)
		)
	)
	(zone
		(layer "In12.Cu")
		(hatch none 0.5)
		(connect_pads
			(clearance 0)
		)
		(min_thickness 0.25)
		(keepout
			(tracks not_allowed)
			(vias allowed)
			(pads allowed)
			(copperpour not_allowed)
			(footprints allowed)
		)
		(placement
			(enabled no)
			(sheetname "")
		)
		(fill
			(thermal_gap 0.5)
			(thermal_bridge_width 0.5)
			(island_removal_mode 0)
		)
		(polygon
			(pts
				(xy 33.669986 -9.721342) (xy 34.228786 -9.721342) (xy 34.228786 -11.524742) (xy 33.669986 -11.524742)
			)
		)
	)
	(zone
		(layer "In12.Cu")
		(hatch none 0.5)
		(connect_pads
			(clearance 0)
		)
		(min_thickness 0.25)
		(keepout
			(tracks not_allowed)
			(vias allowed)
			(pads allowed)
			(copperpour not_allowed)
			(footprints allowed)
		)
		(placement
			(enabled no)
			(sheetname "")
		)
		(fill
			(thermal_gap 0.5)
			(thermal_bridge_width 0.5)
			(island_removal_mode 0)
		)
		(polygon
			(pts
				(xy 302.37049 -151.176482) (xy 302.92929 -151.176482) (xy 302.92929 -152.979882) (xy 302.37049 -152.979882)
			)
		)
	)
	(zone
		(layer "In12.Cu")
		(hatch none 0.5)
		(connect_pads
			(clearance 0)
		)
		(min_thickness 0.25)
		(keepout
			(tracks not_allowed)
			(vias allowed)
			(pads allowed)
			(copperpour not_allowed)
			(footprints allowed)
		)
		(placement
			(enabled no)
			(sheetname "")
		)
		(fill
			(thermal_gap 0.5)
			(thermal_bridge_width 0.5)
			(island_removal_mode 0)
		)
		(polygon
			(pts
				(xy 200.37044 -151.176482) (xy 200.92924 -151.176482) (xy 200.92924 -152.979882) (xy 200.37044 -152.979882)
			)
		)
	)
	(zone
		(layer "In12.Cu")
		(hatch none 0.5)
		(connect_pads
			(clearance 0)
		)
		(min_thickness 0.25)
		(keepout
			(tracks not_allowed)
			(vias allowed)
			(pads allowed)
			(copperpour not_allowed)
			(footprints allowed)
		)
		(placement
			(enabled no)
			(sheetname "")
		)
		(fill
			(thermal_gap 0.5)
			(thermal_bridge_width 0.5)
			(island_removal_mode 0)
		)
		(polygon
			(pts
				(xy 337.791806 -59.225434) (xy 337.791806 -61.511434) (xy 337.283806 -61.511434) (xy 337.283806 -59.225434)
			)
		)
	)
	(zone
		(layer "In12.Cu")
		(hatch none 0.5)
		(connect_pads
			(clearance 0)
		)
		(min_thickness 0.25)
		(keepout
			(tracks not_allowed)
			(vias allowed)
			(pads allowed)
			(copperpour not_allowed)
			(footprints allowed)
		)
		(placement
			(enabled no)
			(sheetname "")
		)
		(fill
			(thermal_gap 0.5)
			(thermal_bridge_width 0.5)
			(island_removal_mode 0)
		)
		(polygon
			(pts
				(xy 59.170062 -131.974082) (xy 59.728862 -131.974082) (xy 59.728862 -133.777482) (xy 59.170062 -133.777482)
			)
		)
	)
	(zone
		(layer "In12.Cu")
		(hatch none 0.5)
		(connect_pads
			(clearance 0)
		)
		(min_thickness 0.25)
		(keepout
			(tracks not_allowed)
			(vias allowed)
			(pads allowed)
			(copperpour not_allowed)
			(footprints allowed)
		)
		(placement
			(enabled no)
			(sheetname "")
		)
		(fill
			(thermal_gap 0.5)
			(thermal_bridge_width 0.5)
			(island_removal_mode 0)
		)
		(polygon
			(pts
				(xy 137.370058 -141.575282) (xy 137.928858 -141.575282) (xy 137.928858 -143.378682) (xy 137.370058 -143.378682)
			)
		)
	)
	(zone
		(layer "In12.Cu")
		(hatch none 0.5)
		(connect_pads
			(clearance 0)
		)
		(min_thickness 0.25)
		(keepout
			(tracks not_allowed)
			(vias allowed)
			(pads allowed)
			(copperpour not_allowed)
			(footprints allowed)
		)
		(placement
			(enabled no)
			(sheetname "")
		)
		(fill
			(thermal_gap 0.5)
			(thermal_bridge_width 0.5)
			(island_removal_mode 0)
		)
		(polygon
			(pts
				(xy 413.6136 -141.6558) (xy 413.6136 -142.4178) (xy 414.6042 -142.4178) (xy 414.6042 -141.6558)
			)
		)
	)
	(zone
		(layer "In12.Cu")
		(hatch none 0.5)
		(connect_pads
			(clearance 0)
		)
		(min_thickness 0.25)
		(keepout
			(tracks not_allowed)
			(vias allowed)
			(pads allowed)
			(copperpour not_allowed)
			(footprints allowed)
		)
		(placement
			(enabled no)
			(sheetname "")
		)
		(fill
			(thermal_gap 0.5)
			(thermal_bridge_width 0.5)
			(island_removal_mode 0)
		)
		(polygon
			(pts
				(xy 82.119978 -131.974082) (xy 82.678778 -131.974082) (xy 82.678778 -133.777482) (xy 82.119978 -133.777482)
			)
		)
	)
	(zone
		(layer "In12.Cu")
		(hatch none 0.5)
		(connect_pads
			(clearance 0)
		)
		(min_thickness 0.25)
		(keepout
			(tracks not_allowed)
			(vias allowed)
			(pads allowed)
			(copperpour not_allowed)
			(footprints allowed)
		)
		(placement
			(enabled no)
			(sheetname "")
		)
		(fill
			(thermal_gap 0.5)
			(thermal_bridge_width 0.5)
			(island_removal_mode 0)
		)
		(polygon
			(pts
				(xy 347.43136 -76.645516) (xy 347.43136 -78.931516) (xy 346.92336 -78.931516) (xy 346.92336 -76.645516)
			)
		)
	)
	(zone
		(layer "In12.Cu")
		(hatch none 0.5)
		(connect_pads
			(clearance 0)
		)
		(min_thickness 0.25)
		(keepout
			(tracks not_allowed)
			(vias allowed)
			(pads allowed)
			(copperpour not_allowed)
			(footprints allowed)
		)
		(placement
			(enabled no)
			(sheetname "")
		)
		(fill
			(thermal_gap 0.5)
			(thermal_bridge_width 0.5)
			(island_removal_mode 0)
		)
		(polygon
			(pts
				(xy 310.020462 -127.374142) (xy 310.579262 -127.374142) (xy 310.579262 -129.177542) (xy 310.020462 -129.177542)
			)
		)
	)
	(zone
		(layer "In12.Cu")
		(hatch none 0.5)
		(connect_pads
			(clearance 0)
		)
		(min_thickness 0.25)
		(keepout
			(tracks not_allowed)
			(vias allowed)
			(pads allowed)
			(copperpour not_allowed)
			(footprints allowed)
		)
		(placement
			(enabled no)
			(sheetname "")
		)
		(fill
			(thermal_gap 0.5)
			(thermal_bridge_width 0.5)
			(island_removal_mode 0)
		)
		(polygon
			(pts
				(xy 265.820398 -141.575282) (xy 266.379198 -141.575282) (xy 266.379198 -143.378682) (xy 265.820398 -143.378682)
			)
		)
	)
	(zone
		(layer "In12.Cu")
		(hatch none 0.5)
		(connect_pads
			(clearance 0)
		)
		(min_thickness 0.25)
		(keepout
			(tracks not_allowed)
			(vias allowed)
			(pads allowed)
			(copperpour not_allowed)
			(footprints allowed)
		)
		(placement
			(enabled no)
			(sheetname "")
		)
		(fill
			(thermal_gap 0.5)
			(thermal_bridge_width 0.5)
			(island_removal_mode 0)
		)
		(polygon
			(pts
				(xy 213.120478 -151.176482) (xy 213.679278 -151.176482) (xy 213.679278 -152.979882) (xy 213.120478 -152.979882)
			)
		)
	)
	(zone
		(layer "In12.Cu")
		(hatch none 0.5)
		(connect_pads
			(clearance 0)
		)
		(min_thickness 0.25)
		(keepout
			(tracks not_allowed)
			(vias allowed)
			(pads allowed)
			(copperpour not_allowed)
			(footprints allowed)
		)
		(placement
			(enabled no)
			(sheetname "")
		)
		(fill
			(thermal_gap 0.5)
			(thermal_bridge_width 0.5)
			(island_removal_mode 0)
		)
		(polygon
			(pts
				(xy 51.52009 -23.922482) (xy 52.07889 -23.922482) (xy 52.07889 -25.725882) (xy 51.52009 -25.725882)
			)
		)
	)
	(zone
		(layer "In12.Cu")
		(hatch none 0.5)
		(connect_pads
			(clearance 0)
		)
		(min_thickness 0.25)
		(keepout
			(tracks not_allowed)
			(vias allowed)
			(pads allowed)
			(copperpour not_allowed)
			(footprints allowed)
		)
		(placement
			(enabled no)
			(sheetname "")
		)
		(fill
			(thermal_gap 0.5)
			(thermal_bridge_width 0.5)
			(island_removal_mode 0)
		)
		(polygon
			(pts
				(xy 197.820534 -4.720082) (xy 198.379334 -4.720082) (xy 198.379334 -6.523482) (xy 197.820534 -6.523482)
			)
		)
	)
	(zone
		(layer "In12.Cu")
		(hatch none 0.5)
		(connect_pads
			(clearance 0)
		)
		(min_thickness 0.25)
		(keepout
			(tracks not_allowed)
			(vias allowed)
			(pads allowed)
			(copperpour not_allowed)
			(footprints allowed)
		)
		(placement
			(enabled no)
			(sheetname "")
		)
		(fill
			(thermal_gap 0.5)
			(thermal_bridge_width 0.5)
			(island_removal_mode 0)
		)
		(polygon
			(pts
				(xy 228.420422 -4.720082) (xy 228.979222 -4.720082) (xy 228.979222 -6.523482) (xy 228.420422 -6.523482)
			)
		)
	)
	(zone
		(layer "In12.Cu")
		(hatch none 0.5)
		(connect_pads
			(clearance 0)
		)
		(min_thickness 0.25)
		(keepout
			(tracks not_allowed)
			(vias allowed)
			(pads allowed)
			(copperpour not_allowed)
			(footprints allowed)
		)
		(placement
			(enabled no)
			(sheetname "")
		)
		(fill
			(thermal_gap 0.5)
			(thermal_bridge_width 0.5)
			(island_removal_mode 0)
		)
		(polygon
			(pts
				(xy 85.520022 -9.721342) (xy 86.078822 -9.721342) (xy 86.078822 -11.524742) (xy 85.520022 -11.524742)
			)
		)
	)
	(zone
		(layer "In12.Cu")
		(hatch none 0.5)
		(connect_pads
			(clearance 0)
		)
		(min_thickness 0.25)
		(keepout
			(tracks not_allowed)
			(vias allowed)
			(pads allowed)
			(copperpour not_allowed)
			(footprints allowed)
		)
		(placement
			(enabled no)
			(sheetname "")
		)
		(fill
			(thermal_gap 0.5)
			(thermal_bridge_width 0.5)
			(island_removal_mode 0)
		)
		(polygon
			(pts
				(xy 290.470336 -131.974082) (xy 291.029136 -131.974082) (xy 291.029136 -133.777482) (xy 290.470336 -133.777482)
			)
		)
	)
	(zone
		(layer "In12.Cu")
		(hatch none 0.5)
		(connect_pads
			(clearance 0)
		)
		(min_thickness 0.25)
		(keepout
			(tracks not_allowed)
			(vias allowed)
			(pads allowed)
			(copperpour not_allowed)
			(footprints allowed)
		)
		(placement
			(enabled no)
			(sheetname "")
		)
		(fill
			(thermal_gap 0.5)
			(thermal_bridge_width 0.5)
			(island_removal_mode 0)
		)
		(polygon
			(pts
				(xy 122.070114 -141.575282) (xy 122.628914 -141.575282) (xy 122.628914 -143.378682) (xy 122.070114 -143.378682)
			)
		)
	)
	(zone
		(layer "In12.Cu")
		(hatch none 0.5)
		(connect_pads
			(clearance 0)
		)
		(min_thickness 0.25)
		(keepout
			(tracks not_allowed)
			(vias allowed)
			(pads allowed)
			(copperpour not_allowed)
			(footprints allowed)
		)
		(placement
			(enabled no)
			(sheetname "")
		)
		(fill
			(thermal_gap 0.5)
			(thermal_bridge_width 0.5)
			(island_removal_mode 0)
		)
		(polygon
			(pts
				(xy 305.770534 -141.575282) (xy 306.329334 -141.575282) (xy 306.329334 -143.378682) (xy 305.770534 -143.378682)
			)
		)
	)
	(zone
		(layer "In12.Cu")
		(hatch none 0.5)
		(connect_pads
			(clearance 0)
		)
		(min_thickness 0.25)
		(keepout
			(tracks not_allowed)
			(vias allowed)
			(pads allowed)
			(copperpour not_allowed)
			(footprints allowed)
		)
		(placement
			(enabled no)
			(sheetname "")
		)
		(fill
			(thermal_gap 0.5)
			(thermal_bridge_width 0.5)
			(island_removal_mode 0)
		)
		(polygon
			(pts
				(xy 146.720052 -141.575282) (xy 147.278852 -141.575282) (xy 147.278852 -143.378682) (xy 146.720052 -143.378682)
			)
		)
	)
	(zone
		(layer "In12.Cu")
		(hatch none 0.5)
		(connect_pads
			(clearance 0)
		)
		(min_thickness 0.25)
		(keepout
			(tracks not_allowed)
			(vias allowed)
			(pads allowed)
			(copperpour not_allowed)
			(footprints allowed)
		)
		(placement
			(enabled no)
			(sheetname "")
		)
		(fill
			(thermal_gap 0.5)
			(thermal_bridge_width 0.5)
			(island_removal_mode 0)
		)
		(polygon
			(pts
				(xy 198.670418 -146.576542) (xy 199.229218 -146.576542) (xy 199.229218 -148.379942) (xy 198.670418 -148.379942)
			)
		)
	)
	(zone
		(layer "In12.Cu")
		(hatch none 0.5)
		(connect_pads
			(clearance 0)
		)
		(min_thickness 0.25)
		(keepout
			(tracks not_allowed)
			(vias allowed)
			(pads allowed)
			(copperpour not_allowed)
			(footprints allowed)
		)
		(placement
			(enabled no)
			(sheetname "")
		)
		(fill
			(thermal_gap 0.5)
			(thermal_bridge_width 0.5)
			(island_removal_mode 0)
		)
		(polygon
			(pts
				(xy 355.990398 -76.772516) (xy 355.990398 -79.058516) (xy 355.482398 -79.058516) (xy 355.482398 -76.772516)
			)
		)
	)
	(zone
		(layer "In12.Cu")
		(hatch none 0.5)
		(connect_pads
			(clearance 0)
		)
		(min_thickness 0.25)
		(keepout
			(tracks not_allowed)
			(vias allowed)
			(pads allowed)
			(copperpour not_allowed)
			(footprints allowed)
		)
		(placement
			(enabled no)
			(sheetname "")
		)
		(fill
			(thermal_gap 0.5)
			(thermal_bridge_width 0.5)
			(island_removal_mode 0)
		)
		(polygon
			(pts
				(xy 205.470506 -4.720082) (xy 206.029306 -4.720082) (xy 206.029306 -6.523482) (xy 205.470506 -6.523482)
			)
		)
	)
	(zone
		(layer "In12.Cu")
		(hatch none 0.5)
		(connect_pads
			(clearance 0)
		)
		(min_thickness 0.25)
		(keepout
			(tracks not_allowed)
			(vias allowed)
			(pads allowed)
			(copperpour not_allowed)
			(footprints allowed)
		)
		(placement
			(enabled no)
			(sheetname "")
		)
		(fill
			(thermal_gap 0.5)
			(thermal_bridge_width 0.5)
			(island_removal_mode 0)
		)
		(polygon
			(pts
				(xy 73.620122 -0.120142) (xy 74.178922 -0.120142) (xy 74.178922 -1.923542) (xy 73.620122 -1.923542)
			)
		)
	)
	(zone
		(layer "In12.Cu")
		(hatch none 0.5)
		(connect_pads
			(clearance 0)
		)
		(min_thickness 0.25)
		(keepout
			(tracks not_allowed)
			(vias allowed)
			(pads allowed)
			(copperpour not_allowed)
			(footprints allowed)
		)
		(placement
			(enabled no)
			(sheetname "")
		)
		(fill
			(thermal_gap 0.5)
			(thermal_bridge_width 0.5)
			(island_removal_mode 0)
		)
		(polygon
			(pts
				(xy 81.270094 -23.922482) (xy 81.828894 -23.922482) (xy 81.828894 -25.725882) (xy 81.270094 -25.725882)
			)
		)
	)
	(zone
		(layer "In12.Cu")
		(hatch none 0.5)
		(connect_pads
			(clearance 0)
		)
		(min_thickness 0.25)
		(keepout
			(tracks not_allowed)
			(vias allowed)
			(pads allowed)
			(copperpour not_allowed)
			(footprints allowed)
		)
		(placement
			(enabled no)
			(sheetname "")
		)
		(fill
			(thermal_gap 0.5)
			(thermal_bridge_width 0.5)
			(island_removal_mode 0)
		)
		(polygon
			(pts
				(xy 82.970116 -127.374142) (xy 83.528916 -127.374142) (xy 83.528916 -129.177542) (xy 82.970116 -129.177542)
			)
		)
	)
	(zone
		(layer "In12.Cu")
		(hatch none 0.5)
		(connect_pads
			(clearance 0)
		)
		(min_thickness 0.25)
		(keepout
			(tracks not_allowed)
			(vias allowed)
			(pads allowed)
			(copperpour not_allowed)
			(footprints allowed)
		)
		(placement
			(enabled no)
			(sheetname "")
		)
		(fill
			(thermal_gap 0.5)
			(thermal_bridge_width 0.5)
			(island_removal_mode 0)
		)
		(polygon
			(pts
				(xy 125.469904 -131.974082) (xy 126.028704 -131.974082) (xy 126.028704 -133.777482) (xy 125.469904 -133.777482)
			)
		)
	)
	(zone
		(layer "In12.Cu")
		(hatch none 0.5)
		(connect_pads
			(clearance 0)
		)
		(min_thickness 0.25)
		(keepout
			(tracks not_allowed)
			(vias allowed)
			(pads allowed)
			(copperpour not_allowed)
			(footprints allowed)
		)
		(placement
			(enabled no)
			(sheetname "")
		)
		(fill
			(thermal_gap 0.5)
			(thermal_bridge_width 0.5)
			(island_removal_mode 0)
		)
		(polygon
			(pts
				(xy 89.76995 -9.721342) (xy 90.32875 -9.721342) (xy 90.32875 -11.524742) (xy 89.76995 -11.524742)
			)
		)
	)
	(zone
		(layer "In12.Cu")
		(hatch none 0.5)
		(connect_pads
			(clearance 0)
		)
		(min_thickness 0.25)
		(keepout
			(tracks not_allowed)
			(vias allowed)
			(pads allowed)
			(copperpour not_allowed)
			(footprints allowed)
		)
		(placement
			(enabled no)
			(sheetname "")
		)
		(fill
			(thermal_gap 0.5)
			(thermal_bridge_width 0.5)
			(island_removal_mode 0)
		)
		(polygon
			(pts
				(xy 306.620418 -19.322542) (xy 307.179218 -19.322542) (xy 307.179218 -21.125942) (xy 306.620418 -21.125942)
			)
		)
	)
	(zone
		(layer "In12.Cu")
		(hatch none 0.5)
		(connect_pads
			(clearance 0)
		)
		(min_thickness 0.25)
		(keepout
			(tracks not_allowed)
			(vias allowed)
			(pads allowed)
			(copperpour not_allowed)
			(footprints allowed)
		)
		(placement
			(enabled no)
			(sheetname "")
		)
		(fill
			(thermal_gap 0.5)
			(thermal_bridge_width 0.5)
			(island_removal_mode 0)
		)
		(polygon
			(pts
				(xy 242.020852 -127.374142) (xy 242.579652 -127.374142) (xy 242.579652 -129.177542) (xy 242.020852 -129.177542)
			)
		)
	)
	(zone
		(layer "In12.Cu")
		(hatch none 0.5)
		(connect_pads
			(clearance 0)
		)
		(min_thickness 0.25)
		(keepout
			(tracks not_allowed)
			(vias allowed)
			(pads allowed)
			(copperpour not_allowed)
			(footprints allowed)
		)
		(placement
			(enabled no)
			(sheetname "")
		)
		(fill
			(thermal_gap 0.5)
			(thermal_bridge_width 0.5)
			(island_removal_mode 0)
		)
		(polygon
			(pts
				(xy 257.320542 -23.922482) (xy 257.879342 -23.922482) (xy 257.879342 -25.725882) (xy 257.320542 -25.725882)
			)
		)
	)
	(zone
		(layer "In12.Cu")
		(hatch none 0.5)
		(connect_pads
			(clearance 0)
		)
		(min_thickness 0.25)
		(keepout
			(tracks not_allowed)
			(vias allowed)
			(pads allowed)
			(copperpour not_allowed)
			(footprints allowed)
		)
		(placement
			(enabled no)
			(sheetname "")
		)
		(fill
			(thermal_gap 0.5)
			(thermal_bridge_width 0.5)
			(island_removal_mode 0)
		)
		(polygon
			(pts
				(xy 275.170392 -127.374142) (xy 275.729192 -127.374142) (xy 275.729192 -129.177542) (xy 275.170392 -129.177542)
			)
		)
	)
	(zone
		(layer "In12.Cu")
		(hatch none 0.5)
		(connect_pads
			(clearance 0)
		)
		(min_thickness 0.25)
		(keepout
			(tracks not_allowed)
			(vias allowed)
			(pads allowed)
			(copperpour not_allowed)
			(footprints allowed)
		)
		(placement
			(enabled no)
			(sheetname "")
		)
		(fill
			(thermal_gap 0.5)
			(thermal_bridge_width 0.5)
			(island_removal_mode 0)
		)
		(polygon
			(pts
				(xy 266.670536 -146.576542) (xy 267.229336 -146.576542) (xy 267.229336 -148.379942) (xy 266.670536 -148.379942)
			)
		)
	)
	(zone
		(layer "In12.Cu")
		(hatch none 0.5)
		(connect_pads
			(clearance 0)
		)
		(min_thickness 0.25)
		(keepout
			(tracks not_allowed)
			(vias allowed)
			(pads allowed)
			(copperpour not_allowed)
			(footprints allowed)
		)
		(placement
			(enabled no)
			(sheetname "")
		)
		(fill
			(thermal_gap 0.5)
			(thermal_bridge_width 0.5)
			(island_removal_mode 0)
		)
		(polygon
			(pts
				(xy 247.970548 -136.975342) (xy 248.529348 -136.975342) (xy 248.529348 -138.778742) (xy 247.970548 -138.778742)
			)
		)
	)
	(zone
		(layer "In12.Cu")
		(hatch none 0.5)
		(connect_pads
			(clearance 0)
		)
		(min_thickness 0.25)
		(keepout
			(tracks not_allowed)
			(vias allowed)
			(pads allowed)
			(copperpour not_allowed)
			(footprints allowed)
		)
		(placement
			(enabled no)
			(sheetname "")
		)
		(fill
			(thermal_gap 0.5)
			(thermal_bridge_width 0.5)
			(island_removal_mode 0)
		)
		(polygon
			(pts
				(xy 224.170494 -141.575282) (xy 224.729294 -141.575282) (xy 224.729294 -143.378682) (xy 224.170494 -143.378682)
			)
		)
	)
	(zone
		(layer "In12.Cu")
		(hatch none 0.5)
		(connect_pads
			(clearance 0)
		)
		(min_thickness 0.25)
		(keepout
			(tracks not_allowed)
			(vias allowed)
			(pads allowed)
			(copperpour not_allowed)
			(footprints allowed)
		)
		(placement
			(enabled no)
			(sheetname "")
		)
		(fill
			(thermal_gap 0.5)
			(thermal_bridge_width 0.5)
			(island_removal_mode 0)
		)
		(polygon
			(pts
				(xy 442.595 -115.34902) (xy 443.103 -115.34902) (xy 443.103 -116.74602) (xy 442.595 -116.74602)
			)
		)
	)
	(zone
		(layer "In12.Cu")
		(hatch none 0.5)
		(connect_pads
			(clearance 0)
		)
		(min_thickness 0.25)
		(keepout
			(tracks not_allowed)
			(vias allowed)
			(pads allowed)
			(copperpour not_allowed)
			(footprints allowed)
		)
		(placement
			(enabled no)
			(sheetname "")
		)
		(fill
			(thermal_gap 0.5)
			(thermal_bridge_width 0.5)
			(island_removal_mode 0)
		)
		(polygon
			(pts
				(xy 256.470404 -4.720082) (xy 257.029204 -4.720082) (xy 257.029204 -6.523482) (xy 256.470404 -6.523482)
			)
		)
	)
	(zone
		(layer "In12.Cu")
		(hatch none 0.5)
		(connect_pads
			(clearance 0)
		)
		(min_thickness 0.25)
		(keepout
			(tracks not_allowed)
			(vias allowed)
			(pads allowed)
			(copperpour not_allowed)
			(footprints allowed)
		)
		(placement
			(enabled no)
			(sheetname "")
		)
		(fill
			(thermal_gap 0.5)
			(thermal_bridge_width 0.5)
			(island_removal_mode 0)
		)
		(polygon
			(pts
				(xy 305.770534 -14.321282) (xy 306.329334 -14.321282) (xy 306.329334 -16.124682) (xy 305.770534 -16.124682)
			)
		)
	)
	(zone
		(layer "In12.Cu")
		(hatch none 0.5)
		(connect_pads
			(clearance 0)
		)
		(min_thickness 0.25)
		(keepout
			(tracks not_allowed)
			(vias allowed)
			(pads allowed)
			(copperpour not_allowed)
			(footprints allowed)
		)
		(placement
			(enabled no)
			(sheetname "")
		)
		(fill
			(thermal_gap 0.5)
			(thermal_bridge_width 0.5)
			(island_removal_mode 0)
		)
		(polygon
			(pts
				(xy 216.520522 -14.321282) (xy 217.079322 -14.321282) (xy 217.079322 -16.124682) (xy 216.520522 -16.124682)
			)
		)
	)
	(zone
		(layer "In12.Cu")
		(hatch none 0.5)
		(connect_pads
			(clearance 0)
		)
		(min_thickness 0.25)
		(keepout
			(tracks not_allowed)
			(vias allowed)
			(pads allowed)
			(copperpour not_allowed)
			(footprints allowed)
		)
		(placement
			(enabled no)
			(sheetname "")
		)
		(fill
			(thermal_gap 0.5)
			(thermal_bridge_width 0.5)
			(island_removal_mode 0)
		)
		(polygon
			(pts
				(xy 146.720052 -146.576542) (xy 147.278852 -146.576542) (xy 147.278852 -148.379942) (xy 146.720052 -148.379942)
			)
		)
	)
	(zone
		(layer "In12.Cu")
		(hatch none 0.5)
		(connect_pads
			(clearance 0)
		)
		(min_thickness 0.25)
		(keepout
			(tracks not_allowed)
			(vias allowed)
			(pads allowed)
			(copperpour not_allowed)
			(footprints allowed)
		)
		(placement
			(enabled no)
			(sheetname "")
		)
		(fill
			(thermal_gap 0.5)
			(thermal_bridge_width 0.5)
			(island_removal_mode 0)
		)
		(polygon
			(pts
				(xy 127.169926 -4.720082) (xy 127.728726 -4.720082) (xy 127.728726 -6.523482) (xy 127.169926 -6.523482)
			)
		)
	)
	(zone
		(layer "In12.Cu")
		(hatch none 0.5)
		(connect_pads
			(clearance 0)
		)
		(min_thickness 0.25)
		(keepout
			(tracks not_allowed)
			(vias allowed)
			(pads allowed)
			(copperpour not_allowed)
			(footprints allowed)
		)
		(placement
			(enabled no)
			(sheetname "")
		)
		(fill
			(thermal_gap 0.5)
			(thermal_bridge_width 0.5)
			(island_removal_mode 0)
		)
		(polygon
			(pts
				(xy 283.670502 -127.374142) (xy 284.229302 -127.374142) (xy 284.229302 -129.177542) (xy 283.670502 -129.177542)
			)
		)
	)
	(zone
		(layer "In12.Cu")
		(hatch none 0.5)
		(connect_pads
			(clearance 0)
		)
		(min_thickness 0.25)
		(keepout
			(tracks not_allowed)
			(vias allowed)
			(pads allowed)
			(copperpour not_allowed)
			(footprints allowed)
		)
		(placement
			(enabled no)
			(sheetname "")
		)
		(fill
			(thermal_gap 0.5)
			(thermal_bridge_width 0.5)
			(island_removal_mode 0)
		)
		(polygon
			(pts
				(xy 462.788 -115.34902) (xy 463.296 -115.34902) (xy 463.296 -116.74602) (xy 462.788 -116.74602)
			)
		)
	)
	(zone
		(layer "In12.Cu")
		(hatch none 0.5)
		(connect_pads
			(clearance 0)
		)
		(min_thickness 0.25)
		(keepout
			(tracks not_allowed)
			(vias allowed)
			(pads allowed)
			(copperpour not_allowed)
			(footprints allowed)
		)
		(placement
			(enabled no)
			(sheetname "")
		)
		(fill
			(thermal_gap 0.5)
			(thermal_bridge_width 0.5)
			(island_removal_mode 0)
		)
		(polygon
			(pts
				(xy 292.170358 -151.176482) (xy 292.729158 -151.176482) (xy 292.729158 -152.979882) (xy 292.170358 -152.979882)
			)
		)
	)
	(zone
		(layer "In12.Cu")
		(hatch none 0.5)
		(connect_pads
			(clearance 0)
		)
		(min_thickness 0.25)
		(keepout
			(tracks not_allowed)
			(vias allowed)
			(pads allowed)
			(copperpour not_allowed)
			(footprints allowed)
		)
		(placement
			(enabled no)
			(sheetname "")
		)
		(fill
			(thermal_gap 0.5)
			(thermal_bridge_width 0.5)
			(island_removal_mode 0)
		)
		(polygon
			(pts
				(xy 268.370558 -141.575282) (xy 268.929358 -141.575282) (xy 268.929358 -143.378682) (xy 268.370558 -143.378682)
			)
		)
	)
	(zone
		(layer "In12.Cu")
		(hatch none 0.5)
		(connect_pads
			(clearance 0)
		)
		(min_thickness 0.25)
		(keepout
			(tracks not_allowed)
			(vias allowed)
			(pads allowed)
			(copperpour not_allowed)
			(footprints allowed)
		)
		(placement
			(enabled no)
			(sheetname "")
		)
		(fill
			(thermal_gap 0.5)
			(thermal_bridge_width 0.5)
			(island_removal_mode 0)
		)
		(polygon
			(pts
				(xy 298.970446 -19.322542) (xy 299.529246 -19.322542) (xy 299.529246 -21.125942) (xy 298.970446 -21.125942)
			)
		)
	)
	(zone
		(layer "In12.Cu")
		(hatch none 0.5)
		(connect_pads
			(clearance 0)
		)
		(min_thickness 0.25)
		(keepout
			(tracks not_allowed)
			(vias allowed)
			(pads allowed)
			(copperpour not_allowed)
			(footprints allowed)
		)
		(placement
			(enabled no)
			(sheetname "")
		)
		(fill
			(thermal_gap 0.5)
			(thermal_bridge_width 0.5)
			(island_removal_mode 0)
		)
		(polygon
			(pts
				(xy 33.669986 -19.322542) (xy 34.228786 -19.322542) (xy 34.228786 -21.125942) (xy 33.669986 -21.125942)
			)
		)
	)
	(zone
		(layer "In12.Cu")
		(hatch none 0.5)
		(connect_pads
			(clearance 0)
		)
		(min_thickness 0.25)
		(keepout
			(tracks not_allowed)
			(vias allowed)
			(pads allowed)
			(copperpour not_allowed)
			(footprints allowed)
		)
		(placement
			(enabled no)
			(sheetname "")
		)
		(fill
			(thermal_gap 0.5)
			(thermal_bridge_width 0.5)
			(island_removal_mode 0)
		)
		(polygon
			(pts
				(xy 60.019946 -0.120142) (xy 60.578746 -0.120142) (xy 60.578746 -1.923542) (xy 60.019946 -1.923542)
			)
		)
	)
	(zone
		(layer "In12.Cu")
		(hatch none 0.5)
		(connect_pads
			(clearance 0)
		)
		(min_thickness 0.25)
		(keepout
			(tracks not_allowed)
			(vias allowed)
			(pads allowed)
			(copperpour not_allowed)
			(footprints allowed)
		)
		(placement
			(enabled no)
			(sheetname "")
		)
		(fill
			(thermal_gap 0.5)
			(thermal_bridge_width 0.5)
			(island_removal_mode 0)
		)
		(polygon
			(pts
				(xy 197.820534 -23.922482) (xy 198.379334 -23.922482) (xy 198.379334 -25.725882) (xy 197.820534 -25.725882)
			)
		)
	)
	(zone
		(layer "In12.Cu")
		(hatch none 0.5)
		(connect_pads
			(clearance 0)
		)
		(min_thickness 0.25)
		(keepout
			(tracks not_allowed)
			(vias allowed)
			(pads allowed)
			(copperpour not_allowed)
			(footprints allowed)
		)
		(placement
			(enabled no)
			(sheetname "")
		)
		(fill
			(thermal_gap 0.5)
			(thermal_bridge_width 0.5)
			(island_removal_mode 0)
		)
		(polygon
			(pts
				(xy 88.070182 -136.975342) (xy 88.628982 -136.975342) (xy 88.628982 -138.778742) (xy 88.070182 -138.778742)
			)
		)
	)
	(zone
		(layer "In12.Cu")
		(hatch none 0.5)
		(connect_pads
			(clearance 0)
		)
		(min_thickness 0.25)
		(keepout
			(tracks not_allowed)
			(vias allowed)
			(pads allowed)
			(copperpour not_allowed)
			(footprints allowed)
		)
		(placement
			(enabled no)
			(sheetname "")
		)
		(fill
			(thermal_gap 0.5)
			(thermal_bridge_width 0.5)
			(island_removal_mode 0)
		)
		(polygon
			(pts
				(xy 128.020064 -0.120142) (xy 128.578864 -0.120142) (xy 128.578864 -1.923542) (xy 128.020064 -1.923542)
			)
		)
	)
	(zone
		(layer "In12.Cu")
		(hatch none 0.5)
		(connect_pads
			(clearance 0)
		)
		(min_thickness 0.25)
		(keepout
			(tracks not_allowed)
			(vias allowed)
			(pads allowed)
			(copperpour not_allowed)
			(footprints allowed)
		)
		(placement
			(enabled no)
			(sheetname "")
		)
		(fill
			(thermal_gap 0.5)
			(thermal_bridge_width 0.5)
			(island_removal_mode 0)
		)
		(polygon
			(pts
				(xy 54.069996 -4.720082) (xy 54.628796 -4.720082) (xy 54.628796 -6.523482) (xy 54.069996 -6.523482)
			)
		)
	)
	(zone
		(layer "In12.Cu")
		(hatch none 0.5)
		(connect_pads
			(clearance 0)
		)
		(min_thickness 0.25)
		(keepout
			(tracks not_allowed)
			(vias allowed)
			(pads allowed)
			(copperpour not_allowed)
			(footprints allowed)
		)
		(placement
			(enabled no)
			(sheetname "")
		)
		(fill
			(thermal_gap 0.5)
			(thermal_bridge_width 0.5)
			(island_removal_mode 0)
		)
		(polygon
			(pts
				(xy 56.620156 -9.721342) (xy 57.178956 -9.721342) (xy 57.178956 -11.524742) (xy 56.620156 -11.524742)
			)
		)
	)
	(zone
		(layer "In12.Cu")
		(hatch none 0.5)
		(connect_pads
			(clearance 0)
		)
		(min_thickness 0.25)
		(keepout
			(tracks not_allowed)
			(vias allowed)
			(pads allowed)
			(copperpour not_allowed)
			(footprints allowed)
		)
		(placement
			(enabled no)
			(sheetname "")
		)
		(fill
			(thermal_gap 0.5)
			(thermal_bridge_width 0.5)
			(island_removal_mode 0)
		)
		(polygon
			(pts
				(xy 219.920566 -146.576542) (xy 220.479366 -146.576542) (xy 220.479366 -148.379942) (xy 219.920566 -148.379942)
			)
		)
	)
	(zone
		(layer "In12.Cu")
		(hatch none 0.5)
		(connect_pads
			(clearance 0)
		)
		(min_thickness 0.25)
		(keepout
			(tracks not_allowed)
			(vias allowed)
			(pads allowed)
			(copperpour not_allowed)
			(footprints allowed)
		)
		(placement
			(enabled no)
			(sheetname "")
		)
		(fill
			(thermal_gap 0.5)
			(thermal_bridge_width 0.5)
			(island_removal_mode 0)
		)
		(polygon
			(pts
				(xy 274.320508 -151.176482) (xy 274.879308 -151.176482) (xy 274.879308 -152.979882) (xy 274.320508 -152.979882)
			)
		)
	)
	(zone
		(layer "In12.Cu")
		(hatch none 0.5)
		(connect_pads
			(clearance 0)
		)
		(min_thickness 0.25)
		(keepout
			(tracks not_allowed)
			(vias allowed)
			(pads allowed)
			(copperpour not_allowed)
			(footprints allowed)
		)
		(placement
			(enabled no)
			(sheetname "")
		)
		(fill
			(thermal_gap 0.5)
			(thermal_bridge_width 0.5)
			(island_removal_mode 0)
		)
		(polygon
			(pts
				(xy 65.97015 -136.975342) (xy 66.52895 -136.975342) (xy 66.52895 -138.778742) (xy 65.97015 -138.778742)
			)
		)
	)
	(zone
		(layer "In12.Cu")
		(hatch none 0.5)
		(connect_pads
			(clearance 0)
		)
		(min_thickness 0.25)
		(keepout
			(tracks not_allowed)
			(vias allowed)
			(pads allowed)
			(copperpour not_allowed)
			(footprints allowed)
		)
		(placement
			(enabled no)
			(sheetname "")
		)
		(fill
			(thermal_gap 0.5)
			(thermal_bridge_width 0.5)
			(island_removal_mode 0)
		)
		(polygon
			(pts
				(xy 298.120308 -14.321282) (xy 298.679108 -14.321282) (xy 298.679108 -16.124682) (xy 298.120308 -16.124682)
			)
		)
	)
	(zone
		(layer "In12.Cu")
		(hatch none 0.5)
		(connect_pads
			(clearance 0)
		)
		(min_thickness 0.25)
		(keepout
			(tracks not_allowed)
			(vias allowed)
			(pads allowed)
			(copperpour not_allowed)
			(footprints allowed)
		)
		(placement
			(enabled no)
			(sheetname "")
		)
		(fill
			(thermal_gap 0.5)
			(thermal_bridge_width 0.5)
			(island_removal_mode 0)
		)
		(polygon
			(pts
				(xy 114.419888 -151.176482) (xy 114.978688 -151.176482) (xy 114.978688 -152.979882) (xy 114.419888 -152.979882)
			)
		)
	)
	(zone
		(layer "In12.Cu")
		(hatch none 0.5)
		(connect_pads
			(clearance 0)
		)
		(min_thickness 0.25)
		(keepout
			(tracks not_allowed)
			(vias allowed)
			(pads allowed)
			(copperpour not_allowed)
			(footprints allowed)
		)
		(placement
			(enabled no)
			(sheetname "")
		)
		(fill
			(thermal_gap 0.5)
			(thermal_bridge_width 0.5)
			(island_removal_mode 0)
		)
		(polygon
			(pts
				(xy 291.320474 -146.576542) (xy 291.879274 -146.576542) (xy 291.879274 -148.379942) (xy 291.320474 -148.379942)
			)
		)
	)
	(zone
		(layer "In12.Cu")
		(hatch none 0.5)
		(connect_pads
			(clearance 0)
		)
		(min_thickness 0.25)
		(keepout
			(tracks not_allowed)
			(vias allowed)
			(pads allowed)
			(copperpour not_allowed)
			(footprints allowed)
		)
		(placement
			(enabled no)
			(sheetname "")
		)
		(fill
			(thermal_gap 0.5)
			(thermal_bridge_width 0.5)
			(island_removal_mode 0)
		)
		(polygon
			(pts
				(xy 249.67057 -146.576542) (xy 250.22937 -146.576542) (xy 250.22937 -148.379942) (xy 249.67057 -148.379942)
			)
		)
	)
	(zone
		(layer "In12.Cu")
		(hatch none 0.5)
		(connect_pads
			(clearance 0)
		)
		(min_thickness 0.25)
		(keepout
			(tracks not_allowed)
			(vias allowed)
			(pads allowed)
			(copperpour not_allowed)
			(footprints allowed)
		)
		(placement
			(enabled no)
			(sheetname "")
		)
		(fill
			(thermal_gap 0.5)
			(thermal_bridge_width 0.5)
			(island_removal_mode 0)
		)
		(polygon
			(pts
				(xy 105.070148 -127.374142) (xy 105.628948 -127.374142) (xy 105.628948 -129.177542) (xy 105.070148 -129.177542)
			)
		)
	)
	(zone
		(layer "In12.Cu")
		(hatch none 0.5)
		(connect_pads
			(clearance 0)
		)
		(min_thickness 0.25)
		(keepout
			(tracks not_allowed)
			(vias allowed)
			(pads allowed)
			(copperpour not_allowed)
			(footprints allowed)
		)
		(placement
			(enabled no)
			(sheetname "")
		)
		(fill
			(thermal_gap 0.5)
			(thermal_bridge_width 0.5)
			(island_removal_mode 0)
		)
		(polygon
			(pts
				(xy 334.997806 -59.225434) (xy 334.997806 -61.511434) (xy 334.489806 -61.511434) (xy 334.489806 -59.225434)
			)
		)
	)
	(zone
		(layer "In12.Cu")
		(hatch none 0.5)
		(connect_pads
			(clearance 0)
		)
		(min_thickness 0.25)
		(keepout
			(tracks not_allowed)
			(vias allowed)
			(pads allowed)
			(copperpour not_allowed)
			(footprints allowed)
		)
		(placement
			(enabled no)
			(sheetname "")
		)
		(fill
			(thermal_gap 0.5)
			(thermal_bridge_width 0.5)
			(island_removal_mode 0)
		)
		(polygon
			(pts
				(xy 37.07003 -23.922482) (xy 37.62883 -23.922482) (xy 37.62883 -25.725882) (xy 37.07003 -25.725882)
			)
		)
	)
	(zone
		(layer "In12.Cu")
		(hatch none 0.5)
		(connect_pads
			(clearance 0)
		)
		(min_thickness 0.25)
		(keepout
			(tracks not_allowed)
			(vias allowed)
			(pads allowed)
			(copperpour not_allowed)
			(footprints allowed)
		)
		(placement
			(enabled no)
			(sheetname "")
		)
		(fill
			(thermal_gap 0.5)
			(thermal_bridge_width 0.5)
			(island_removal_mode 0)
		)
		(polygon
			(pts
				(xy 89.76995 -19.322542) (xy 90.32875 -19.322542) (xy 90.32875 -21.125942) (xy 89.76995 -21.125942)
			)
		)
	)
	(zone
		(layer "In12.Cu")
		(hatch none 0.5)
		(connect_pads
			(clearance 0)
		)
		(min_thickness 0.25)
		(keepout
			(tracks not_allowed)
			(vias allowed)
			(pads allowed)
			(copperpour not_allowed)
			(footprints allowed)
		)
		(placement
			(enabled no)
			(sheetname "")
		)
		(fill
			(thermal_gap 0.5)
			(thermal_bridge_width 0.5)
			(island_removal_mode 0)
		)
		(polygon
			(pts
				(xy 289.620452 -19.322542) (xy 290.179252 -19.322542) (xy 290.179252 -21.125942) (xy 289.620452 -21.125942)
			)
		)
	)
	(zone
		(layer "In12.Cu")
		(hatch none 0.5)
		(connect_pads
			(clearance 0)
		)
		(min_thickness 0.25)
		(keepout
			(tracks not_allowed)
			(vias allowed)
			(pads allowed)
			(copperpour not_allowed)
			(footprints allowed)
		)
		(placement
			(enabled no)
			(sheetname "")
		)
		(fill
			(thermal_gap 0.5)
			(thermal_bridge_width 0.5)
			(island_removal_mode 0)
		)
		(polygon
			(pts
				(xy 112.72012 -136.975342) (xy 113.27892 -136.975342) (xy 113.27892 -138.778742) (xy 112.72012 -138.778742)
			)
		)
	)
	(zone
		(layer "In12.Cu")
		(hatch none 0.5)
		(connect_pads
			(clearance 0)
		)
		(min_thickness 0.25)
		(keepout
			(tracks not_allowed)
			(vias allowed)
			(pads allowed)
			(copperpour not_allowed)
			(footprints allowed)
		)
		(placement
			(enabled no)
			(sheetname "")
		)
		(fill
			(thermal_gap 0.5)
			(thermal_bridge_width 0.5)
			(island_removal_mode 0)
		)
		(polygon
			(pts
				(xy 241.170714 -151.176482) (xy 241.729514 -151.176482) (xy 241.729514 -152.979882) (xy 241.170714 -152.979882)
			)
		)
	)
	(zone
		(layer "In12.Cu")
		(hatch none 0.5)
		(connect_pads
			(clearance 0)
		)
		(min_thickness 0.25)
		(keepout
			(tracks not_allowed)
			(vias allowed)
			(pads allowed)
			(copperpour not_allowed)
			(footprints allowed)
		)
		(placement
			(enabled no)
			(sheetname "")
		)
		(fill
			(thermal_gap 0.5)
			(thermal_bridge_width 0.5)
			(island_removal_mode 0)
		)
		(polygon
			(pts
				(xy 305.770534 -131.974082) (xy 306.329334 -131.974082) (xy 306.329334 -133.777482) (xy 305.770534 -133.777482)
			)
		)
	)
	(zone
		(layer "In12.Cu")
		(hatch none 0.5)
		(connect_pads
			(clearance 0)
		)
		(min_thickness 0.25)
		(keepout
			(tracks not_allowed)
			(vias allowed)
			(pads allowed)
			(copperpour not_allowed)
			(footprints allowed)
		)
		(placement
			(enabled no)
			(sheetname "")
		)
		(fill
			(thermal_gap 0.5)
			(thermal_bridge_width 0.5)
			(island_removal_mode 0)
		)
		(polygon
			(pts
				(xy 303.220374 -127.374142) (xy 303.779174 -127.374142) (xy 303.779174 -129.177542) (xy 303.220374 -129.177542)
			)
		)
	)
	(zone
		(layer "In12.Cu")
		(hatch none 0.5)
		(connect_pads
			(clearance 0)
		)
		(min_thickness 0.25)
		(keepout
			(tracks not_allowed)
			(vias allowed)
			(pads allowed)
			(copperpour not_allowed)
			(footprints allowed)
		)
		(placement
			(enabled no)
			(sheetname "")
		)
		(fill
			(thermal_gap 0.5)
			(thermal_bridge_width 0.5)
			(island_removal_mode 0)
		)
		(polygon
			(pts
				(xy 123.769882 -151.176482) (xy 124.328682 -151.176482) (xy 124.328682 -152.979882) (xy 123.769882 -152.979882)
			)
		)
	)
	(zone
		(layer "In12.Cu")
		(hatch none 0.5)
		(connect_pads
			(clearance 0)
		)
		(min_thickness 0.25)
		(keepout
			(tracks not_allowed)
			(vias allowed)
			(pads allowed)
			(copperpour not_allowed)
			(footprints allowed)
		)
		(placement
			(enabled no)
			(sheetname "")
		)
		(fill
			(thermal_gap 0.5)
			(thermal_bridge_width 0.5)
			(island_removal_mode 0)
		)
		(polygon
			(pts
				(xy 350.364806 -59.225434) (xy 350.364806 -61.511434) (xy 349.856806 -61.511434) (xy 349.856806 -59.225434)
			)
		)
	)
	(zone
		(layer "In12.Cu")
		(hatch none 0.5)
		(connect_pads
			(clearance 0)
		)
		(min_thickness 0.25)
		(keepout
			(tracks not_allowed)
			(vias allowed)
			(pads allowed)
			(copperpour not_allowed)
			(footprints allowed)
		)
		(placement
			(enabled no)
			(sheetname "")
		)
		(fill
			(thermal_gap 0.5)
			(thermal_bridge_width 0.5)
			(island_removal_mode 0)
		)
		(polygon
			(pts
				(xy 122.070114 -4.720082) (xy 122.628914 -4.720082) (xy 122.628914 -6.523482) (xy 122.070114 -6.523482)
			)
		)
	)
	(zone
		(layer "In12.Cu")
		(hatch none 0.5)
		(connect_pads
			(clearance 0)
		)
		(min_thickness 0.25)
		(keepout
			(tracks not_allowed)
			(vias allowed)
			(pads allowed)
			(copperpour not_allowed)
			(footprints allowed)
		)
		(placement
			(enabled no)
			(sheetname "")
		)
		(fill
			(thermal_gap 0.5)
			(thermal_bridge_width 0.5)
			(island_removal_mode 0)
		)
		(polygon
			(pts
				(xy 293.87038 -127.374142) (xy 294.42918 -127.374142) (xy 294.42918 -129.177542) (xy 293.87038 -129.177542)
			)
		)
	)
	(zone
		(layer "In12.Cu")
		(hatch none 0.5)
		(connect_pads
			(clearance 0)
		)
		(min_thickness 0.25)
		(keepout
			(tracks not_allowed)
			(vias allowed)
			(pads allowed)
			(copperpour not_allowed)
			(footprints allowed)
		)
		(placement
			(enabled no)
			(sheetname "")
		)
		(fill
			(thermal_gap 0.5)
			(thermal_bridge_width 0.5)
			(island_removal_mode 0)
		)
		(polygon
			(pts
				(xy 144.169892 -23.922482) (xy 144.728692 -23.922482) (xy 144.728692 -25.725882) (xy 144.169892 -25.725882)
			)
		)
	)
	(zone
		(layer "In12.Cu")
		(hatch none 0.5)
		(connect_pads
			(clearance 0)
		)
		(min_thickness 0.25)
		(keepout
			(tracks not_allowed)
			(vias allowed)
			(pads allowed)
			(copperpour not_allowed)
			(footprints allowed)
		)
		(placement
			(enabled no)
			(sheetname "")
		)
		(fill
			(thermal_gap 0.5)
			(thermal_bridge_width 0.5)
			(island_removal_mode 0)
		)
		(polygon
			(pts
				(xy 408.6606 -147.60448) (xy 408.6606 -148.36648) (xy 409.6512 -148.36648) (xy 409.6512 -147.60448)
			)
		)
	)
	(zone
		(layer "In12.Cu")
		(hatch none 0.5)
		(connect_pads
			(clearance 0)
		)
		(min_thickness 0.25)
		(keepout
			(tracks not_allowed)
			(vias allowed)
			(pads allowed)
			(copperpour not_allowed)
			(footprints allowed)
		)
		(placement
			(enabled no)
			(sheetname "")
		)
		(fill
			(thermal_gap 0.5)
			(thermal_bridge_width 0.5)
			(island_removal_mode 0)
		)
		(polygon
			(pts
				(xy 126.320042 -127.374142) (xy 126.878842 -127.374142) (xy 126.878842 -129.177542) (xy 126.320042 -129.177542)
			)
		)
	)
	(zone
		(layer "In12.Cu")
		(hatch none 0.5)
		(connect_pads
			(clearance 0)
		)
		(min_thickness 0.25)
		(keepout
			(tracks not_allowed)
			(vias allowed)
			(pads allowed)
			(copperpour not_allowed)
			(footprints allowed)
		)
		(placement
			(enabled no)
			(sheetname "")
		)
		(fill
			(thermal_gap 0.5)
			(thermal_bridge_width 0.5)
			(island_removal_mode 0)
		)
		(polygon
			(pts
				(xy 84.670138 -141.575282) (xy 85.228938 -141.575282) (xy 85.228938 -143.378682) (xy 84.670138 -143.378682)
			)
		)
	)
	(zone
		(layer "In12.Cu")
		(hatch none 0.5)
		(connect_pads
			(clearance 0)
		)
		(min_thickness 0.25)
		(keepout
			(tracks not_allowed)
			(vias allowed)
			(pads allowed)
			(copperpour not_allowed)
			(footprints allowed)
		)
		(placement
			(enabled no)
			(sheetname "")
		)
		(fill
			(thermal_gap 0.5)
			(thermal_bridge_width 0.5)
			(island_removal_mode 0)
		)
		(polygon
			(pts
				(xy 232.67035 -19.322542) (xy 233.22915 -19.322542) (xy 233.22915 -21.125942) (xy 232.67035 -21.125942)
			)
		)
	)
	(zone
		(layer "In12.Cu")
		(hatch none 0.5)
		(connect_pads
			(clearance 0)
		)
		(min_thickness 0.25)
		(keepout
			(tracks not_allowed)
			(vias allowed)
			(pads allowed)
			(copperpour not_allowed)
			(footprints allowed)
		)
		(placement
			(enabled no)
			(sheetname "")
		)
		(fill
			(thermal_gap 0.5)
			(thermal_bridge_width 0.5)
			(island_removal_mode 0)
		)
		(polygon
			(pts
				(xy 311.720484 -151.176482) (xy 312.279284 -151.176482) (xy 312.279284 -152.979882) (xy 311.720484 -152.979882)
			)
		)
	)
	(zone
		(layer "In12.Cu")
		(hatch none 0.5)
		(connect_pads
			(clearance 0)
		)
		(min_thickness 0.25)
		(keepout
			(tracks not_allowed)
			(vias allowed)
			(pads allowed)
			(copperpour not_allowed)
			(footprints allowed)
		)
		(placement
			(enabled no)
			(sheetname "")
		)
		(fill
			(thermal_gap 0.5)
			(thermal_bridge_width 0.5)
			(island_removal_mode 0)
		)
		(polygon
			(pts
				(xy 105.070148 -14.321282) (xy 105.628948 -14.321282) (xy 105.628948 -16.124682) (xy 105.070148 -16.124682)
			)
		)
	)
	(zone
		(layer "In12.Cu")
		(hatch none 0.5)
		(connect_pads
			(clearance 0)
		)
		(min_thickness 0.25)
		(keepout
			(tracks not_allowed)
			(vias allowed)
			(pads allowed)
			(copperpour not_allowed)
			(footprints allowed)
		)
		(placement
			(enabled no)
			(sheetname "")
		)
		(fill
			(thermal_gap 0.5)
			(thermal_bridge_width 0.5)
			(island_removal_mode 0)
		)
		(polygon
			(pts
				(xy 257.320542 -0.120142) (xy 257.879342 -0.120142) (xy 257.879342 -1.923542) (xy 257.320542 -1.923542)
			)
		)
	)
	(zone
		(layer "In12.Cu")
		(hatch none 0.5)
		(connect_pads
			(clearance 0)
		)
		(min_thickness 0.25)
		(keepout
			(tracks not_allowed)
			(vias allowed)
			(pads allowed)
			(copperpour not_allowed)
			(footprints allowed)
		)
		(placement
			(enabled no)
			(sheetname "")
		)
		(fill
			(thermal_gap 0.5)
			(thermal_bridge_width 0.5)
			(island_removal_mode 0)
		)
		(polygon
			(pts
				(xy 272.620486 -141.575282) (xy 273.179286 -141.575282) (xy 273.179286 -143.378682) (xy 272.620486 -143.378682)
			)
		)
	)
	(zone
		(layer "In12.Cu")
		(hatch none 0.5)
		(connect_pads
			(clearance 0)
		)
		(min_thickness 0.25)
		(keepout
			(tracks not_allowed)
			(vias allowed)
			(pads allowed)
			(copperpour not_allowed)
			(footprints allowed)
		)
		(placement
			(enabled no)
			(sheetname "")
		)
		(fill
			(thermal_gap 0.5)
			(thermal_bridge_width 0.5)
			(island_removal_mode 0)
		)
		(polygon
			(pts
				(xy 36.220146 -0.120142) (xy 36.778946 -0.120142) (xy 36.778946 -1.923542) (xy 36.220146 -1.923542)
			)
		)
	)
	(zone
		(layer "In12.Cu")
		(hatch none 0.5)
		(connect_pads
			(clearance 0)
		)
		(min_thickness 0.25)
		(keepout
			(tracks not_allowed)
			(vias allowed)
			(pads allowed)
			(copperpour not_allowed)
			(footprints allowed)
		)
		(placement
			(enabled no)
			(sheetname "")
		)
		(fill
			(thermal_gap 0.5)
			(thermal_bridge_width 0.5)
			(island_removal_mode 0)
		)
		(polygon
			(pts
				(xy 91.469972 -136.975342) (xy 92.028772 -136.975342) (xy 92.028772 -138.778742) (xy 91.469972 -138.778742)
			)
		)
	)
	(zone
		(layer "In12.Cu")
		(hatch none 0.5)
		(connect_pads
			(clearance 0)
		)
		(min_thickness 0.25)
		(keepout
			(tracks not_allowed)
			(vias allowed)
			(pads allowed)
			(copperpour not_allowed)
			(footprints allowed)
		)
		(placement
			(enabled no)
			(sheetname "")
		)
		(fill
			(thermal_gap 0.5)
			(thermal_bridge_width 0.5)
			(island_removal_mode 0)
		)
		(polygon
			(pts
				(xy 196.120512 -14.321282) (xy 196.679312 -14.321282) (xy 196.679312 -16.124682) (xy 196.120512 -16.124682)
			)
		)
	)
	(zone
		(layer "In12.Cu")
		(hatch none 0.5)
		(connect_pads
			(clearance 0)
		)
		(min_thickness 0.25)
		(keepout
			(tracks not_allowed)
			(vias allowed)
			(pads allowed)
			(copperpour not_allowed)
			(footprints allowed)
		)
		(placement
			(enabled no)
			(sheetname "")
		)
		(fill
			(thermal_gap 0.5)
			(thermal_bridge_width 0.5)
			(island_removal_mode 0)
		)
		(polygon
			(pts
				(xy 111.020098 -146.576542) (xy 111.578898 -146.576542) (xy 111.578898 -148.379942) (xy 111.020098 -148.379942)
			)
		)
	)
	(zone
		(layer "In12.Cu")
		(hatch none 0.5)
		(connect_pads
			(clearance 0)
		)
		(min_thickness 0.25)
		(keepout
			(tracks not_allowed)
			(vias allowed)
			(pads allowed)
			(copperpour not_allowed)
			(footprints allowed)
		)
		(placement
			(enabled no)
			(sheetname "")
		)
		(fill
			(thermal_gap 0.5)
			(thermal_bridge_width 0.5)
			(island_removal_mode 0)
		)
		(polygon
			(pts
				(xy 100.819966 -14.321282) (xy 101.378766 -14.321282) (xy 101.378766 -16.124682) (xy 100.819966 -16.124682)
			)
		)
	)
	(zone
		(layer "In12.Cu")
		(hatch none 0.5)
		(connect_pads
			(clearance 0)
		)
		(min_thickness 0.25)
		(keepout
			(tracks not_allowed)
			(vias allowed)
			(pads allowed)
			(copperpour not_allowed)
			(footprints allowed)
		)
		(placement
			(enabled no)
			(sheetname "")
		)
		(fill
			(thermal_gap 0.5)
			(thermal_bridge_width 0.5)
			(island_removal_mode 0)
		)
		(polygon
			(pts
				(xy 253.920498 -131.974082) (xy 254.479298 -131.974082) (xy 254.479298 -133.777482) (xy 253.920498 -133.777482)
			)
		)
	)
	(zone
		(layer "In12.Cu")
		(hatch none 0.5)
		(connect_pads
			(clearance 0)
		)
		(min_thickness 0.25)
		(keepout
			(tracks not_allowed)
			(vias allowed)
			(pads allowed)
			(copperpour not_allowed)
			(footprints allowed)
		)
		(placement
			(enabled no)
			(sheetname "")
		)
		(fill
			(thermal_gap 0.5)
			(thermal_bridge_width 0.5)
			(island_removal_mode 0)
		)
		(polygon
			(pts
				(xy 62.570106 -151.176482) (xy 63.128906 -151.176482) (xy 63.128906 -152.979882) (xy 62.570106 -152.979882)
			)
		)
	)
	(zone
		(layer "In12.Cu")
		(hatch none 0.5)
		(connect_pads
			(clearance 0)
		)
		(min_thickness 0.25)
		(keepout
			(tracks not_allowed)
			(vias allowed)
			(pads allowed)
			(copperpour not_allowed)
			(footprints allowed)
		)
		(placement
			(enabled no)
			(sheetname "")
		)
		(fill
			(thermal_gap 0.5)
			(thermal_bridge_width 0.5)
			(island_removal_mode 0)
		)
		(polygon
			(pts
				(xy 36.220146 -146.576542) (xy 36.778946 -146.576542) (xy 36.778946 -148.379942) (xy 36.220146 -148.379942)
			)
		)
	)
	(zone
		(layer "In12.Cu")
		(hatch none 0.5)
		(connect_pads
			(clearance 0)
		)
		(min_thickness 0.25)
		(keepout
			(tracks not_allowed)
			(vias allowed)
			(pads allowed)
			(copperpour not_allowed)
			(footprints allowed)
		)
		(placement
			(enabled no)
			(sheetname "")
		)
		(fill
			(thermal_gap 0.5)
			(thermal_bridge_width 0.5)
			(island_removal_mode 0)
		)
		(polygon
			(pts
				(xy 270.07058 -151.176482) (xy 270.62938 -151.176482) (xy 270.62938 -152.979882) (xy 270.07058 -152.979882)
			)
		)
	)
	(zone
		(layer "In12.Cu")
		(hatch none 0.5)
		(connect_pads
			(clearance 0)
		)
		(min_thickness 0.25)
		(keepout
			(tracks not_allowed)
			(vias allowed)
			(pads allowed)
			(copperpour not_allowed)
			(footprints allowed)
		)
		(placement
			(enabled no)
			(sheetname "")
		)
		(fill
			(thermal_gap 0.5)
			(thermal_bridge_width 0.5)
			(island_removal_mode 0)
		)
		(polygon
			(pts
				(xy 267.52042 -14.321282) (xy 268.07922 -14.321282) (xy 268.07922 -16.124682) (xy 267.52042 -16.124682)
			)
		)
	)
	(zone
		(layer "In12.Cu")
		(hatch none 0.5)
		(connect_pads
			(clearance 0)
		)
		(min_thickness 0.25)
		(keepout
			(tracks not_allowed)
			(vias allowed)
			(pads allowed)
			(copperpour not_allowed)
			(footprints allowed)
		)
		(placement
			(enabled no)
			(sheetname "")
		)
		(fill
			(thermal_gap 0.5)
			(thermal_bridge_width 0.5)
			(island_removal_mode 0)
		)
		(polygon
			(pts
				(xy 199.520556 -14.321282) (xy 200.079356 -14.321282) (xy 200.079356 -16.124682) (xy 199.520556 -16.124682)
			)
		)
	)
	(zone
		(layer "In12.Cu")
		(hatch none 0.5)
		(connect_pads
			(clearance 0)
		)
		(min_thickness 0.25)
		(keepout
			(tracks not_allowed)
			(vias allowed)
			(pads allowed)
			(copperpour not_allowed)
			(footprints allowed)
		)
		(placement
			(enabled no)
			(sheetname "")
		)
		(fill
			(thermal_gap 0.5)
			(thermal_bridge_width 0.5)
			(island_removal_mode 0)
		)
		(polygon
			(pts
				(xy 199.520556 -141.575282) (xy 200.079356 -141.575282) (xy 200.079356 -143.378682) (xy 199.520556 -143.378682)
			)
		)
	)
	(zone
		(layer "In12.Cu")
		(hatch none 0.5)
		(connect_pads
			(clearance 0)
		)
		(min_thickness 0.25)
		(keepout
			(tracks not_allowed)
			(vias allowed)
			(pads allowed)
			(copperpour not_allowed)
			(footprints allowed)
		)
		(placement
			(enabled no)
			(sheetname "")
		)
		(fill
			(thermal_gap 0.5)
			(thermal_bridge_width 0.5)
			(island_removal_mode 0)
		)
		(polygon
			(pts
				(xy 284.520386 -146.576542) (xy 285.079186 -146.576542) (xy 285.079186 -148.379942) (xy 284.520386 -148.379942)
			)
		)
	)
	(zone
		(layer "In12.Cu")
		(hatch none 0.5)
		(connect_pads
			(clearance 0)
		)
		(min_thickness 0.25)
		(keepout
			(tracks not_allowed)
			(vias allowed)
			(pads allowed)
			(copperpour not_allowed)
			(footprints allowed)
		)
		(placement
			(enabled no)
			(sheetname "")
		)
		(fill
			(thermal_gap 0.5)
			(thermal_bridge_width 0.5)
			(island_removal_mode 0)
		)
		(polygon
			(pts
				(xy 44.720002 -131.974082) (xy 45.278802 -131.974082) (xy 45.278802 -133.777482) (xy 44.720002 -133.777482)
			)
		)
	)
	(zone
		(layer "In12.Cu")
		(hatch none 0.5)
		(connect_pads
			(clearance 0)
		)
		(min_thickness 0.25)
		(keepout
			(tracks not_allowed)
			(vias allowed)
			(pads allowed)
			(copperpour not_allowed)
			(footprints allowed)
		)
		(placement
			(enabled no)
			(sheetname "")
		)
		(fill
			(thermal_gap 0.5)
			(thermal_bridge_width 0.5)
			(island_removal_mode 0)
		)
		(polygon
			(pts
				(xy 65.120012 -14.321282) (xy 65.678812 -14.321282) (xy 65.678812 -16.124682) (xy 65.120012 -16.124682)
			)
		)
	)
	(zone
		(layer "In12.Cu")
		(hatch none 0.5)
		(connect_pads
			(clearance 0)
		)
		(min_thickness 0.25)
		(keepout
			(tracks not_allowed)
			(vias allowed)
			(pads allowed)
			(copperpour not_allowed)
			(footprints allowed)
		)
		(placement
			(enabled no)
			(sheetname "")
		)
		(fill
			(thermal_gap 0.5)
			(thermal_bridge_width 0.5)
			(island_removal_mode 0)
		)
		(polygon
			(pts
				(xy 228.420422 -9.721342) (xy 228.979222 -9.721342) (xy 228.979222 -11.524742) (xy 228.420422 -11.524742)
			)
		)
	)
	(zone
		(layer "In12.Cu")
		(hatch none 0.5)
		(connect_pads
			(clearance 0)
		)
		(min_thickness 0.25)
		(keepout
			(tracks not_allowed)
			(vias allowed)
			(pads allowed)
			(copperpour not_allowed)
			(footprints allowed)
		)
		(placement
			(enabled no)
			(sheetname "")
		)
		(fill
			(thermal_gap 0.5)
			(thermal_bridge_width 0.5)
			(island_removal_mode 0)
		)
		(polygon
			(pts
				(xy 211.420456 -4.720082) (xy 211.979256 -4.720082) (xy 211.979256 -6.523482) (xy 211.420456 -6.523482)
			)
		)
	)
	(zone
		(layer "In12.Cu")
		(hatch none 0.5)
		(connect_pads
			(clearance 0)
		)
		(min_thickness 0.25)
		(keepout
			(tracks not_allowed)
			(vias allowed)
			(pads allowed)
			(copperpour not_allowed)
			(footprints allowed)
		)
		(placement
			(enabled no)
			(sheetname "")
		)
		(fill
			(thermal_gap 0.5)
			(thermal_bridge_width 0.5)
			(island_removal_mode 0)
		)
		(polygon
			(pts
				(xy 42.170096 -151.176482) (xy 42.728896 -151.176482) (xy 42.728896 -152.979882) (xy 42.170096 -152.979882)
			)
		)
	)
	(zone
		(layer "In12.Cu")
		(hatch none 0.5)
		(connect_pads
			(clearance 0)
		)
		(min_thickness 0.25)
		(keepout
			(tracks not_allowed)
			(vias allowed)
			(pads allowed)
			(copperpour not_allowed)
			(footprints allowed)
		)
		(placement
			(enabled no)
			(sheetname "")
		)
		(fill
			(thermal_gap 0.5)
			(thermal_bridge_width 0.5)
			(island_removal_mode 0)
		)
		(polygon
			(pts
				(xy 48.96993 -136.975342) (xy 49.52873 -136.975342) (xy 49.52873 -138.778742) (xy 48.96993 -138.778742)
			)
		)
	)
	(zone
		(layer "In12.Cu")
		(hatch none 0.5)
		(connect_pads
			(clearance 0)
		)
		(min_thickness 0.25)
		(keepout
			(tracks not_allowed)
			(vias allowed)
			(pads allowed)
			(copperpour not_allowed)
			(footprints allowed)
		)
		(placement
			(enabled no)
			(sheetname "")
		)
		(fill
			(thermal_gap 0.5)
			(thermal_bridge_width 0.5)
			(island_removal_mode 0)
		)
		(polygon
			(pts
				(xy 132.269992 -0.120142) (xy 132.828792 -0.120142) (xy 132.828792 -1.923542) (xy 132.269992 -1.923542)
			)
		)
	)
	(zone
		(layer "In12.Cu")
		(hatch none 0.5)
		(connect_pads
			(clearance 0)
		)
		(min_thickness 0.25)
		(keepout
			(tracks not_allowed)
			(vias allowed)
			(pads allowed)
			(copperpour not_allowed)
			(footprints allowed)
		)
		(placement
			(enabled no)
			(sheetname "")
		)
		(fill
			(thermal_gap 0.5)
			(thermal_bridge_width 0.5)
			(island_removal_mode 0)
		)
		(polygon
			(pts
				(xy 256.470404 -136.975342) (xy 257.029204 -136.975342) (xy 257.029204 -138.778742) (xy 256.470404 -138.778742)
			)
		)
	)
	(zone
		(layer "In12.Cu")
		(hatch none 0.5)
		(connect_pads
			(clearance 0)
		)
		(min_thickness 0.25)
		(keepout
			(tracks not_allowed)
			(vias allowed)
			(pads allowed)
			(copperpour not_allowed)
			(footprints allowed)
		)
		(placement
			(enabled no)
			(sheetname "")
		)
		(fill
			(thermal_gap 0.5)
			(thermal_bridge_width 0.5)
			(island_removal_mode 0)
		)
		(polygon
			(pts
				(xy 212.270594 -0.120142) (xy 212.829394 -0.120142) (xy 212.829394 -1.923542) (xy 212.270594 -1.923542)
			)
		)
	)
	(zone
		(layer "In12.Cu")
		(hatch none 0.5)
		(connect_pads
			(clearance 0)
		)
		(min_thickness 0.25)
		(keepout
			(tracks not_allowed)
			(vias allowed)
			(pads allowed)
			(copperpour not_allowed)
			(footprints allowed)
		)
		(placement
			(enabled no)
			(sheetname "")
		)
		(fill
			(thermal_gap 0.5)
			(thermal_bridge_width 0.5)
			(island_removal_mode 0)
		)
		(polygon
			(pts
				(xy 88.070182 -9.721342) (xy 88.628982 -9.721342) (xy 88.628982 -11.524742) (xy 88.070182 -11.524742)
			)
		)
	)
	(zone
		(layer "In12.Cu")
		(hatch none 0.5)
		(connect_pads
			(clearance 0)
		)
		(min_thickness 0.25)
		(keepout
			(tracks not_allowed)
			(vias allowed)
			(pads allowed)
			(copperpour not_allowed)
			(footprints allowed)
		)
		(placement
			(enabled no)
			(sheetname "")
		)
		(fill
			(thermal_gap 0.5)
			(thermal_bridge_width 0.5)
			(island_removal_mode 0)
		)
		(polygon
			(pts
				(xy 110.16996 -136.975342) (xy 110.72876 -136.975342) (xy 110.72876 -138.778742) (xy 110.16996 -138.778742)
			)
		)
	)
	(zone
		(layer "In12.Cu")
		(hatch none 0.5)
		(connect_pads
			(clearance 0)
		)
		(min_thickness 0.25)
		(keepout
			(tracks not_allowed)
			(vias allowed)
			(pads allowed)
			(copperpour not_allowed)
			(footprints allowed)
		)
		(placement
			(enabled no)
			(sheetname "")
		)
		(fill
			(thermal_gap 0.5)
			(thermal_bridge_width 0.5)
			(island_removal_mode 0)
		)
		(polygon
			(pts
				(xy 99.970082 -127.374142) (xy 100.528882 -127.374142) (xy 100.528882 -129.177542) (xy 99.970082 -129.177542)
			)
		)
	)
	(zone
		(layer "In12.Cu")
		(hatch none 0.5)
		(connect_pads
			(clearance 0)
		)
		(min_thickness 0.25)
		(keepout
			(tracks not_allowed)
			(vias allowed)
			(pads allowed)
			(copperpour not_allowed)
			(footprints allowed)
		)
		(placement
			(enabled no)
			(sheetname "")
		)
		(fill
			(thermal_gap 0.5)
			(thermal_bridge_width 0.5)
			(island_removal_mode 0)
		)
		(polygon
			(pts
				(xy 71.9201 -131.974082) (xy 72.4789 -131.974082) (xy 72.4789 -133.777482) (xy 71.9201 -133.777482)
			)
		)
	)
	(zone
		(layer "In12.Cu")
		(hatch none 0.5)
		(connect_pads
			(clearance 0)
		)
		(min_thickness 0.25)
		(keepout
			(tracks not_allowed)
			(vias allowed)
			(pads allowed)
			(copperpour not_allowed)
			(footprints allowed)
		)
		(placement
			(enabled no)
			(sheetname "")
		)
		(fill
			(thermal_gap 0.5)
			(thermal_bridge_width 0.5)
			(island_removal_mode 0)
		)
		(polygon
			(pts
				(xy 68.520056 -151.176482) (xy 69.078856 -151.176482) (xy 69.078856 -152.979882) (xy 68.520056 -152.979882)
			)
		)
	)
	(zone
		(layer "In12.Cu")
		(hatch none 0.5)
		(connect_pads
			(clearance 0)
		)
		(min_thickness 0.25)
		(keepout
			(tracks not_allowed)
			(vias allowed)
			(pads allowed)
			(copperpour not_allowed)
			(footprints allowed)
		)
		(placement
			(enabled no)
			(sheetname "")
		)
		(fill
			(thermal_gap 0.5)
			(thermal_bridge_width 0.5)
			(island_removal_mode 0)
		)
		(polygon
			(pts
				(xy 65.120012 -131.974082) (xy 65.678812 -131.974082) (xy 65.678812 -133.777482) (xy 65.120012 -133.777482)
			)
		)
	)
	(zone
		(layer "In12.Cu")
		(hatch none 0.5)
		(connect_pads
			(clearance 0)
		)
		(min_thickness 0.25)
		(keepout
			(tracks not_allowed)
			(vias allowed)
			(pads allowed)
			(copperpour not_allowed)
			(footprints allowed)
		)
		(placement
			(enabled no)
			(sheetname "")
		)
		(fill
			(thermal_gap 0.5)
			(thermal_bridge_width 0.5)
			(island_removal_mode 0)
		)
		(polygon
			(pts
				(xy 102.519988 -136.975342) (xy 103.078788 -136.975342) (xy 103.078788 -138.778742) (xy 102.519988 -138.778742)
			)
		)
	)
	(zone
		(layer "In12.Cu")
		(hatch none 0.5)
		(connect_pads
			(clearance 0)
		)
		(min_thickness 0.25)
		(keepout
			(tracks not_allowed)
			(vias allowed)
			(pads allowed)
			(copperpour not_allowed)
			(footprints allowed)
		)
		(placement
			(enabled no)
			(sheetname "")
		)
		(fill
			(thermal_gap 0.5)
			(thermal_bridge_width 0.5)
			(island_removal_mode 0)
		)
		(polygon
			(pts
				(xy 298.120308 -23.922482) (xy 298.679108 -23.922482) (xy 298.679108 -25.725882) (xy 298.120308 -25.725882)
			)
		)
	)
	(zone
		(layer "In12.Cu")
		(hatch none 0.5)
		(connect_pads
			(clearance 0)
		)
		(min_thickness 0.25)
		(keepout
			(tracks not_allowed)
			(vias allowed)
			(pads allowed)
			(copperpour not_allowed)
			(footprints allowed)
		)
		(placement
			(enabled no)
			(sheetname "")
		)
		(fill
			(thermal_gap 0.5)
			(thermal_bridge_width 0.5)
			(island_removal_mode 0)
		)
		(polygon
			(pts
				(xy 54.069996 -14.321282) (xy 54.628796 -14.321282) (xy 54.628796 -16.124682) (xy 54.069996 -16.124682)
			)
		)
	)
	(zone
		(layer "In12.Cu")
		(hatch none 0.5)
		(connect_pads
			(clearance 0)
		)
		(min_thickness 0.25)
		(keepout
			(tracks not_allowed)
			(vias allowed)
			(pads allowed)
			(copperpour not_allowed)
			(footprints allowed)
		)
		(placement
			(enabled no)
			(sheetname "")
		)
		(fill
			(thermal_gap 0.5)
			(thermal_bridge_width 0.5)
			(island_removal_mode 0)
		)
		(polygon
			(pts
				(xy 246.270526 -14.321282) (xy 246.829326 -14.321282) (xy 246.829326 -16.124682) (xy 246.270526 -16.124682)
			)
		)
	)
	(zone
		(layer "In12.Cu")
		(hatch none 0.5)
		(connect_pads
			(clearance 0)
		)
		(min_thickness 0.25)
		(keepout
			(tracks not_allowed)
			(vias allowed)
			(pads allowed)
			(copperpour not_allowed)
			(footprints allowed)
		)
		(placement
			(enabled no)
			(sheetname "")
		)
		(fill
			(thermal_gap 0.5)
			(thermal_bridge_width 0.5)
			(island_removal_mode 0)
		)
		(polygon
			(pts
				(xy 456.2348 -51.340258) (xy 456.7428 -51.340258) (xy 456.7428 -52.737258) (xy 456.2348 -52.737258)
			)
		)
	)
	(zone
		(layer "In12.Cu")
		(hatch none 0.5)
		(connect_pads
			(clearance 0)
		)
		(min_thickness 0.25)
		(keepout
			(tracks not_allowed)
			(vias allowed)
			(pads allowed)
			(copperpour not_allowed)
			(footprints allowed)
		)
		(placement
			(enabled no)
			(sheetname "")
		)
		(fill
			(thermal_gap 0.5)
			(thermal_bridge_width 0.5)
			(island_removal_mode 0)
		)
		(polygon
			(pts
				(xy 277.720552 -151.176482) (xy 278.279352 -151.176482) (xy 278.279352 -152.979882) (xy 277.720552 -152.979882)
			)
		)
	)
	(zone
		(layer "In12.Cu")
		(hatch none 0.5)
		(connect_pads
			(clearance 0)
		)
		(min_thickness 0.25)
		(keepout
			(tracks not_allowed)
			(vias allowed)
			(pads allowed)
			(copperpour not_allowed)
			(footprints allowed)
		)
		(placement
			(enabled no)
			(sheetname "")
		)
		(fill
			(thermal_gap 0.5)
			(thermal_bridge_width 0.5)
			(island_removal_mode 0)
		)
		(polygon
			(pts
				(xy 63.41999 -0.120142) (xy 63.97879 -0.120142) (xy 63.97879 -1.923542) (xy 63.41999 -1.923542)
			)
		)
	)
	(zone
		(layer "In12.Cu")
		(hatch none 0.5)
		(connect_pads
			(clearance 0)
		)
		(min_thickness 0.25)
		(keepout
			(tracks not_allowed)
			(vias allowed)
			(pads allowed)
			(copperpour not_allowed)
			(footprints allowed)
		)
		(placement
			(enabled no)
			(sheetname "")
		)
		(fill
			(thermal_gap 0.5)
			(thermal_bridge_width 0.5)
			(island_removal_mode 0)
		)
		(polygon
			(pts
				(xy 127.169926 -23.922482) (xy 127.728726 -23.922482) (xy 127.728726 -25.725882) (xy 127.169926 -25.725882)
			)
		)
	)
	(zone
		(layer "In12.Cu")
		(hatch none 0.5)
		(connect_pads
			(clearance 0)
		)
		(min_thickness 0.25)
		(keepout
			(tracks not_allowed)
			(vias allowed)
			(pads allowed)
			(copperpour not_allowed)
			(footprints allowed)
		)
		(placement
			(enabled no)
			(sheetname "")
		)
		(fill
			(thermal_gap 0.5)
			(thermal_bridge_width 0.5)
			(island_removal_mode 0)
		)
		(polygon
			(pts
				(xy 219.070428 -0.120142) (xy 219.629228 -0.120142) (xy 219.629228 -1.923542) (xy 219.070428 -1.923542)
			)
		)
	)
	(zone
		(layer "In12.Cu")
		(hatch none 0.5)
		(connect_pads
			(clearance 0)
		)
		(min_thickness 0.25)
		(keepout
			(tracks not_allowed)
			(vias allowed)
			(pads allowed)
			(copperpour not_allowed)
			(footprints allowed)
		)
		(placement
			(enabled no)
			(sheetname "")
		)
		(fill
			(thermal_gap 0.5)
			(thermal_bridge_width 0.5)
			(island_removal_mode 0)
		)
		(polygon
			(pts
				(xy 213.970362 -0.120142) (xy 214.529162 -0.120142) (xy 214.529162 -1.923542) (xy 213.970362 -1.923542)
			)
		)
	)
	(zone
		(layer "In12.Cu")
		(hatch none 0.5)
		(connect_pads
			(clearance 0)
		)
		(min_thickness 0.25)
		(keepout
			(tracks not_allowed)
			(vias allowed)
			(pads allowed)
			(copperpour not_allowed)
			(footprints allowed)
		)
		(placement
			(enabled no)
			(sheetname "")
		)
		(fill
			(thermal_gap 0.5)
			(thermal_bridge_width 0.5)
			(island_removal_mode 0)
		)
		(polygon
			(pts
				(xy 51.52009 -131.974082) (xy 52.07889 -131.974082) (xy 52.07889 -133.777482) (xy 51.52009 -133.777482)
			)
		)
	)
	(zone
		(layer "In12.Cu")
		(hatch none 0.5)
		(connect_pads
			(clearance 0)
		)
		(min_thickness 0.25)
		(keepout
			(tracks not_allowed)
			(vias allowed)
			(pads allowed)
			(copperpour not_allowed)
			(footprints allowed)
		)
		(placement
			(enabled no)
			(sheetname "")
		)
		(fill
			(thermal_gap 0.5)
			(thermal_bridge_width 0.5)
			(island_removal_mode 0)
		)
		(polygon
			(pts
				(xy 150.120096 -151.176482) (xy 150.678896 -151.176482) (xy 150.678896 -152.979882) (xy 150.120096 -152.979882)
			)
		)
	)
	(zone
		(layer "In12.Cu")
		(hatch none 0.5)
		(connect_pads
			(clearance 0)
		)
		(min_thickness 0.25)
		(keepout
			(tracks not_allowed)
			(vias allowed)
			(pads allowed)
			(copperpour not_allowed)
			(footprints allowed)
		)
		(placement
			(enabled no)
			(sheetname "")
		)
		(fill
			(thermal_gap 0.5)
			(thermal_bridge_width 0.5)
			(island_removal_mode 0)
		)
		(polygon
			(pts
				(xy 282.820364 -23.922482) (xy 283.379164 -23.922482) (xy 283.379164 -25.725882) (xy 282.820364 -25.725882)
			)
		)
	)
	(zone
		(layer "In12.Cu")
		(hatch none 0.5)
		(connect_pads
			(clearance 0)
		)
		(min_thickness 0.25)
		(keepout
			(tracks not_allowed)
			(vias allowed)
			(pads allowed)
			(copperpour not_allowed)
			(footprints allowed)
		)
		(placement
			(enabled no)
			(sheetname "")
		)
		(fill
			(thermal_gap 0.5)
			(thermal_bridge_width 0.5)
			(island_removal_mode 0)
		)
		(polygon
			(pts
				(xy 141.619986 -0.120142) (xy 142.178786 -0.120142) (xy 142.178786 -1.923542) (xy 141.619986 -1.923542)
			)
		)
	)
	(zone
		(layer "In12.Cu")
		(hatch none 0.5)
		(connect_pads
			(clearance 0)
		)
		(min_thickness 0.25)
		(keepout
			(tracks not_allowed)
			(vias allowed)
			(pads allowed)
			(copperpour not_allowed)
			(footprints allowed)
		)
		(placement
			(enabled no)
			(sheetname "")
		)
		(fill
			(thermal_gap 0.5)
			(thermal_bridge_width 0.5)
			(island_removal_mode 0)
		)
		(polygon
			(pts
				(xy 53.220112 -14.321282) (xy 53.778912 -14.321282) (xy 53.778912 -16.124682) (xy 53.220112 -16.124682)
			)
		)
	)
	(zone
		(layer "In12.Cu")
		(hatch none 0.5)
		(connect_pads
			(clearance 0)
		)
		(min_thickness 0.25)
		(keepout
			(tracks not_allowed)
			(vias allowed)
			(pads allowed)
			(copperpour not_allowed)
			(footprints allowed)
		)
		(placement
			(enabled no)
			(sheetname "")
		)
		(fill
			(thermal_gap 0.5)
			(thermal_bridge_width 0.5)
			(island_removal_mode 0)
		)
		(polygon
			(pts
				(xy 357.387398 -76.772516) (xy 357.387398 -79.058516) (xy 356.879398 -79.058516) (xy 356.879398 -76.772516)
			)
		)
	)
	(zone
		(layer "In12.Cu")
		(hatch none 0.5)
		(connect_pads
			(clearance 0)
		)
		(min_thickness 0.25)
		(keepout
			(tracks not_allowed)
			(vias allowed)
			(pads allowed)
			(copperpour not_allowed)
			(footprints allowed)
		)
		(placement
			(enabled no)
			(sheetname "")
		)
		(fill
			(thermal_gap 0.5)
			(thermal_bridge_width 0.5)
			(island_removal_mode 0)
		)
		(polygon
			(pts
				(xy 99.970082 -9.721342) (xy 100.528882 -9.721342) (xy 100.528882 -11.524742) (xy 99.970082 -11.524742)
			)
		)
	)
	(zone
		(layer "In12.Cu")
		(hatch none 0.5)
		(connect_pads
			(clearance 0)
		)
		(min_thickness 0.25)
		(keepout
			(tracks not_allowed)
			(vias allowed)
			(pads allowed)
			(copperpour not_allowed)
			(footprints allowed)
		)
		(placement
			(enabled no)
			(sheetname "")
		)
		(fill
			(thermal_gap 0.5)
			(thermal_bridge_width 0.5)
			(island_removal_mode 0)
		)
		(polygon
			(pts
				(xy 302.37049 -0.120142) (xy 302.92929 -0.120142) (xy 302.92929 -1.923542) (xy 302.37049 -1.923542)
			)
		)
	)
	(zone
		(layer "In12.Cu")
		(hatch none 0.5)
		(connect_pads
			(clearance 0)
		)
		(min_thickness 0.25)
		(keepout
			(tracks not_allowed)
			(vias allowed)
			(pads allowed)
			(copperpour not_allowed)
			(footprints allowed)
		)
		(placement
			(enabled no)
			(sheetname "")
		)
		(fill
			(thermal_gap 0.5)
			(thermal_bridge_width 0.5)
			(island_removal_mode 0)
		)
		(polygon
			(pts
				(xy 74.470006 -4.720082) (xy 75.028806 -4.720082) (xy 75.028806 -6.523482) (xy 74.470006 -6.523482)
			)
		)
	)
	(zone
		(layer "In12.Cu")
		(hatch none 0.5)
		(connect_pads
			(clearance 0)
		)
		(min_thickness 0.25)
		(keepout
			(tracks not_allowed)
			(vias allowed)
			(pads allowed)
			(copperpour not_allowed)
			(footprints allowed)
		)
		(placement
			(enabled no)
			(sheetname "")
		)
		(fill
			(thermal_gap 0.5)
			(thermal_bridge_width 0.5)
			(island_removal_mode 0)
		)
		(polygon
			(pts
				(xy 220.77045 -131.974082) (xy 221.32925 -131.974082) (xy 221.32925 -133.777482) (xy 220.77045 -133.777482)
			)
		)
	)
	(zone
		(layer "In12.Cu")
		(hatch none 0.5)
		(connect_pads
			(clearance 0)
		)
		(min_thickness 0.25)
		(keepout
			(tracks not_allowed)
			(vias allowed)
			(pads allowed)
			(copperpour not_allowed)
			(footprints allowed)
		)
		(placement
			(enabled no)
			(sheetname "")
		)
		(fill
			(thermal_gap 0.5)
			(thermal_bridge_width 0.5)
			(island_removal_mode 0)
		)
		(polygon
			(pts
				(xy 237.770416 -4.720082) (xy 238.329216 -4.720082) (xy 238.329216 -6.523482) (xy 237.770416 -6.523482)
			)
		)
	)
	(zone
		(layer "In12.Cu")
		(hatch none 0.5)
		(connect_pads
			(clearance 0)
		)
		(min_thickness 0.25)
		(keepout
			(tracks not_allowed)
			(vias allowed)
			(pads allowed)
			(copperpour not_allowed)
			(footprints allowed)
		)
		(placement
			(enabled no)
			(sheetname "")
		)
		(fill
			(thermal_gap 0.5)
			(thermal_bridge_width 0.5)
			(island_removal_mode 0)
		)
		(polygon
			(pts
				(xy 42.170096 -4.720082) (xy 42.728896 -4.720082) (xy 42.728896 -6.523482) (xy 42.170096 -6.523482)
			)
		)
	)
	(zone
		(layer "In12.Cu")
		(hatch none 0.5)
		(connect_pads
			(clearance 0)
		)
		(min_thickness 0.25)
		(keepout
			(tracks not_allowed)
			(vias allowed)
			(pads allowed)
			(copperpour not_allowed)
			(footprints allowed)
		)
		(placement
			(enabled no)
			(sheetname "")
		)
		(fill
			(thermal_gap 0.5)
			(thermal_bridge_width 0.5)
			(island_removal_mode 0)
		)
		(polygon
			(pts
				(xy 459.3844 -51.314858) (xy 459.8924 -51.314858) (xy 459.8924 -52.711858) (xy 459.3844 -52.711858)
			)
		)
	)
	(zone
		(layer "In12.Cu")
		(hatch none 0.5)
		(connect_pads
			(clearance 0)
		)
		(min_thickness 0.25)
		(keepout
			(tracks not_allowed)
			(vias allowed)
			(pads allowed)
			(copperpour not_allowed)
			(footprints allowed)
		)
		(placement
			(enabled no)
			(sheetname "")
		)
		(fill
			(thermal_gap 0.5)
			(thermal_bridge_width 0.5)
			(island_removal_mode 0)
		)
		(polygon
			(pts
				(xy 57.47004 -4.720082) (xy 58.02884 -4.720082) (xy 58.02884 -6.523482) (xy 57.47004 -6.523482)
			)
		)
	)
	(zone
		(layer "In12.Cu")
		(hatch none 0.5)
		(connect_pads
			(clearance 0)
		)
		(min_thickness 0.25)
		(keepout
			(tracks not_allowed)
			(vias allowed)
			(pads allowed)
			(copperpour not_allowed)
			(footprints allowed)
		)
		(placement
			(enabled no)
			(sheetname "")
		)
		(fill
			(thermal_gap 0.5)
			(thermal_bridge_width 0.5)
			(island_removal_mode 0)
		)
		(polygon
			(pts
				(xy 195.270374 -127.374142) (xy 195.829174 -127.374142) (xy 195.829174 -129.177542) (xy 195.270374 -129.177542)
			)
		)
	)
	(zone
		(layer "In12.Cu")
		(hatch none 0.5)
		(connect_pads
			(clearance 0)
		)
		(min_thickness 0.25)
		(keepout
			(tracks not_allowed)
			(vias allowed)
			(pads allowed)
			(copperpour not_allowed)
			(footprints allowed)
		)
		(placement
			(enabled no)
			(sheetname "")
		)
		(fill
			(thermal_gap 0.5)
			(thermal_bridge_width 0.5)
			(island_removal_mode 0)
		)
		(polygon
			(pts
				(xy 202.9206 -127.374142) (xy 203.4794 -127.374142) (xy 203.4794 -129.177542) (xy 202.9206 -129.177542)
			)
		)
	)
	(zone
		(layer "In12.Cu")
		(hatch none 0.5)
		(connect_pads
			(clearance 0)
		)
		(min_thickness 0.25)
		(keepout
			(tracks not_allowed)
			(vias allowed)
			(pads allowed)
			(copperpour not_allowed)
			(footprints allowed)
		)
		(placement
			(enabled no)
			(sheetname "")
		)
		(fill
			(thermal_gap 0.5)
			(thermal_bridge_width 0.5)
			(island_removal_mode 0)
		)
		(polygon
			(pts
				(xy 433.99075 -141.939264) (xy 434.75275 -141.939264) (xy 434.75275 -140.948664) (xy 433.99075 -140.948664)
			)
		)
	)
	(zone
		(layer "In12.Cu")
		(hatch none 0.5)
		(connect_pads
			(clearance 0)
		)
		(min_thickness 0.25)
		(keepout
			(tracks not_allowed)
			(vias allowed)
			(pads allowed)
			(copperpour not_allowed)
			(footprints allowed)
		)
		(placement
			(enabled no)
			(sheetname "")
		)
		(fill
			(thermal_gap 0.5)
			(thermal_bridge_width 0.5)
			(island_removal_mode 0)
		)
		(polygon
			(pts
				(xy 257.320542 -4.720082) (xy 257.879342 -4.720082) (xy 257.879342 -6.523482) (xy 257.320542 -6.523482)
			)
		)
	)
	(zone
		(layer "In12.Cu")
		(hatch none 0.5)
		(connect_pads
			(clearance 0)
		)
		(min_thickness 0.25)
		(keepout
			(tracks not_allowed)
			(vias allowed)
			(pads allowed)
			(copperpour not_allowed)
			(footprints allowed)
		)
		(placement
			(enabled no)
			(sheetname "")
		)
		(fill
			(thermal_gap 0.5)
			(thermal_bridge_width 0.5)
			(island_removal_mode 0)
		)
		(polygon
			(pts
				(xy 117.819932 -131.974082) (xy 118.378732 -131.974082) (xy 118.378732 -133.777482) (xy 117.819932 -133.777482)
			)
		)
	)
	(zone
		(layer "In12.Cu")
		(hatch none 0.5)
		(connect_pads
			(clearance 0)
		)
		(min_thickness 0.25)
		(keepout
			(tracks not_allowed)
			(vias allowed)
			(pads allowed)
			(copperpour not_allowed)
			(footprints allowed)
		)
		(placement
			(enabled no)
			(sheetname "")
		)
		(fill
			(thermal_gap 0.5)
			(thermal_bridge_width 0.5)
			(island_removal_mode 0)
		)
		(polygon
			(pts
				(xy 37.07003 -151.176482) (xy 37.62883 -151.176482) (xy 37.62883 -152.979882) (xy 37.07003 -152.979882)
			)
		)
	)
	(zone
		(layer "In12.Cu")
		(hatch none 0.5)
		(connect_pads
			(clearance 0)
		)
		(min_thickness 0.25)
		(keepout
			(tracks not_allowed)
			(vias allowed)
			(pads allowed)
			(copperpour not_allowed)
			(footprints allowed)
		)
		(placement
			(enabled no)
			(sheetname "")
		)
		(fill
			(thermal_gap 0.5)
			(thermal_bridge_width 0.5)
			(island_removal_mode 0)
		)
		(polygon
			(pts
				(xy 131.420108 -141.575282) (xy 131.978908 -141.575282) (xy 131.978908 -143.378682) (xy 131.420108 -143.378682)
			)
		)
	)
	(zone
		(layer "In12.Cu")
		(hatch none 0.5)
		(connect_pads
			(clearance 0)
		)
		(min_thickness 0.25)
		(keepout
			(tracks not_allowed)
			(vias allowed)
			(pads allowed)
			(copperpour not_allowed)
			(footprints allowed)
		)
		(placement
			(enabled no)
			(sheetname "")
		)
		(fill
			(thermal_gap 0.5)
			(thermal_bridge_width 0.5)
			(island_removal_mode 0)
		)
		(polygon
			(pts
				(xy 368.970814 -125.761242) (xy 366.684814 -125.761242) (xy 366.684814 -125.253242) (xy 368.970814 -125.253242)
			)
		)
	)
	(zone
		(layer "In12.Cu")
		(hatch none 0.5)
		(connect_pads
			(clearance 0)
		)
		(min_thickness 0.25)
		(keepout
			(tracks not_allowed)
			(vias allowed)
			(pads allowed)
			(copperpour not_allowed)
			(footprints allowed)
		)
		(placement
			(enabled no)
			(sheetname "")
		)
		(fill
			(thermal_gap 0.5)
			(thermal_bridge_width 0.5)
			(island_removal_mode 0)
		)
		(polygon
			(pts
				(xy 228.420422 -151.176482) (xy 228.979222 -151.176482) (xy 228.979222 -152.979882) (xy 228.420422 -152.979882)
			)
		)
	)
	(zone
		(layer "In12.Cu")
		(hatch none 0.5)
		(connect_pads
			(clearance 0)
		)
		(min_thickness 0.25)
		(keepout
			(tracks not_allowed)
			(vias allowed)
			(pads allowed)
			(copperpour not_allowed)
			(footprints allowed)
		)
		(placement
			(enabled no)
			(sheetname "")
		)
		(fill
			(thermal_gap 0.5)
			(thermal_bridge_width 0.5)
			(island_removal_mode 0)
		)
		(polygon
			(pts
				(xy 65.120012 -4.720082) (xy 65.678812 -4.720082) (xy 65.678812 -6.523482) (xy 65.120012 -6.523482)
			)
		)
	)
	(zone
		(layer "In12.Cu")
		(hatch none 0.5)
		(connect_pads
			(clearance 0)
		)
		(min_thickness 0.25)
		(keepout
			(tracks not_allowed)
			(vias allowed)
			(pads allowed)
			(copperpour not_allowed)
			(footprints allowed)
		)
		(placement
			(enabled no)
			(sheetname "")
		)
		(fill
			(thermal_gap 0.5)
			(thermal_bridge_width 0.5)
			(island_removal_mode 0)
		)
		(polygon
			(pts
				(xy 236.920532 -23.922482) (xy 237.479332 -23.922482) (xy 237.479332 -25.725882) (xy 236.920532 -25.725882)
			)
		)
	)
	(zone
		(layer "In12.Cu")
		(hatch none 0.5)
		(connect_pads
			(clearance 0)
		)
		(min_thickness 0.25)
		(keepout
			(tracks not_allowed)
			(vias allowed)
			(pads allowed)
			(copperpour not_allowed)
			(footprints allowed)
		)
		(placement
			(enabled no)
			(sheetname "")
		)
		(fill
			(thermal_gap 0.5)
			(thermal_bridge_width 0.5)
			(island_removal_mode 0)
		)
		(polygon
			(pts
				(xy 31.12008 -14.321282) (xy 31.67888 -14.321282) (xy 31.67888 -16.124682) (xy 31.12008 -16.124682)
			)
		)
	)
	(zone
		(layer "In12.Cu")
		(hatch none 0.5)
		(connect_pads
			(clearance 0)
		)
		(min_thickness 0.25)
		(keepout
			(tracks not_allowed)
			(vias allowed)
			(pads allowed)
			(copperpour not_allowed)
			(footprints allowed)
		)
		(placement
			(enabled no)
			(sheetname "")
		)
		(fill
			(thermal_gap 0.5)
			(thermal_bridge_width 0.5)
			(island_removal_mode 0)
		)
		(polygon
			(pts
				(xy 41.319958 -9.721342) (xy 41.878758 -9.721342) (xy 41.878758 -11.524742) (xy 41.319958 -11.524742)
			)
		)
	)
	(zone
		(layer "In12.Cu")
		(hatch none 0.5)
		(connect_pads
			(clearance 0)
		)
		(min_thickness 0.25)
		(keepout
			(tracks not_allowed)
			(vias allowed)
			(pads allowed)
			(copperpour not_allowed)
			(footprints allowed)
		)
		(placement
			(enabled no)
			(sheetname "")
		)
		(fill
			(thermal_gap 0.5)
			(thermal_bridge_width 0.5)
			(island_removal_mode 0)
		)
		(polygon
			(pts
				(xy 283.670502 -23.922482) (xy 284.229302 -23.922482) (xy 284.229302 -25.725882) (xy 283.670502 -25.725882)
			)
		)
	)
	(zone
		(layer "In12.Cu")
		(hatch none 0.5)
		(connect_pads
			(clearance 0)
		)
		(min_thickness 0.25)
		(keepout
			(tracks not_allowed)
			(vias allowed)
			(pads allowed)
			(copperpour not_allowed)
			(footprints allowed)
		)
		(placement
			(enabled no)
			(sheetname "")
		)
		(fill
			(thermal_gap 0.5)
			(thermal_bridge_width 0.5)
			(island_removal_mode 0)
		)
		(polygon
			(pts
				(xy 31.12008 -131.974082) (xy 31.67888 -131.974082) (xy 31.67888 -133.777482) (xy 31.12008 -133.777482)
			)
		)
	)
	(zone
		(layer "In12.Cu")
		(hatch none 0.5)
		(connect_pads
			(clearance 0)
		)
		(min_thickness 0.25)
		(keepout
			(tracks not_allowed)
			(vias allowed)
			(pads allowed)
			(copperpour not_allowed)
			(footprints allowed)
		)
		(placement
			(enabled no)
			(sheetname "")
		)
		(fill
			(thermal_gap 0.5)
			(thermal_bridge_width 0.5)
			(island_removal_mode 0)
		)
		(polygon
			(pts
				(xy 288.770314 -141.575282) (xy 289.329114 -141.575282) (xy 289.329114 -143.378682) (xy 288.770314 -143.378682)
			)
		)
	)
	(zone
		(layer "In12.Cu")
		(hatch none 0.5)
		(connect_pads
			(clearance 0)
		)
		(min_thickness 0.25)
		(keepout
			(tracks not_allowed)
			(vias allowed)
			(pads allowed)
			(copperpour not_allowed)
			(footprints allowed)
		)
		(placement
			(enabled no)
			(sheetname "")
		)
		(fill
			(thermal_gap 0.5)
			(thermal_bridge_width 0.5)
			(island_removal_mode 0)
		)
		(polygon
			(pts
				(xy 77.87005 -131.974082) (xy 78.42885 -131.974082) (xy 78.42885 -133.777482) (xy 77.87005 -133.777482)
			)
		)
	)
	(zone
		(layer "In12.Cu")
		(hatch none 0.5)
		(connect_pads
			(clearance 0)
		)
		(min_thickness 0.25)
		(keepout
			(tracks not_allowed)
			(vias allowed)
			(pads allowed)
			(copperpour not_allowed)
			(footprints allowed)
		)
		(placement
			(enabled no)
			(sheetname "")
		)
		(fill
			(thermal_gap 0.5)
			(thermal_bridge_width 0.5)
			(island_removal_mode 0)
		)
		(polygon
			(pts
				(xy 81.270094 -151.176482) (xy 81.828894 -151.176482) (xy 81.828894 -152.979882) (xy 81.270094 -152.979882)
			)
		)
	)
	(zone
		(layer "In12.Cu")
		(hatch none 0.5)
		(connect_pads
			(clearance 0)
		)
		(min_thickness 0.25)
		(keepout
			(tracks not_allowed)
			(vias allowed)
			(pads allowed)
			(copperpour not_allowed)
			(footprints allowed)
		)
		(placement
			(enabled no)
			(sheetname "")
		)
		(fill
			(thermal_gap 0.5)
			(thermal_bridge_width 0.5)
			(island_removal_mode 0)
		)
		(polygon
			(pts
				(xy 215.670384 -9.721342) (xy 216.229184 -9.721342) (xy 216.229184 -11.524742) (xy 215.670384 -11.524742)
			)
		)
	)
	(zone
		(layer "In12.Cu")
		(hatch none 0.5)
		(connect_pads
			(clearance 0)
		)
		(min_thickness 0.25)
		(keepout
			(tracks not_allowed)
			(vias allowed)
			(pads allowed)
			(copperpour not_allowed)
			(footprints allowed)
		)
		(placement
			(enabled no)
			(sheetname "")
		)
		(fill
			(thermal_gap 0.5)
			(thermal_bridge_width 0.5)
			(island_removal_mode 0)
		)
		(polygon
			(pts
				(xy 241.170714 -4.720082) (xy 241.729514 -4.720082) (xy 241.729514 -6.523482) (xy 241.170714 -6.523482)
			)
		)
	)
	(zone
		(layer "In12.Cu")
		(hatch none 0.5)
		(connect_pads
			(clearance 0)
		)
		(min_thickness 0.25)
		(keepout
			(tracks not_allowed)
			(vias allowed)
			(pads allowed)
			(copperpour not_allowed)
			(footprints allowed)
		)
		(placement
			(enabled no)
			(sheetname "")
		)
		(fill
			(thermal_gap 0.5)
			(thermal_bridge_width 0.5)
			(island_removal_mode 0)
		)
		(polygon
			(pts
				(xy 92.32011 -14.321282) (xy 92.87891 -14.321282) (xy 92.87891 -16.124682) (xy 92.32011 -16.124682)
			)
		)
	)
	(zone
		(layer "In12.Cu")
		(hatch none 0.5)
		(connect_pads
			(clearance 0)
		)
		(min_thickness 0.25)
		(keepout
			(tracks not_allowed)
			(vias allowed)
			(pads allowed)
			(copperpour not_allowed)
			(footprints allowed)
		)
		(placement
			(enabled no)
			(sheetname "")
		)
		(fill
			(thermal_gap 0.5)
			(thermal_bridge_width 0.5)
			(island_removal_mode 0)
		)
		(polygon
			(pts
				(xy 106.77017 -151.176482) (xy 107.32897 -151.176482) (xy 107.32897 -152.979882) (xy 106.77017 -152.979882)
			)
		)
	)
	(zone
		(layer "In12.Cu")
		(hatch none 0.5)
		(connect_pads
			(clearance 0)
		)
		(min_thickness 0.25)
		(keepout
			(tracks not_allowed)
			(vias allowed)
			(pads allowed)
			(copperpour not_allowed)
			(footprints allowed)
		)
		(placement
			(enabled no)
			(sheetname "")
		)
		(fill
			(thermal_gap 0.5)
			(thermal_bridge_width 0.5)
			(island_removal_mode 0)
		)
		(polygon
			(pts
				(xy 54.069996 -141.575282) (xy 54.628796 -141.575282) (xy 54.628796 -143.378682) (xy 54.069996 -143.378682)
			)
		)
	)
	(zone
		(layer "In12.Cu")
		(hatch none 0.5)
		(connect_pads
			(clearance 0)
		)
		(min_thickness 0.25)
		(keepout
			(tracks not_allowed)
			(vias allowed)
			(pads allowed)
			(copperpour not_allowed)
			(footprints allowed)
		)
		(placement
			(enabled no)
			(sheetname "")
		)
		(fill
			(thermal_gap 0.5)
			(thermal_bridge_width 0.5)
			(island_removal_mode 0)
		)
		(polygon
			(pts
				(xy 78.719934 -146.576542) (xy 79.278734 -146.576542) (xy 79.278734 -148.379942) (xy 78.719934 -148.379942)
			)
		)
	)
	(zone
		(layer "In12.Cu")
		(hatch none 0.5)
		(connect_pads
			(clearance 0)
		)
		(min_thickness 0.25)
		(keepout
			(tracks not_allowed)
			(vias allowed)
			(pads allowed)
			(copperpour not_allowed)
			(footprints allowed)
		)
		(placement
			(enabled no)
			(sheetname "")
		)
		(fill
			(thermal_gap 0.5)
			(thermal_bridge_width 0.5)
			(island_removal_mode 0)
		)
		(polygon
			(pts
				(xy 43.01998 -127.374142) (xy 43.57878 -127.374142) (xy 43.57878 -129.177542) (xy 43.01998 -129.177542)
			)
		)
	)
	(zone
		(layer "In12.Cu")
		(hatch none 0.5)
		(connect_pads
			(clearance 0)
		)
		(min_thickness 0.25)
		(keepout
			(tracks not_allowed)
			(vias allowed)
			(pads allowed)
			(copperpour not_allowed)
			(footprints allowed)
		)
		(placement
			(enabled no)
			(sheetname "")
		)
		(fill
			(thermal_gap 0.5)
			(thermal_bridge_width 0.5)
			(island_removal_mode 0)
		)
		(polygon
			(pts
				(xy 455.422 -115.34902) (xy 455.93 -115.34902) (xy 455.93 -116.74602) (xy 455.422 -116.74602)
			)
		)
	)
	(zone
		(layer "In12.Cu")
		(hatch none 0.5)
		(connect_pads
			(clearance 0)
		)
		(min_thickness 0.25)
		(keepout
			(tracks not_allowed)
			(vias allowed)
			(pads allowed)
			(copperpour not_allowed)
			(footprints allowed)
		)
		(placement
			(enabled no)
			(sheetname "")
		)
		(fill
			(thermal_gap 0.5)
			(thermal_bridge_width 0.5)
			(island_removal_mode 0)
		)
		(polygon
			(pts
				(xy 31.12008 -151.176482) (xy 31.67888 -151.176482) (xy 31.67888 -152.979882) (xy 31.12008 -152.979882)
			)
		)
	)
	(zone
		(layer "In12.Cu")
		(hatch none 0.5)
		(connect_pads
			(clearance 0)
		)
		(min_thickness 0.25)
		(keepout
			(tracks not_allowed)
			(vias allowed)
			(pads allowed)
			(copperpour not_allowed)
			(footprints allowed)
		)
		(placement
			(enabled no)
			(sheetname "")
		)
		(fill
			(thermal_gap 0.5)
			(thermal_bridge_width 0.5)
			(island_removal_mode 0)
		)
		(polygon
			(pts
				(xy 85.520022 -146.576542) (xy 86.078822 -146.576542) (xy 86.078822 -148.379942) (xy 85.520022 -148.379942)
			)
		)
	)
	(zone
		(layer "In12.Cu")
		(hatch none 0.5)
		(connect_pads
			(clearance 0)
		)
		(min_thickness 0.25)
		(keepout
			(tracks not_allowed)
			(vias allowed)
			(pads allowed)
			(copperpour not_allowed)
			(footprints allowed)
		)
		(placement
			(enabled no)
			(sheetname "")
		)
		(fill
			(thermal_gap 0.5)
			(thermal_bridge_width 0.5)
			(island_removal_mode 0)
		)
		(polygon
			(pts
				(xy 84.670138 -127.374142) (xy 85.228938 -127.374142) (xy 85.228938 -129.177542) (xy 84.670138 -129.177542)
			)
		)
	)
	(zone
		(layer "In12.Cu")
		(hatch none 0.5)
		(connect_pads
			(clearance 0)
		)
		(min_thickness 0.25)
		(keepout
			(tracks not_allowed)
			(vias allowed)
			(pads allowed)
			(copperpour not_allowed)
			(footprints allowed)
		)
		(placement
			(enabled no)
			(sheetname "")
		)
		(fill
			(thermal_gap 0.5)
			(thermal_bridge_width 0.5)
			(island_removal_mode 0)
		)
		(polygon
			(pts
				(xy 132.269992 -146.576542) (xy 132.828792 -146.576542) (xy 132.828792 -148.379942) (xy 132.269992 -148.379942)
			)
		)
	)
	(zone
		(layer "In12.Cu")
		(hatch none 0.5)
		(connect_pads
			(clearance 0)
		)
		(min_thickness 0.25)
		(keepout
			(tracks not_allowed)
			(vias allowed)
			(pads allowed)
			(copperpour not_allowed)
			(footprints allowed)
		)
		(placement
			(enabled no)
			(sheetname "")
		)
		(fill
			(thermal_gap 0.5)
			(thermal_bridge_width 0.5)
			(island_removal_mode 0)
		)
		(polygon
			(pts
				(xy 287.92043 -127.374142) (xy 288.47923 -127.374142) (xy 288.47923 -129.177542) (xy 287.92043 -129.177542)
			)
		)
	)
	(zone
		(layer "In12.Cu")
		(hatch none 0.5)
		(connect_pads
			(clearance 0)
		)
		(min_thickness 0.25)
		(keepout
			(tracks not_allowed)
			(vias allowed)
			(pads allowed)
			(copperpour not_allowed)
			(footprints allowed)
		)
		(placement
			(enabled no)
			(sheetname "")
		)
		(fill
			(thermal_gap 0.5)
			(thermal_bridge_width 0.5)
			(island_removal_mode 0)
		)
		(polygon
			(pts
				(xy 54.069996 -131.974082) (xy 54.628796 -131.974082) (xy 54.628796 -133.777482) (xy 54.069996 -133.777482)
			)
		)
	)
	(zone
		(layer "In12.Cu")
		(hatch none 0.5)
		(connect_pads
			(clearance 0)
		)
		(min_thickness 0.25)
		(keepout
			(tracks not_allowed)
			(vias allowed)
			(pads allowed)
			(copperpour not_allowed)
			(footprints allowed)
		)
		(placement
			(enabled no)
			(sheetname "")
		)
		(fill
			(thermal_gap 0.5)
			(thermal_bridge_width 0.5)
			(island_removal_mode 0)
		)
		(polygon
			(pts
				(xy 106.77017 -131.974082) (xy 107.32897 -131.974082) (xy 107.32897 -133.777482) (xy 106.77017 -133.777482)
			)
		)
	)
	(zone
		(layer "In12.Cu")
		(hatch none 0.5)
		(connect_pads
			(clearance 0)
		)
		(min_thickness 0.25)
		(keepout
			(tracks not_allowed)
			(vias allowed)
			(pads allowed)
			(copperpour not_allowed)
			(footprints allowed)
		)
		(placement
			(enabled no)
			(sheetname "")
		)
		(fill
			(thermal_gap 0.5)
			(thermal_bridge_width 0.5)
			(island_removal_mode 0)
		)
		(polygon
			(pts
				(xy 422.65092 -149.606) (xy 422.65092 -150.368) (xy 423.64152 -150.368) (xy 423.64152 -149.606)
			)
		)
	)
	(zone
		(layer "In12.Cu")
		(hatch none 0.5)
		(connect_pads
			(clearance 0)
		)
		(min_thickness 0.25)
		(keepout
			(tracks not_allowed)
			(vias allowed)
			(pads allowed)
			(copperpour not_allowed)
			(footprints allowed)
		)
		(placement
			(enabled no)
			(sheetname "")
		)
		(fill
			(thermal_gap 0.5)
			(thermal_bridge_width 0.5)
			(island_removal_mode 0)
		)
		(polygon
			(pts
				(xy 37.920168 -19.322542) (xy 38.478968 -19.322542) (xy 38.478968 -21.125942) (xy 37.920168 -21.125942)
			)
		)
	)
	(zone
		(layer "In12.Cu")
		(hatch none 0.5)
		(connect_pads
			(clearance 0)
		)
		(min_thickness 0.25)
		(keepout
			(tracks not_allowed)
			(vias allowed)
			(pads allowed)
			(copperpour not_allowed)
			(footprints allowed)
		)
		(placement
			(enabled no)
			(sheetname "")
		)
		(fill
			(thermal_gap 0.5)
			(thermal_bridge_width 0.5)
			(island_removal_mode 0)
		)
		(polygon
			(pts
				(xy 291.320474 -136.975342) (xy 291.879274 -136.975342) (xy 291.879274 -138.778742) (xy 291.320474 -138.778742)
			)
		)
	)
	(zone
		(layer "In12.Cu")
		(hatch none 0.5)
		(connect_pads
			(clearance 0)
		)
		(min_thickness 0.25)
		(keepout
			(tracks not_allowed)
			(vias allowed)
			(pads allowed)
			(copperpour not_allowed)
			(footprints allowed)
		)
		(placement
			(enabled no)
			(sheetname "")
		)
		(fill
			(thermal_gap 0.5)
			(thermal_bridge_width 0.5)
			(island_removal_mode 0)
		)
		(polygon
			(pts
				(xy 276.02053 -151.176482) (xy 276.57933 -151.176482) (xy 276.57933 -152.979882) (xy 276.02053 -152.979882)
			)
		)
	)
	(zone
		(layer "In12.Cu")
		(hatch none 0.5)
		(connect_pads
			(clearance 0)
		)
		(min_thickness 0.25)
		(keepout
			(tracks not_allowed)
			(vias allowed)
			(pads allowed)
			(copperpour not_allowed)
			(footprints allowed)
		)
		(placement
			(enabled no)
			(sheetname "")
		)
		(fill
			(thermal_gap 0.5)
			(thermal_bridge_width 0.5)
			(island_removal_mode 0)
		)
		(polygon
			(pts
				(xy 281.97048 -19.322542) (xy 282.52928 -19.322542) (xy 282.52928 -21.125942) (xy 281.97048 -21.125942)
			)
		)
	)
	(zone
		(layer "In12.Cu")
		(hatch none 0.5)
		(connect_pads
			(clearance 0)
		)
		(min_thickness 0.25)
		(keepout
			(tracks not_allowed)
			(vias allowed)
			(pads allowed)
			(copperpour not_allowed)
			(footprints allowed)
		)
		(placement
			(enabled no)
			(sheetname "")
		)
		(fill
			(thermal_gap 0.5)
			(thermal_bridge_width 0.5)
			(island_removal_mode 0)
		)
		(polygon
			(pts
				(xy 285.370524 -14.321282) (xy 285.929324 -14.321282) (xy 285.929324 -16.124682) (xy 285.370524 -16.124682)
			)
		)
	)
	(zone
		(layer "In12.Cu")
		(hatch none 0.5)
		(connect_pads
			(clearance 0)
		)
		(min_thickness 0.25)
		(keepout
			(tracks not_allowed)
			(vias allowed)
			(pads allowed)
			(copperpour not_allowed)
			(footprints allowed)
		)
		(placement
			(enabled no)
			(sheetname "")
		)
		(fill
			(thermal_gap 0.5)
			(thermal_bridge_width 0.5)
			(island_removal_mode 0)
		)
		(polygon
			(pts
				(xy 200.37044 -9.721342) (xy 200.92924 -9.721342) (xy 200.92924 -11.524742) (xy 200.37044 -11.524742)
			)
		)
	)
	(zone
		(layer "In12.Cu")
		(hatch none 0.5)
		(connect_pads
			(clearance 0)
		)
		(min_thickness 0.25)
		(keepout
			(tracks not_allowed)
			(vias allowed)
			(pads allowed)
			(copperpour not_allowed)
			(footprints allowed)
		)
		(placement
			(enabled no)
			(sheetname "")
		)
		(fill
			(thermal_gap 0.5)
			(thermal_bridge_width 0.5)
			(island_removal_mode 0)
		)
		(polygon
			(pts
				(xy 37.920168 -9.721342) (xy 38.478968 -9.721342) (xy 38.478968 -11.524742) (xy 37.920168 -11.524742)
			)
		)
	)
	(zone
		(layer "In12.Cu")
		(hatch none 0.5)
		(connect_pads
			(clearance 0)
		)
		(min_thickness 0.25)
		(keepout
			(tracks not_allowed)
			(vias allowed)
			(pads allowed)
			(copperpour not_allowed)
			(footprints allowed)
		)
		(placement
			(enabled no)
			(sheetname "")
		)
		(fill
			(thermal_gap 0.5)
			(thermal_bridge_width 0.5)
			(island_removal_mode 0)
		)
		(polygon
			(pts
				(xy 280.270458 -127.374142) (xy 280.829258 -127.374142) (xy 280.829258 -129.177542) (xy 280.270458 -129.177542)
			)
		)
	)
	(zone
		(layer "In12.Cu")
		(hatch none 0.5)
		(connect_pads
			(clearance 0)
		)
		(min_thickness 0.25)
		(keepout
			(tracks not_allowed)
			(vias allowed)
			(pads allowed)
			(copperpour not_allowed)
			(footprints allowed)
		)
		(placement
			(enabled no)
			(sheetname "")
		)
		(fill
			(thermal_gap 0.5)
			(thermal_bridge_width 0.5)
			(island_removal_mode 0)
		)
		(polygon
			(pts
				(xy 101.670104 -19.322542) (xy 102.228904 -19.322542) (xy 102.228904 -21.125942) (xy 101.670104 -21.125942)
			)
		)
	)
	(zone
		(layer "In12.Cu")
		(hatch none 0.5)
		(connect_pads
			(clearance 0)
		)
		(min_thickness 0.25)
		(keepout
			(tracks not_allowed)
			(vias allowed)
			(pads allowed)
			(copperpour not_allowed)
			(footprints allowed)
		)
		(placement
			(enabled no)
			(sheetname "")
		)
		(fill
			(thermal_gap 0.5)
			(thermal_bridge_width 0.5)
			(island_removal_mode 0)
		)
		(polygon
			(pts
				(xy 233.520488 -4.720082) (xy 234.079288 -4.720082) (xy 234.079288 -6.523482) (xy 233.520488 -6.523482)
			)
		)
	)
	(zone
		(layer "In12.Cu")
		(hatch none 0.5)
		(connect_pads
			(clearance 0)
		)
		(min_thickness 0.25)
		(keepout
			(tracks not_allowed)
			(vias allowed)
			(pads allowed)
			(copperpour not_allowed)
			(footprints allowed)
		)
		(placement
			(enabled no)
			(sheetname "")
		)
		(fill
			(thermal_gap 0.5)
			(thermal_bridge_width 0.5)
			(island_removal_mode 0)
		)
		(polygon
			(pts
				(xy 274.320508 -23.922482) (xy 274.879308 -23.922482) (xy 274.879308 -25.725882) (xy 274.320508 -25.725882)
			)
		)
	)
	(zone
		(layer "In12.Cu")
		(hatch none 0.5)
		(connect_pads
			(clearance 0)
		)
		(min_thickness 0.25)
		(keepout
			(tracks not_allowed)
			(vias allowed)
			(pads allowed)
			(copperpour not_allowed)
			(footprints allowed)
		)
		(placement
			(enabled no)
			(sheetname "")
		)
		(fill
			(thermal_gap 0.5)
			(thermal_bridge_width 0.5)
			(island_removal_mode 0)
		)
		(polygon
			(pts
				(xy 291.320474 -127.374142) (xy 291.879274 -127.374142) (xy 291.879274 -129.177542) (xy 291.320474 -129.177542)
			)
		)
	)
	(zone
		(layer "In12.Cu")
		(hatch none 0.5)
		(connect_pads
			(clearance 0)
		)
		(min_thickness 0.25)
		(keepout
			(tracks not_allowed)
			(vias allowed)
			(pads allowed)
			(copperpour not_allowed)
			(footprints allowed)
		)
		(placement
			(enabled no)
			(sheetname "")
		)
		(fill
			(thermal_gap 0.5)
			(thermal_bridge_width 0.5)
			(island_removal_mode 0)
		)
		(polygon
			(pts
				(xy 408.1018 -153.2128) (xy 408.1018 -153.9748) (xy 409.0924 -153.9748) (xy 409.0924 -153.2128)
			)
		)
	)
	(zone
		(layer "In12.Cu")
		(hatch none 0.5)
		(connect_pads
			(clearance 0)
		)
		(min_thickness 0.25)
		(keepout
			(tracks not_allowed)
			(vias allowed)
			(pads allowed)
			(copperpour not_allowed)
			(footprints allowed)
		)
		(placement
			(enabled no)
			(sheetname "")
		)
		(fill
			(thermal_gap 0.5)
			(thermal_bridge_width 0.5)
			(island_removal_mode 0)
		)
		(polygon
			(pts
				(xy 48.96993 -146.576542) (xy 49.52873 -146.576542) (xy 49.52873 -148.379942) (xy 48.96993 -148.379942)
			)
		)
	)
	(zone
		(layer "In12.Cu")
		(hatch none 0.5)
		(connect_pads
			(clearance 0)
		)
		(min_thickness 0.25)
		(keepout
			(tracks not_allowed)
			(vias allowed)
			(pads allowed)
			(copperpour not_allowed)
			(footprints allowed)
		)
		(placement
			(enabled no)
			(sheetname "")
		)
		(fill
			(thermal_gap 0.5)
			(thermal_bridge_width 0.5)
			(island_removal_mode 0)
		)
		(polygon
			(pts
				(xy 84.670138 -4.720082) (xy 85.228938 -4.720082) (xy 85.228938 -6.523482) (xy 84.670138 -6.523482)
			)
		)
	)
	(zone
		(layer "In12.Cu")
		(hatch none 0.5)
		(connect_pads
			(clearance 0)
		)
		(min_thickness 0.25)
		(keepout
			(tracks not_allowed)
			(vias allowed)
			(pads allowed)
			(copperpour not_allowed)
			(footprints allowed)
		)
		(placement
			(enabled no)
			(sheetname "")
		)
		(fill
			(thermal_gap 0.5)
			(thermal_bridge_width 0.5)
			(island_removal_mode 0)
		)
		(polygon
			(pts
				(xy 270.07058 -146.576542) (xy 270.62938 -146.576542) (xy 270.62938 -148.379942) (xy 270.07058 -148.379942)
			)
		)
	)
	(zone
		(layer "In12.Cu")
		(hatch none 0.5)
		(connect_pads
			(clearance 0)
		)
		(min_thickness 0.25)
		(keepout
			(tracks not_allowed)
			(vias allowed)
			(pads allowed)
			(copperpour not_allowed)
			(footprints allowed)
		)
		(placement
			(enabled no)
			(sheetname "")
		)
		(fill
			(thermal_gap 0.5)
			(thermal_bridge_width 0.5)
			(island_removal_mode 0)
		)
		(polygon
			(pts
				(xy 314.27039 -19.322542) (xy 314.82919 -19.322542) (xy 314.82919 -21.125942) (xy 314.27039 -21.125942)
			)
		)
	)
	(zone
		(layer "In12.Cu")
		(hatch none 0.5)
		(connect_pads
			(clearance 0)
		)
		(min_thickness 0.25)
		(keepout
			(tracks not_allowed)
			(vias allowed)
			(pads allowed)
			(copperpour not_allowed)
			(footprints allowed)
		)
		(placement
			(enabled no)
			(sheetname "")
		)
		(fill
			(thermal_gap 0.5)
			(thermal_bridge_width 0.5)
			(island_removal_mode 0)
		)
		(polygon
			(pts
				(xy 247.12041 -127.374142) (xy 247.67921 -127.374142) (xy 247.67921 -129.177542) (xy 247.12041 -129.177542)
			)
		)
	)
	(zone
		(layer "In12.Cu")
		(hatch none 0.5)
		(connect_pads
			(clearance 0)
		)
		(min_thickness 0.25)
		(keepout
			(tracks not_allowed)
			(vias allowed)
			(pads allowed)
			(copperpour not_allowed)
			(footprints allowed)
		)
		(placement
			(enabled no)
			(sheetname "")
		)
		(fill
			(thermal_gap 0.5)
			(thermal_bridge_width 0.5)
			(island_removal_mode 0)
		)
		(polygon
			(pts
				(xy 219.070428 -131.974082) (xy 219.629228 -131.974082) (xy 219.629228 -133.777482) (xy 219.070428 -133.777482)
			)
		)
	)
	(zone
		(layer "In12.Cu")
		(hatch none 0.5)
		(connect_pads
			(clearance 0)
		)
		(min_thickness 0.25)
		(keepout
			(tracks not_allowed)
			(vias allowed)
			(pads allowed)
			(copperpour not_allowed)
			(footprints allowed)
		)
		(placement
			(enabled no)
			(sheetname "")
		)
		(fill
			(thermal_gap 0.5)
			(thermal_bridge_width 0.5)
			(island_removal_mode 0)
		)
		(polygon
			(pts
				(xy 236.920532 -14.321282) (xy 237.479332 -14.321282) (xy 237.479332 -16.124682) (xy 236.920532 -16.124682)
			)
		)
	)
	(zone
		(layer "In12.Cu")
		(hatch none 0.5)
		(connect_pads
			(clearance 0)
		)
		(min_thickness 0.25)
		(keepout
			(tracks not_allowed)
			(vias allowed)
			(pads allowed)
			(copperpour not_allowed)
			(footprints allowed)
		)
		(placement
			(enabled no)
			(sheetname "")
		)
		(fill
			(thermal_gap 0.5)
			(thermal_bridge_width 0.5)
			(island_removal_mode 0)
		)
		(polygon
			(pts
				(xy 148.420074 -23.922482) (xy 148.978874 -23.922482) (xy 148.978874 -25.725882) (xy 148.420074 -25.725882)
			)
		)
	)
	(zone
		(layer "In12.Cu")
		(hatch none 0.5)
		(connect_pads
			(clearance 0)
		)
		(min_thickness 0.25)
		(keepout
			(tracks not_allowed)
			(vias allowed)
			(pads allowed)
			(copperpour not_allowed)
			(footprints allowed)
		)
		(placement
			(enabled no)
			(sheetname "")
		)
		(fill
			(thermal_gap 0.5)
			(thermal_bridge_width 0.5)
			(island_removal_mode 0)
		)
		(polygon
			(pts
				(xy 59.170062 -4.720082) (xy 59.728862 -4.720082) (xy 59.728862 -6.523482) (xy 59.170062 -6.523482)
			)
		)
	)
	(zone
		(layer "In12.Cu")
		(hatch none 0.5)
		(connect_pads
			(clearance 0)
		)
		(min_thickness 0.25)
		(keepout
			(tracks not_allowed)
			(vias allowed)
			(pads allowed)
			(copperpour not_allowed)
			(footprints allowed)
		)
		(placement
			(enabled no)
			(sheetname "")
		)
		(fill
			(thermal_gap 0.5)
			(thermal_bridge_width 0.5)
			(island_removal_mode 0)
		)
		(polygon
			(pts
				(xy 297.270424 -9.721342) (xy 297.829224 -9.721342) (xy 297.829224 -11.524742) (xy 297.270424 -11.524742)
			)
		)
	)
	(zone
		(layer "In12.Cu")
		(hatch none 0.5)
		(connect_pads
			(clearance 0)
		)
		(min_thickness 0.25)
		(keepout
			(tracks not_allowed)
			(vias allowed)
			(pads allowed)
			(copperpour not_allowed)
			(footprints allowed)
		)
		(placement
			(enabled no)
			(sheetname "")
		)
		(fill
			(thermal_gap 0.5)
			(thermal_bridge_width 0.5)
			(island_removal_mode 0)
		)
		(polygon
			(pts
				(xy 315.120528 -23.922482) (xy 315.679328 -23.922482) (xy 315.679328 -25.725882) (xy 315.120528 -25.725882)
			)
		)
	)
	(zone
		(layer "In12.Cu")
		(hatch none 0.5)
		(connect_pads
			(clearance 0)
		)
		(min_thickness 0.25)
		(keepout
			(tracks not_allowed)
			(vias allowed)
			(pads allowed)
			(copperpour not_allowed)
			(footprints allowed)
		)
		(placement
			(enabled no)
			(sheetname "")
		)
		(fill
			(thermal_gap 0.5)
			(thermal_bridge_width 0.5)
			(island_removal_mode 0)
		)
		(polygon
			(pts
				(xy 247.12041 -131.974082) (xy 247.67921 -131.974082) (xy 247.67921 -133.777482) (xy 247.12041 -133.777482)
			)
		)
	)
	(zone
		(layer "In12.Cu")
		(hatch none 0.5)
		(connect_pads
			(clearance 0)
		)
		(min_thickness 0.25)
		(keepout
			(tracks not_allowed)
			(vias allowed)
			(pads allowed)
			(copperpour not_allowed)
			(footprints allowed)
		)
		(placement
			(enabled no)
			(sheetname "")
		)
		(fill
			(thermal_gap 0.5)
			(thermal_bridge_width 0.5)
			(island_removal_mode 0)
		)
		(polygon
			(pts
				(xy 237.770416 -146.576542) (xy 238.329216 -146.576542) (xy 238.329216 -148.379942) (xy 237.770416 -148.379942)
			)
		)
	)
	(zone
		(layer "In12.Cu")
		(hatch none 0.5)
		(connect_pads
			(clearance 0)
		)
		(min_thickness 0.25)
		(keepout
			(tracks not_allowed)
			(vias allowed)
			(pads allowed)
			(copperpour not_allowed)
			(footprints allowed)
		)
		(placement
			(enabled no)
			(sheetname "")
		)
		(fill
			(thermal_gap 0.5)
			(thermal_bridge_width 0.5)
			(island_removal_mode 0)
		)
		(polygon
			(pts
				(xy 142.46987 -23.922482) (xy 143.02867 -23.922482) (xy 143.02867 -25.725882) (xy 142.46987 -25.725882)
			)
		)
	)
	(zone
		(layer "In12.Cu")
		(hatch none 0.5)
		(connect_pads
			(clearance 0)
		)
		(min_thickness 0.25)
		(keepout
			(tracks not_allowed)
			(vias allowed)
			(pads allowed)
			(copperpour not_allowed)
			(footprints allowed)
		)
		(placement
			(enabled no)
			(sheetname "")
		)
		(fill
			(thermal_gap 0.5)
			(thermal_bridge_width 0.5)
			(island_removal_mode 0)
		)
		(polygon
			(pts
				(xy 441.0964 -51.1556) (xy 441.6044 -51.1556) (xy 441.6044 -52.5526) (xy 441.0964 -52.5526)
			)
		)
	)
	(zone
		(layer "In12.Cu")
		(hatch none 0.5)
		(connect_pads
			(clearance 0)
		)
		(min_thickness 0.25)
		(keepout
			(tracks not_allowed)
			(vias allowed)
			(pads allowed)
			(copperpour not_allowed)
			(footprints allowed)
		)
		(placement
			(enabled no)
			(sheetname "")
		)
		(fill
			(thermal_gap 0.5)
			(thermal_bridge_width 0.5)
			(island_removal_mode 0)
		)
		(polygon
			(pts
				(xy 225.870516 -4.720082) (xy 226.429316 -4.720082) (xy 226.429316 -6.523482) (xy 225.870516 -6.523482)
			)
		)
	)
	(zone
		(layer "In12.Cu")
		(hatch none 0.5)
		(connect_pads
			(clearance 0)
		)
		(min_thickness 0.25)
		(keepout
			(tracks not_allowed)
			(vias allowed)
			(pads allowed)
			(copperpour not_allowed)
			(footprints allowed)
		)
		(placement
			(enabled no)
			(sheetname "")
		)
		(fill
			(thermal_gap 0.5)
			(thermal_bridge_width 0.5)
			(island_removal_mode 0)
		)
		(polygon
			(pts
				(xy 150.96998 -9.721342) (xy 151.52878 -9.721342) (xy 151.52878 -11.524742) (xy 150.96998 -11.524742)
			)
		)
	)
	(zone
		(layer "In12.Cu")
		(hatch none 0.5)
		(connect_pads
			(clearance 0)
		)
		(min_thickness 0.25)
		(keepout
			(tracks not_allowed)
			(vias allowed)
			(pads allowed)
			(copperpour not_allowed)
			(footprints allowed)
		)
		(placement
			(enabled no)
			(sheetname "")
		)
		(fill
			(thermal_gap 0.5)
			(thermal_bridge_width 0.5)
			(island_removal_mode 0)
		)
		(polygon
			(pts
				(xy 201.220578 -19.322542) (xy 201.779378 -19.322542) (xy 201.779378 -21.125942) (xy 201.220578 -21.125942)
			)
		)
	)
	(zone
		(layer "In12.Cu")
		(hatch none 0.5)
		(connect_pads
			(clearance 0)
		)
		(min_thickness 0.25)
		(keepout
			(tracks not_allowed)
			(vias allowed)
			(pads allowed)
			(copperpour not_allowed)
			(footprints allowed)
		)
		(placement
			(enabled no)
			(sheetname "")
		)
		(fill
			(thermal_gap 0.5)
			(thermal_bridge_width 0.5)
			(island_removal_mode 0)
		)
		(polygon
			(pts
				(xy 225.020378 -127.374142) (xy 225.579178 -127.374142) (xy 225.579178 -129.177542) (xy 225.020378 -129.177542)
			)
		)
	)
	(zone
		(layer "In12.Cu")
		(hatch none 0.5)
		(connect_pads
			(clearance 0)
		)
		(min_thickness 0.25)
		(keepout
			(tracks not_allowed)
			(vias allowed)
			(pads allowed)
			(copperpour not_allowed)
			(footprints allowed)
		)
		(placement
			(enabled no)
			(sheetname "")
		)
		(fill
			(thermal_gap 0.5)
			(thermal_bridge_width 0.5)
			(island_removal_mode 0)
		)
		(polygon
			(pts
				(xy 33.669986 -127.374142) (xy 34.228786 -127.374142) (xy 34.228786 -129.177542) (xy 33.669986 -129.177542)
			)
		)
	)
	(zone
		(layer "In12.Cu")
		(hatch none 0.5)
		(connect_pads
			(clearance 0)
		)
		(min_thickness 0.25)
		(keepout
			(tracks not_allowed)
			(vias allowed)
			(pads allowed)
			(copperpour not_allowed)
			(footprints allowed)
		)
		(placement
			(enabled no)
			(sheetname "")
		)
		(fill
			(thermal_gap 0.5)
			(thermal_bridge_width 0.5)
			(island_removal_mode 0)
		)
		(polygon
			(pts
				(xy 34.520124 -151.176482) (xy 35.078924 -151.176482) (xy 35.078924 -152.979882) (xy 34.520124 -152.979882)
			)
		)
	)
	(zone
		(layer "In12.Cu")
		(hatch none 0.5)
		(connect_pads
			(clearance 0)
		)
		(min_thickness 0.25)
		(keepout
			(tracks not_allowed)
			(vias allowed)
			(pads allowed)
			(copperpour not_allowed)
			(footprints allowed)
		)
		(placement
			(enabled no)
			(sheetname "")
		)
		(fill
			(thermal_gap 0.5)
			(thermal_bridge_width 0.5)
			(island_removal_mode 0)
		)
		(polygon
			(pts
				(xy 210.570572 -0.120142) (xy 211.129372 -0.120142) (xy 211.129372 -1.923542) (xy 210.570572 -1.923542)
			)
		)
	)
	(zone
		(layer "In12.Cu")
		(hatch none 0.5)
		(connect_pads
			(clearance 0)
		)
		(min_thickness 0.25)
		(keepout
			(tracks not_allowed)
			(vias allowed)
			(pads allowed)
			(copperpour not_allowed)
			(footprints allowed)
		)
		(placement
			(enabled no)
			(sheetname "")
		)
		(fill
			(thermal_gap 0.5)
			(thermal_bridge_width 0.5)
			(island_removal_mode 0)
		)
		(polygon
			(pts
				(xy 202.070462 -141.575282) (xy 202.629262 -141.575282) (xy 202.629262 -143.378682) (xy 202.070462 -143.378682)
			)
		)
	)
	(zone
		(layer "In12.Cu")
		(hatch none 0.5)
		(connect_pads
			(clearance 0)
		)
		(min_thickness 0.25)
		(keepout
			(tracks not_allowed)
			(vias allowed)
			(pads allowed)
			(copperpour not_allowed)
			(footprints allowed)
		)
		(placement
			(enabled no)
			(sheetname "")
		)
		(fill
			(thermal_gap 0.5)
			(thermal_bridge_width 0.5)
			(island_removal_mode 0)
		)
		(polygon
			(pts
				(xy 243.720366 -9.721342) (xy 244.279166 -9.721342) (xy 244.279166 -11.524742) (xy 243.720366 -11.524742)
			)
		)
	)
	(zone
		(layer "In12.Cu")
		(hatch none 0.5)
		(connect_pads
			(clearance 0)
		)
		(min_thickness 0.25)
		(keepout
			(tracks not_allowed)
			(vias allowed)
			(pads allowed)
			(copperpour not_allowed)
			(footprints allowed)
		)
		(placement
			(enabled no)
			(sheetname "")
		)
		(fill
			(thermal_gap 0.5)
			(thermal_bridge_width 0.5)
			(island_removal_mode 0)
		)
		(polygon
			(pts
				(xy 266.670536 -136.975342) (xy 267.229336 -136.975342) (xy 267.229336 -138.778742) (xy 266.670536 -138.778742)
			)
		)
	)
	(zone
		(layer "In12.Cu")
		(hatch none 0.5)
		(connect_pads
			(clearance 0)
		)
		(min_thickness 0.25)
		(keepout
			(tracks not_allowed)
			(vias allowed)
			(pads allowed)
			(copperpour not_allowed)
			(footprints allowed)
		)
		(placement
			(enabled no)
			(sheetname "")
		)
		(fill
			(thermal_gap 0.5)
			(thermal_bridge_width 0.5)
			(island_removal_mode 0)
		)
		(polygon
			(pts
				(xy 205.470506 -131.974082) (xy 206.029306 -131.974082) (xy 206.029306 -133.777482) (xy 205.470506 -133.777482)
			)
		)
	)
	(zone
		(layer "In12.Cu")
		(hatch none 0.5)
		(connect_pads
			(clearance 0)
		)
		(min_thickness 0.25)
		(keepout
			(tracks not_allowed)
			(vias allowed)
			(pads allowed)
			(copperpour not_allowed)
			(footprints allowed)
		)
		(placement
			(enabled no)
			(sheetname "")
		)
		(fill
			(thermal_gap 0.5)
			(thermal_bridge_width 0.5)
			(island_removal_mode 0)
		)
		(polygon
			(pts
				(xy 250.520454 -0.120142) (xy 251.079254 -0.120142) (xy 251.079254 -1.923542) (xy 250.520454 -1.923542)
			)
		)
	)
	(zone
		(layer "In12.Cu")
		(hatch none 0.5)
		(connect_pads
			(clearance 0)
		)
		(min_thickness 0.25)
		(keepout
			(tracks not_allowed)
			(vias allowed)
			(pads allowed)
			(copperpour not_allowed)
			(footprints allowed)
		)
		(placement
			(enabled no)
			(sheetname "")
		)
		(fill
			(thermal_gap 0.5)
			(thermal_bridge_width 0.5)
			(island_removal_mode 0)
		)
		(polygon
			(pts
				(xy 302.37049 -19.322542) (xy 302.92929 -19.322542) (xy 302.92929 -21.125942) (xy 302.37049 -21.125942)
			)
		)
	)
	(zone
		(layer "In12.Cu")
		(hatch none 0.5)
		(connect_pads
			(clearance 0)
		)
		(min_thickness 0.25)
		(keepout
			(tracks not_allowed)
			(vias allowed)
			(pads allowed)
			(copperpour not_allowed)
			(footprints allowed)
		)
		(placement
			(enabled no)
			(sheetname "")
		)
		(fill
			(thermal_gap 0.5)
			(thermal_bridge_width 0.5)
			(island_removal_mode 0)
		)
		(polygon
			(pts
				(xy 44.720002 -151.176482) (xy 45.278802 -151.176482) (xy 45.278802 -152.979882) (xy 44.720002 -152.979882)
			)
		)
	)
	(zone
		(layer "In12.Cu")
		(hatch none 0.5)
		(connect_pads
			(clearance 0)
		)
		(min_thickness 0.25)
		(keepout
			(tracks not_allowed)
			(vias allowed)
			(pads allowed)
			(copperpour not_allowed)
			(footprints allowed)
		)
		(placement
			(enabled no)
			(sheetname "")
		)
		(fill
			(thermal_gap 0.5)
			(thermal_bridge_width 0.5)
			(island_removal_mode 0)
		)
		(polygon
			(pts
				(xy 137.370058 -19.322542) (xy 137.928858 -19.322542) (xy 137.928858 -21.125942) (xy 137.370058 -21.125942)
			)
		)
	)
	(zone
		(layer "In12.Cu")
		(hatch none 0.5)
		(connect_pads
			(clearance 0)
		)
		(min_thickness 0.25)
		(keepout
			(tracks not_allowed)
			(vias allowed)
			(pads allowed)
			(copperpour not_allowed)
			(footprints allowed)
		)
		(placement
			(enabled no)
			(sheetname "")
		)
		(fill
			(thermal_gap 0.5)
			(thermal_bridge_width 0.5)
			(island_removal_mode 0)
		)
		(polygon
			(pts
				(xy 37.07003 -14.321282) (xy 37.62883 -14.321282) (xy 37.62883 -16.124682) (xy 37.07003 -16.124682)
			)
		)
	)
	(zone
		(layer "In12.Cu")
		(hatch none 0.5)
		(connect_pads
			(clearance 0)
		)
		(min_thickness 0.25)
		(keepout
			(tracks not_allowed)
			(vias allowed)
			(pads allowed)
			(copperpour not_allowed)
			(footprints allowed)
		)
		(placement
			(enabled no)
			(sheetname "")
		)
		(fill
			(thermal_gap 0.5)
			(thermal_bridge_width 0.5)
			(island_removal_mode 0)
		)
		(polygon
			(pts
				(xy 229.27056 -0.120142) (xy 229.82936 -0.120142) (xy 229.82936 -1.923542) (xy 229.27056 -1.923542)
			)
		)
	)
	(zone
		(layer "In12.Cu")
		(hatch none 0.5)
		(connect_pads
			(clearance 0)
		)
		(min_thickness 0.25)
		(keepout
			(tracks not_allowed)
			(vias allowed)
			(pads allowed)
			(copperpour not_allowed)
			(footprints allowed)
		)
		(placement
			(enabled no)
			(sheetname "")
		)
		(fill
			(thermal_gap 0.5)
			(thermal_bridge_width 0.5)
			(island_removal_mode 0)
		)
		(polygon
			(pts
				(xy 83.82 -131.974082) (xy 84.3788 -131.974082) (xy 84.3788 -133.777482) (xy 83.82 -133.777482)
			)
		)
	)
	(zone
		(layer "In12.Cu")
		(hatch none 0.5)
		(connect_pads
			(clearance 0)
		)
		(min_thickness 0.25)
		(keepout
			(tracks not_allowed)
			(vias allowed)
			(pads allowed)
			(copperpour not_allowed)
			(footprints allowed)
		)
		(placement
			(enabled no)
			(sheetname "")
		)
		(fill
			(thermal_gap 0.5)
			(thermal_bridge_width 0.5)
			(island_removal_mode 0)
		)
		(polygon
			(pts
				(xy 43.870118 -4.720082) (xy 44.428918 -4.720082) (xy 44.428918 -6.523482) (xy 43.870118 -6.523482)
			)
		)
	)
	(zone
		(layer "In12.Cu")
		(hatch none 0.5)
		(connect_pads
			(clearance 0)
		)
		(min_thickness 0.25)
		(keepout
			(tracks not_allowed)
			(vias allowed)
			(pads allowed)
			(copperpour not_allowed)
			(footprints allowed)
		)
		(placement
			(enabled no)
			(sheetname "")
		)
		(fill
			(thermal_gap 0.5)
			(thermal_bridge_width 0.5)
			(island_removal_mode 0)
		)
		(polygon
			(pts
				(xy 65.120012 -23.922482) (xy 65.678812 -23.922482) (xy 65.678812 -25.725882) (xy 65.120012 -25.725882)
			)
		)
	)
	(zone
		(layer "In12.Cu")
		(hatch none 0.5)
		(connect_pads
			(clearance 0)
		)
		(min_thickness 0.25)
		(keepout
			(tracks not_allowed)
			(vias allowed)
			(pads allowed)
			(copperpour not_allowed)
			(footprints allowed)
		)
		(placement
			(enabled no)
			(sheetname "")
		)
		(fill
			(thermal_gap 0.5)
			(thermal_bridge_width 0.5)
			(island_removal_mode 0)
		)
		(polygon
			(pts
				(xy 256.470404 -131.974082) (xy 257.029204 -131.974082) (xy 257.029204 -133.777482) (xy 256.470404 -133.777482)
			)
		)
	)
	(zone
		(layer "In12.Cu")
		(hatch none 0.5)
		(connect_pads
			(clearance 0)
		)
		(min_thickness 0.25)
		(keepout
			(tracks not_allowed)
			(vias allowed)
			(pads allowed)
			(copperpour not_allowed)
			(footprints allowed)
		)
		(placement
			(enabled no)
			(sheetname "")
		)
		(fill
			(thermal_gap 0.5)
			(thermal_bridge_width 0.5)
			(island_removal_mode 0)
		)
		(polygon
			(pts
				(xy 131.420108 -23.922482) (xy 131.978908 -23.922482) (xy 131.978908 -25.725882) (xy 131.420108 -25.725882)
			)
		)
	)
	(zone
		(layer "In12.Cu")
		(hatch none 0.5)
		(connect_pads
			(clearance 0)
		)
		(min_thickness 0.25)
		(keepout
			(tracks not_allowed)
			(vias allowed)
			(pads allowed)
			(copperpour not_allowed)
			(footprints allowed)
		)
		(placement
			(enabled no)
			(sheetname "")
		)
		(fill
			(thermal_gap 0.5)
			(thermal_bridge_width 0.5)
			(island_removal_mode 0)
		)
		(polygon
			(pts
				(xy 89.76995 -131.974082) (xy 90.32875 -131.974082) (xy 90.32875 -133.777482) (xy 89.76995 -133.777482)
			)
		)
	)
	(zone
		(layer "In12.Cu")
		(hatch none 0.5)
		(connect_pads
			(clearance 0)
		)
		(min_thickness 0.25)
		(keepout
			(tracks not_allowed)
			(vias allowed)
			(pads allowed)
			(copperpour not_allowed)
			(footprints allowed)
		)
		(placement
			(enabled no)
			(sheetname "")
		)
		(fill
			(thermal_gap 0.5)
			(thermal_bridge_width 0.5)
			(island_removal_mode 0)
		)
		(polygon
			(pts
				(xy 60.019946 -9.721342) (xy 60.578746 -9.721342) (xy 60.578746 -11.524742) (xy 60.019946 -11.524742)
			)
		)
	)
	(zone
		(layer "In12.Cu")
		(hatch none 0.5)
		(connect_pads
			(clearance 0)
		)
		(min_thickness 0.25)
		(keepout
			(tracks not_allowed)
			(vias allowed)
			(pads allowed)
			(copperpour not_allowed)
			(footprints allowed)
		)
		(placement
			(enabled no)
			(sheetname "")
		)
		(fill
			(thermal_gap 0.5)
			(thermal_bridge_width 0.5)
			(island_removal_mode 0)
		)
		(polygon
			(pts
				(xy 118.67007 -127.374142) (xy 119.22887 -127.374142) (xy 119.22887 -129.177542) (xy 118.67007 -129.177542)
			)
		)
	)
	(zone
		(net "PVDDQ_DEF")
		(layer "In12.Cu")
		(hatch none 0.5)
		(connect_pads
			(clearance 0.5)
		)
		(min_thickness 0.25)
		(fill yes
			(thermal_gap 0.5)
			(thermal_bridge_width 0.5)
			(island_removal_mode 0)
		)
		(polygon
			(pts
				(xy 265.153394 -148.3741) (xy 264.9601 -148.567394) (xy 264.9601 -149.425406) (xy 265.127994 -149.5933)
				(xy 267.992606 -149.5933) (xy 268.399006 -149.1869) (xy 268.830806 -149.1869) (xy 268.8971 -149.120606)
				(xy 268.8971 -148.643594) (xy 268.627606 -148.3741)
			)
		)
	)
	(zone
		(layer "In12.Cu")
		(hatch none 0.5)
		(connect_pads
			(clearance 0)
		)
		(min_thickness 0.25)
		(keepout
			(tracks not_allowed)
			(vias allowed)
			(pads allowed)
			(copperpour not_allowed)
			(footprints allowed)
		)
		(placement
			(enabled no)
			(sheetname "")
		)
		(fill
			(thermal_gap 0.5)
			(thermal_bridge_width 0.5)
			(island_removal_mode 0)
		)
		(polygon
			(pts
				(xy 84.670138 -14.321282) (xy 85.228938 -14.321282) (xy 85.228938 -16.124682) (xy 84.670138 -16.124682)
			)
		)
	)
	(zone
		(layer "In12.Cu")
		(hatch none 0.5)
		(connect_pads
			(clearance 0)
		)
		(min_thickness 0.25)
		(keepout
			(tracks not_allowed)
			(vias allowed)
			(pads allowed)
			(copperpour not_allowed)
			(footprints allowed)
		)
		(placement
			(enabled no)
			(sheetname "")
		)
		(fill
			(thermal_gap 0.5)
			(thermal_bridge_width 0.5)
			(island_removal_mode 0)
		)
		(polygon
			(pts
				(xy 213.120478 -4.720082) (xy 213.679278 -4.720082) (xy 213.679278 -6.523482) (xy 213.120478 -6.523482)
			)
		)
	)
	(zone
		(layer "In12.Cu")
		(hatch none 0.5)
		(connect_pads
			(clearance 0)
		)
		(min_thickness 0.25)
		(keepout
			(tracks not_allowed)
			(vias allowed)
			(pads allowed)
			(copperpour not_allowed)
			(footprints allowed)
		)
		(placement
			(enabled no)
			(sheetname "")
		)
		(fill
			(thermal_gap 0.5)
			(thermal_bridge_width 0.5)
			(island_removal_mode 0)
		)
		(polygon
			(pts
				(xy 43.01998 -19.322542) (xy 43.57878 -19.322542) (xy 43.57878 -21.125942) (xy 43.01998 -21.125942)
			)
		)
	)
	(zone
		(layer "In12.Cu")
		(hatch none 0.5)
		(connect_pads
			(clearance 0)
		)
		(min_thickness 0.25)
		(keepout
			(tracks not_allowed)
			(vias allowed)
			(pads allowed)
			(copperpour not_allowed)
			(footprints allowed)
		)
		(placement
			(enabled no)
			(sheetname "")
		)
		(fill
			(thermal_gap 0.5)
			(thermal_bridge_width 0.5)
			(island_removal_mode 0)
		)
		(polygon
			(pts
				(xy 248.820432 -23.922482) (xy 249.379232 -23.922482) (xy 249.379232 -25.725882) (xy 248.820432 -25.725882)
			)
		)
	)
	(zone
		(layer "In12.Cu")
		(hatch none 0.5)
		(connect_pads
			(clearance 0)
		)
		(min_thickness 0.25)
		(keepout
			(tracks not_allowed)
			(vias allowed)
			(pads allowed)
			(copperpour not_allowed)
			(footprints allowed)
		)
		(placement
			(enabled no)
			(sheetname "")
		)
		(fill
			(thermal_gap 0.5)
			(thermal_bridge_width 0.5)
			(island_removal_mode 0)
		)
		(polygon
			(pts
				(xy 287.070546 -4.720082) (xy 287.629346 -4.720082) (xy 287.629346 -6.523482) (xy 287.070546 -6.523482)
			)
		)
	)
	(zone
		(layer "In12.Cu")
		(hatch none 0.5)
		(connect_pads
			(clearance 0)
		)
		(min_thickness 0.25)
		(keepout
			(tracks not_allowed)
			(vias allowed)
			(pads allowed)
			(copperpour not_allowed)
			(footprints allowed)
		)
		(placement
			(enabled no)
			(sheetname "")
		)
		(fill
			(thermal_gap 0.5)
			(thermal_bridge_width 0.5)
			(island_removal_mode 0)
		)
		(polygon
			(pts
				(xy 230.120444 -151.176482) (xy 230.679244 -151.176482) (xy 230.679244 -152.979882) (xy 230.120444 -152.979882)
			)
		)
	)
	(zone
		(layer "In12.Cu")
		(hatch none 0.5)
		(connect_pads
			(clearance 0)
		)
		(min_thickness 0.25)
		(keepout
			(tracks not_allowed)
			(vias allowed)
			(pads allowed)
			(copperpour not_allowed)
			(footprints allowed)
		)
		(placement
			(enabled no)
			(sheetname "")
		)
		(fill
			(thermal_gap 0.5)
			(thermal_bridge_width 0.5)
			(island_removal_mode 0)
		)
		(polygon
			(pts
				(xy 41.319958 -0.120142) (xy 41.878758 -0.120142) (xy 41.878758 -1.923542) (xy 41.319958 -1.923542)
			)
		)
	)
	(zone
		(layer "In12.Cu")
		(hatch none 0.5)
		(connect_pads
			(clearance 0)
		)
		(min_thickness 0.25)
		(keepout
			(tracks not_allowed)
			(vias allowed)
			(pads allowed)
			(copperpour not_allowed)
			(footprints allowed)
		)
		(placement
			(enabled no)
			(sheetname "")
		)
		(fill
			(thermal_gap 0.5)
			(thermal_bridge_width 0.5)
			(island_removal_mode 0)
		)
		(polygon
			(pts
				(xy 105.070148 -0.120142) (xy 105.628948 -0.120142) (xy 105.628948 -1.923542) (xy 105.070148 -1.923542)
			)
		)
	)
	(zone
		(layer "In12.Cu")
		(hatch none 0.5)
		(connect_pads
			(clearance 0)
		)
		(min_thickness 0.25)
		(keepout
			(tracks not_allowed)
			(vias allowed)
			(pads allowed)
			(copperpour not_allowed)
			(footprints allowed)
		)
		(placement
			(enabled no)
			(sheetname "")
		)
		(fill
			(thermal_gap 0.5)
			(thermal_bridge_width 0.5)
			(island_removal_mode 0)
		)
		(polygon
			(pts
				(xy 135.670036 -136.975342) (xy 136.228836 -136.975342) (xy 136.228836 -138.778742) (xy 135.670036 -138.778742)
			)
		)
	)
	(zone
		(layer "In12.Cu")
		(hatch none 0.5)
		(connect_pads
			(clearance 0)
		)
		(min_thickness 0.25)
		(keepout
			(tracks not_allowed)
			(vias allowed)
			(pads allowed)
			(copperpour not_allowed)
			(footprints allowed)
		)
		(placement
			(enabled no)
			(sheetname "")
		)
		(fill
			(thermal_gap 0.5)
			(thermal_bridge_width 0.5)
			(island_removal_mode 0)
		)
		(polygon
			(pts
				(xy 204.620368 -0.120142) (xy 205.179168 -0.120142) (xy 205.179168 -1.923542) (xy 204.620368 -1.923542)
			)
		)
	)
	(zone
		(net "PVDDQ_KLM")
		(layer "In12.Cu")
		(hatch none 0.5)
		(connect_pads
			(clearance 0.5)
		)
		(min_thickness 0.25)
		(fill yes
			(thermal_gap 0.5)
			(thermal_bridge_width 0.5)
			(island_removal_mode 0)
		)
		(polygon
			(pts
				(xy 100.180394 -148.3995) (xy 100.0125 -148.567394) (xy 100.0125 -149.400006) (xy 100.152454 -149.53996)
				(xy 103.00589 -149.53996) (xy 103.38435 -149.1615) (xy 103.807006 -149.1615) (xy 103.8987 -149.069806)
				(xy 103.8987 -148.567394) (xy 103.730806 -148.3995)
			)
		)
	)
	(zone
		(layer "In12.Cu")
		(hatch none 0.5)
		(connect_pads
			(clearance 0)
		)
		(min_thickness 0.25)
		(keepout
			(tracks not_allowed)
			(vias allowed)
			(pads allowed)
			(copperpour not_allowed)
			(footprints allowed)
		)
		(placement
			(enabled no)
			(sheetname "")
		)
		(fill
			(thermal_gap 0.5)
			(thermal_bridge_width 0.5)
			(island_removal_mode 0)
		)
		(polygon
			(pts
				(xy 145.02003 -19.322542) (xy 145.57883 -19.322542) (xy 145.57883 -21.125942) (xy 145.02003 -21.125942)
			)
		)
	)
	(zone
		(layer "In12.Cu")
		(hatch none 0.5)
		(connect_pads
			(clearance 0)
		)
		(min_thickness 0.25)
		(keepout
			(tracks not_allowed)
			(vias allowed)
			(pads allowed)
			(copperpour not_allowed)
			(footprints allowed)
		)
		(placement
			(enabled no)
			(sheetname "")
		)
		(fill
			(thermal_gap 0.5)
			(thermal_bridge_width 0.5)
			(island_removal_mode 0)
		)
		(polygon
			(pts
				(xy 48.120046 -14.321282) (xy 48.678846 -14.321282) (xy 48.678846 -16.124682) (xy 48.120046 -16.124682)
			)
		)
	)
	(zone
		(layer "In12.Cu")
		(hatch none 0.5)
		(connect_pads
			(clearance 0)
		)
		(min_thickness 0.25)
		(keepout
			(tracks not_allowed)
			(vias allowed)
			(pads allowed)
			(copperpour not_allowed)
			(footprints allowed)
		)
		(placement
			(enabled no)
			(sheetname "")
		)
		(fill
			(thermal_gap 0.5)
			(thermal_bridge_width 0.5)
			(island_removal_mode 0)
		)
		(polygon
			(pts
				(xy 64.270128 -0.120142) (xy 64.828928 -0.120142) (xy 64.828928 -1.923542) (xy 64.270128 -1.923542)
			)
		)
	)
	(zone
		(layer "In12.Cu")
		(hatch none 0.5)
		(connect_pads
			(clearance 0)
		)
		(min_thickness 0.25)
		(keepout
			(tracks not_allowed)
			(vias allowed)
			(pads allowed)
			(copperpour not_allowed)
			(footprints allowed)
		)
		(placement
			(enabled no)
			(sheetname "")
		)
		(fill
			(thermal_gap 0.5)
			(thermal_bridge_width 0.5)
			(island_removal_mode 0)
		)
		(polygon
			(pts
				(xy 49.820068 -4.720082) (xy 50.378868 -4.720082) (xy 50.378868 -6.523482) (xy 49.820068 -6.523482)
			)
		)
	)
	(zone
		(layer "In12.Cu")
		(hatch none 0.5)
		(connect_pads
			(clearance 0)
		)
		(min_thickness 0.25)
		(keepout
			(tracks not_allowed)
			(vias allowed)
			(pads allowed)
			(copperpour not_allowed)
			(footprints allowed)
		)
		(placement
			(enabled no)
			(sheetname "")
		)
		(fill
			(thermal_gap 0.5)
			(thermal_bridge_width 0.5)
			(island_removal_mode 0)
		)
		(polygon
			(pts
				(xy 92.32011 -141.575282) (xy 92.87891 -141.575282) (xy 92.87891 -143.378682) (xy 92.32011 -143.378682)
			)
		)
	)
	(zone
		(layer "In12.Cu")
		(hatch none 0.5)
		(connect_pads
			(clearance 0)
		)
		(min_thickness 0.25)
		(keepout
			(tracks not_allowed)
			(vias allowed)
			(pads allowed)
			(copperpour not_allowed)
			(footprints allowed)
		)
		(placement
			(enabled no)
			(sheetname "")
		)
		(fill
			(thermal_gap 0.5)
			(thermal_bridge_width 0.5)
			(island_removal_mode 0)
		)
		(polygon
			(pts
				(xy 116.11991 -14.321282) (xy 116.67871 -14.321282) (xy 116.67871 -16.124682) (xy 116.11991 -16.124682)
			)
		)
	)
	(zone
		(layer "In12.Cu")
		(hatch none 0.5)
		(connect_pads
			(clearance 0)
		)
		(min_thickness 0.25)
		(keepout
			(tracks not_allowed)
			(vias allowed)
			(pads allowed)
			(copperpour not_allowed)
			(footprints allowed)
		)
		(placement
			(enabled no)
			(sheetname "")
		)
		(fill
			(thermal_gap 0.5)
			(thermal_bridge_width 0.5)
			(island_removal_mode 0)
		)
		(polygon
			(pts
				(xy 73.620122 -9.721342) (xy 74.178922 -9.721342) (xy 74.178922 -11.524742) (xy 73.620122 -11.524742)
			)
		)
	)
	(zone
		(layer "In12.Cu")
		(hatch none 0.5)
		(connect_pads
			(clearance 0)
		)
		(min_thickness 0.25)
		(keepout
			(tracks not_allowed)
			(vias allowed)
			(pads allowed)
			(copperpour not_allowed)
			(footprints allowed)
		)
		(placement
			(enabled no)
			(sheetname "")
		)
		(fill
			(thermal_gap 0.5)
			(thermal_bridge_width 0.5)
			(island_removal_mode 0)
		)
		(polygon
			(pts
				(xy 102.519988 -14.321282) (xy 103.078788 -14.321282) (xy 103.078788 -16.124682) (xy 102.519988 -16.124682)
			)
		)
	)
	(zone
		(layer "In12.Cu")
		(hatch none 0.5)
		(connect_pads
			(clearance 0)
		)
		(min_thickness 0.25)
		(keepout
			(tracks not_allowed)
			(vias allowed)
			(pads allowed)
			(copperpour not_allowed)
			(footprints allowed)
		)
		(placement
			(enabled no)
			(sheetname "")
		)
		(fill
			(thermal_gap 0.5)
			(thermal_bridge_width 0.5)
			(island_removal_mode 0)
		)
		(polygon
			(pts
				(xy 105.070148 -131.974082) (xy 105.628948 -131.974082) (xy 105.628948 -133.777482) (xy 105.070148 -133.777482)
			)
		)
	)
	(zone
		(layer "In12.Cu")
		(hatch none 0.5)
		(connect_pads
			(clearance 0)
		)
		(min_thickness 0.25)
		(keepout
			(tracks not_allowed)
			(vias allowed)
			(pads allowed)
			(copperpour not_allowed)
			(footprints allowed)
		)
		(placement
			(enabled no)
			(sheetname "")
		)
		(fill
			(thermal_gap 0.5)
			(thermal_bridge_width 0.5)
			(island_removal_mode 0)
		)
		(polygon
			(pts
				(xy 109.320076 -131.974082) (xy 109.878876 -131.974082) (xy 109.878876 -133.777482) (xy 109.320076 -133.777482)
			)
		)
	)
	(zone
		(layer "In12.Cu")
		(hatch none 0.5)
		(connect_pads
			(clearance 0)
		)
		(min_thickness 0.25)
		(keepout
			(tracks not_allowed)
			(vias allowed)
			(pads allowed)
			(copperpour not_allowed)
			(footprints allowed)
		)
		(placement
			(enabled no)
			(sheetname "")
		)
		(fill
			(thermal_gap 0.5)
			(thermal_bridge_width 0.5)
			(island_removal_mode 0)
		)
		(polygon
			(pts
				(xy 303.220374 -136.975342) (xy 303.779174 -136.975342) (xy 303.779174 -138.778742) (xy 303.220374 -138.778742)
			)
		)
	)
	(zone
		(layer "In12.Cu")
		(hatch none 0.5)
		(connect_pads
			(clearance 0)
		)
		(min_thickness 0.25)
		(keepout
			(tracks not_allowed)
			(vias allowed)
			(pads allowed)
			(copperpour not_allowed)
			(footprints allowed)
		)
		(placement
			(enabled no)
			(sheetname "")
		)
		(fill
			(thermal_gap 0.5)
			(thermal_bridge_width 0.5)
			(island_removal_mode 0)
		)
		(polygon
			(pts
				(xy 234.370372 -0.120142) (xy 234.929172 -0.120142) (xy 234.929172 -1.923542) (xy 234.370372 -1.923542)
			)
		)
	)
	(zone
		(layer "In12.Cu")
		(hatch none 0.5)
		(connect_pads
			(clearance 0)
		)
		(min_thickness 0.25)
		(keepout
			(tracks not_allowed)
			(vias allowed)
			(pads allowed)
			(copperpour not_allowed)
			(footprints allowed)
		)
		(placement
			(enabled no)
			(sheetname "")
		)
		(fill
			(thermal_gap 0.5)
			(thermal_bridge_width 0.5)
			(island_removal_mode 0)
		)
		(polygon
			(pts
				(xy 57.47004 -141.575282) (xy 58.02884 -141.575282) (xy 58.02884 -143.378682) (xy 57.47004 -143.378682)
			)
		)
	)
	(zone
		(layer "In12.Cu")
		(hatch none 0.5)
		(connect_pads
			(clearance 0)
		)
		(min_thickness 0.25)
		(keepout
			(tracks not_allowed)
			(vias allowed)
			(pads allowed)
			(copperpour not_allowed)
			(footprints allowed)
		)
		(placement
			(enabled no)
			(sheetname "")
		)
		(fill
			(thermal_gap 0.5)
			(thermal_bridge_width 0.5)
			(island_removal_mode 0)
		)
		(polygon
			(pts
				(xy 237.770416 -23.922482) (xy 238.329216 -23.922482) (xy 238.329216 -25.725882) (xy 237.770416 -25.725882)
			)
		)
	)
	(zone
		(layer "In12.Cu")
		(hatch none 0.5)
		(connect_pads
			(clearance 0)
		)
		(min_thickness 0.25)
		(keepout
			(tracks not_allowed)
			(vias allowed)
			(pads allowed)
			(copperpour not_allowed)
			(footprints allowed)
		)
		(placement
			(enabled no)
			(sheetname "")
		)
		(fill
			(thermal_gap 0.5)
			(thermal_bridge_width 0.5)
			(island_removal_mode 0)
		)
		(polygon
			(pts
				(xy 102.519988 -0.120142) (xy 103.078788 -0.120142) (xy 103.078788 -1.923542) (xy 102.519988 -1.923542)
			)
		)
	)
	(zone
		(layer "In12.Cu")
		(hatch none 0.5)
		(connect_pads
			(clearance 0)
		)
		(min_thickness 0.25)
		(keepout
			(tracks not_allowed)
			(vias allowed)
			(pads allowed)
			(copperpour not_allowed)
			(footprints allowed)
		)
		(placement
			(enabled no)
			(sheetname "")
		)
		(fill
			(thermal_gap 0.5)
			(thermal_bridge_width 0.5)
			(island_removal_mode 0)
		)
		(polygon
			(pts
				(xy 236.070394 -19.322542) (xy 236.629194 -19.322542) (xy 236.629194 -21.125942) (xy 236.070394 -21.125942)
			)
		)
	)
	(zone
		(layer "In12.Cu")
		(hatch none 0.5)
		(connect_pads
			(clearance 0)
		)
		(min_thickness 0.25)
		(keepout
			(tracks not_allowed)
			(vias allowed)
			(pads allowed)
			(copperpour not_allowed)
			(footprints allowed)
		)
		(placement
			(enabled no)
			(sheetname "")
		)
		(fill
			(thermal_gap 0.5)
			(thermal_bridge_width 0.5)
			(island_removal_mode 0)
		)
		(polygon
			(pts
				(xy 228.420422 -23.922482) (xy 228.979222 -23.922482) (xy 228.979222 -25.725882) (xy 228.420422 -25.725882)
			)
		)
	)
	(zone
		(layer "In12.Cu")
		(hatch none 0.5)
		(connect_pads
			(clearance 0)
		)
		(min_thickness 0.25)
		(keepout
			(tracks not_allowed)
			(vias allowed)
			(pads allowed)
			(copperpour not_allowed)
			(footprints allowed)
		)
		(placement
			(enabled no)
			(sheetname "")
		)
		(fill
			(thermal_gap 0.5)
			(thermal_bridge_width 0.5)
			(island_removal_mode 0)
		)
		(polygon
			(pts
				(xy 231.820466 -23.922482) (xy 232.379266 -23.922482) (xy 232.379266 -25.725882) (xy 231.820466 -25.725882)
			)
		)
	)
	(zone
		(layer "In12.Cu")
		(hatch none 0.5)
		(connect_pads
			(clearance 0)
		)
		(min_thickness 0.25)
		(keepout
			(tracks not_allowed)
			(vias allowed)
			(pads allowed)
			(copperpour not_allowed)
			(footprints allowed)
		)
		(placement
			(enabled no)
			(sheetname "")
		)
		(fill
			(thermal_gap 0.5)
			(thermal_bridge_width 0.5)
			(island_removal_mode 0)
		)
		(polygon
			(pts
				(xy 203.770484 -151.176482) (xy 204.329284 -151.176482) (xy 204.329284 -152.979882) (xy 203.770484 -152.979882)
			)
		)
	)
	(zone
		(layer "In12.Cu")
		(hatch none 0.5)
		(connect_pads
			(clearance 0)
		)
		(min_thickness 0.25)
		(keepout
			(tracks not_allowed)
			(vias allowed)
			(pads allowed)
			(copperpour not_allowed)
			(footprints allowed)
		)
		(placement
			(enabled no)
			(sheetname "")
		)
		(fill
			(thermal_gap 0.5)
			(thermal_bridge_width 0.5)
			(island_removal_mode 0)
		)
		(polygon
			(pts
				(xy 89.76995 -151.176482) (xy 90.32875 -151.176482) (xy 90.32875 -152.979882) (xy 89.76995 -152.979882)
			)
		)
	)
	(zone
		(layer "In12.Cu")
		(hatch none 0.5)
		(connect_pads
			(clearance 0)
		)
		(min_thickness 0.25)
		(keepout
			(tracks not_allowed)
			(vias allowed)
			(pads allowed)
			(copperpour not_allowed)
			(footprints allowed)
		)
		(placement
			(enabled no)
			(sheetname "")
		)
		(fill
			(thermal_gap 0.5)
			(thermal_bridge_width 0.5)
			(island_removal_mode 0)
		)
		(polygon
			(pts
				(xy 264.970514 -136.975342) (xy 265.529314 -136.975342) (xy 265.529314 -138.778742) (xy 264.970514 -138.778742)
			)
		)
	)
	(zone
		(layer "In12.Cu")
		(hatch none 0.5)
		(connect_pads
			(clearance 0)
		)
		(min_thickness 0.25)
		(keepout
			(tracks not_allowed)
			(vias allowed)
			(pads allowed)
			(copperpour not_allowed)
			(footprints allowed)
		)
		(placement
			(enabled no)
			(sheetname "")
		)
		(fill
			(thermal_gap 0.5)
			(thermal_bridge_width 0.5)
			(island_removal_mode 0)
		)
		(polygon
			(pts
				(xy 87.220044 -0.120142) (xy 87.778844 -0.120142) (xy 87.778844 -1.923542) (xy 87.220044 -1.923542)
			)
		)
	)
	(zone
		(layer "In12.Cu")
		(hatch none 0.5)
		(connect_pads
			(clearance 0)
		)
		(min_thickness 0.25)
		(keepout
			(tracks not_allowed)
			(vias allowed)
			(pads allowed)
			(copperpour not_allowed)
			(footprints allowed)
		)
		(placement
			(enabled no)
			(sheetname "")
		)
		(fill
			(thermal_gap 0.5)
			(thermal_bridge_width 0.5)
			(island_removal_mode 0)
		)
		(polygon
			(pts
				(xy 242.870482 -4.720082) (xy 243.429282 -4.720082) (xy 243.429282 -6.523482) (xy 242.870482 -6.523482)
			)
		)
	)
	(zone
		(net "AGND_PVPP_GHJ")
		(layer "In12.Cu")
		(hatch none 0.5)
		(connect_pads
			(clearance 0.5)
		)
		(min_thickness 0.25)
		(fill yes
			(thermal_gap 0.5)
			(thermal_bridge_width 0.5)
			(island_removal_mode 0)
		)
		(polygon
			(pts
				(xy 175.238156 -6.477) (xy 174.857156 -6.858) (xy 173.079156 -6.858) (xy 172.212 -7.725156) (xy 172.212 -8.995156)
				(xy 171.069 -10.138156) (xy 171.069 -11.959844) (xy 171.428156 -12.319) (xy 173.333156 -12.319)
				(xy 174.095156 -13.081) (xy 174.646844 -13.081) (xy 175.006 -12.721844) (xy 175.006 -11.070844)
				(xy 175.408844 -10.668) (xy 178.075844 -10.668) (xy 178.181 -10.562844) (xy 178.181 -9.800844) (xy 178.435 -9.546844)
				(xy 178.435 -8.360156) (xy 178.181 -8.106156) (xy 178.181 -6.709156) (xy 177.948844 -6.477)
			)
		)
	)
	(zone
		(layer "In12.Cu")
		(hatch none 0.5)
		(connect_pads
			(clearance 0)
		)
		(min_thickness 0.25)
		(keepout
			(tracks not_allowed)
			(vias allowed)
			(pads allowed)
			(copperpour not_allowed)
			(footprints allowed)
		)
		(placement
			(enabled no)
			(sheetname "")
		)
		(fill
			(thermal_gap 0.5)
			(thermal_bridge_width 0.5)
			(island_removal_mode 0)
		)
		(polygon
			(pts
				(xy 287.92043 -146.576542) (xy 288.47923 -146.576542) (xy 288.47923 -148.379942) (xy 287.92043 -148.379942)
			)
		)
	)
	(zone
		(layer "In12.Cu")
		(hatch none 0.5)
		(connect_pads
			(clearance 0)
		)
		(min_thickness 0.25)
		(keepout
			(tracks not_allowed)
			(vias allowed)
			(pads allowed)
			(copperpour not_allowed)
			(footprints allowed)
		)
		(placement
			(enabled no)
			(sheetname "")
		)
		(fill
			(thermal_gap 0.5)
			(thermal_bridge_width 0.5)
			(island_removal_mode 0)
		)
		(polygon
			(pts
				(xy 296.42054 -14.321282) (xy 296.97934 -14.321282) (xy 296.97934 -16.124682) (xy 296.42054 -16.124682)
			)
		)
	)
	(zone
		(layer "In12.Cu")
		(hatch none 0.5)
		(connect_pads
			(clearance 0)
		)
		(min_thickness 0.25)
		(keepout
			(tracks not_allowed)
			(vias allowed)
			(pads allowed)
			(copperpour not_allowed)
			(footprints allowed)
		)
		(placement
			(enabled no)
			(sheetname "")
		)
		(fill
			(thermal_gap 0.5)
			(thermal_bridge_width 0.5)
			(island_removal_mode 0)
		)
		(polygon
			(pts
				(xy 236.070394 -0.120142) (xy 236.629194 -0.120142) (xy 236.629194 -1.923542) (xy 236.070394 -1.923542)
			)
		)
	)
	(zone
		(layer "In12.Cu")
		(hatch none 0.5)
		(connect_pads
			(clearance 0)
		)
		(min_thickness 0.25)
		(keepout
			(tracks not_allowed)
			(vias allowed)
			(pads allowed)
			(copperpour not_allowed)
			(footprints allowed)
		)
		(placement
			(enabled no)
			(sheetname "")
		)
		(fill
			(thermal_gap 0.5)
			(thermal_bridge_width 0.5)
			(island_removal_mode 0)
		)
		(polygon
			(pts
				(xy 52.369974 -136.975342) (xy 52.928774 -136.975342) (xy 52.928774 -138.778742) (xy 52.369974 -138.778742)
			)
		)
	)
	(zone
		(layer "In12.Cu")
		(hatch none 0.5)
		(connect_pads
			(clearance 0)
		)
		(min_thickness 0.25)
		(keepout
			(tracks not_allowed)
			(vias allowed)
			(pads allowed)
			(copperpour not_allowed)
			(footprints allowed)
		)
		(placement
			(enabled no)
			(sheetname "")
		)
		(fill
			(thermal_gap 0.5)
			(thermal_bridge_width 0.5)
			(island_removal_mode 0)
		)
		(polygon
			(pts
				(xy 200.37044 -141.575282) (xy 200.92924 -141.575282) (xy 200.92924 -143.378682) (xy 200.37044 -143.378682)
			)
		)
	)
	(zone
		(layer "In12.Cu")
		(hatch none 0.5)
		(connect_pads
			(clearance 0)
		)
		(min_thickness 0.25)
		(keepout
			(tracks not_allowed)
			(vias allowed)
			(pads allowed)
			(copperpour not_allowed)
			(footprints allowed)
		)
		(placement
			(enabled no)
			(sheetname "")
		)
		(fill
			(thermal_gap 0.5)
			(thermal_bridge_width 0.5)
			(island_removal_mode 0)
		)
		(polygon
			(pts
				(xy 312.570368 -127.374142) (xy 313.129168 -127.374142) (xy 313.129168 -129.177542) (xy 312.570368 -129.177542)
			)
		)
	)
	(zone
		(layer "In12.Cu")
		(hatch none 0.5)
		(connect_pads
			(clearance 0)
		)
		(min_thickness 0.25)
		(keepout
			(tracks not_allowed)
			(vias allowed)
			(pads allowed)
			(copperpour not_allowed)
			(footprints allowed)
		)
		(placement
			(enabled no)
			(sheetname "")
		)
		(fill
			(thermal_gap 0.5)
			(thermal_bridge_width 0.5)
			(island_removal_mode 0)
		)
		(polygon
			(pts
				(xy 209.720434 -19.322542) (xy 210.279234 -19.322542) (xy 210.279234 -21.125942) (xy 209.720434 -21.125942)
			)
		)
	)
	(zone
		(layer "In12.Cu")
		(hatch none 0.5)
		(connect_pads
			(clearance 0)
		)
		(min_thickness 0.25)
		(keepout
			(tracks not_allowed)
			(vias allowed)
			(pads allowed)
			(copperpour not_allowed)
			(footprints allowed)
		)
		(placement
			(enabled no)
			(sheetname "")
		)
		(fill
			(thermal_gap 0.5)
			(thermal_bridge_width 0.5)
			(island_removal_mode 0)
		)
		(polygon
			(pts
				(xy 241.170714 -23.922482) (xy 241.729514 -23.922482) (xy 241.729514 -25.725882) (xy 241.170714 -25.725882)
			)
		)
	)
	(zone
		(layer "In12.Cu")
		(hatch none 0.5)
		(connect_pads
			(clearance 0)
		)
		(min_thickness 0.25)
		(keepout
			(tracks not_allowed)
			(vias allowed)
			(pads allowed)
			(copperpour not_allowed)
			(footprints allowed)
		)
		(placement
			(enabled no)
			(sheetname "")
		)
		(fill
			(thermal_gap 0.5)
			(thermal_bridge_width 0.5)
			(island_removal_mode 0)
		)
		(polygon
			(pts
				(xy 149.269958 -146.576542) (xy 149.828758 -146.576542) (xy 149.828758 -148.379942) (xy 149.269958 -148.379942)
			)
		)
	)
	(zone
		(layer "In12.Cu")
		(hatch none 0.5)
		(connect_pads
			(clearance 0)
		)
		(min_thickness 0.25)
		(keepout
			(tracks not_allowed)
			(vias allowed)
			(pads allowed)
			(copperpour not_allowed)
			(footprints allowed)
		)
		(placement
			(enabled no)
			(sheetname "")
		)
		(fill
			(thermal_gap 0.5)
			(thermal_bridge_width 0.5)
			(island_removal_mode 0)
		)
		(polygon
			(pts
				(xy 301.520352 -14.321282) (xy 302.079152 -14.321282) (xy 302.079152 -16.124682) (xy 301.520352 -16.124682)
			)
		)
	)
	(zone
		(layer "In12.Cu")
		(hatch none 0.5)
		(connect_pads
			(clearance 0)
		)
		(min_thickness 0.25)
		(keepout
			(tracks not_allowed)
			(vias allowed)
			(pads allowed)
			(copperpour not_allowed)
			(footprints allowed)
		)
		(placement
			(enabled no)
			(sheetname "")
		)
		(fill
			(thermal_gap 0.5)
			(thermal_bridge_width 0.5)
			(island_removal_mode 0)
		)
		(polygon
			(pts
				(xy 69.36994 -127.374142) (xy 69.92874 -127.374142) (xy 69.92874 -129.177542) (xy 69.36994 -129.177542)
			)
		)
	)
	(zone
		(layer "In12.Cu")
		(hatch none 0.5)
		(connect_pads
			(clearance 0)
		)
		(min_thickness 0.25)
		(keepout
			(tracks not_allowed)
			(vias allowed)
			(pads allowed)
			(copperpour not_allowed)
			(footprints allowed)
		)
		(placement
			(enabled no)
			(sheetname "")
		)
		(fill
			(thermal_gap 0.5)
			(thermal_bridge_width 0.5)
			(island_removal_mode 0)
		)
		(polygon
			(pts
				(xy 91.469972 -131.974082) (xy 92.028772 -131.974082) (xy 92.028772 -133.777482) (xy 91.469972 -133.777482)
			)
		)
	)
	(zone
		(layer "In12.Cu")
		(hatch none 0.5)
		(connect_pads
			(clearance 0)
		)
		(min_thickness 0.25)
		(keepout
			(tracks not_allowed)
			(vias allowed)
			(pads allowed)
			(copperpour not_allowed)
			(footprints allowed)
		)
		(placement
			(enabled no)
			(sheetname "")
		)
		(fill
			(thermal_gap 0.5)
			(thermal_bridge_width 0.5)
			(island_removal_mode 0)
		)
		(polygon
			(pts
				(xy 146.720052 -0.120142) (xy 147.278852 -0.120142) (xy 147.278852 -1.923542) (xy 146.720052 -1.923542)
			)
		)
	)
	(zone
		(layer "In12.Cu")
		(hatch none 0.5)
		(connect_pads
			(clearance 0)
		)
		(min_thickness 0.25)
		(keepout
			(tracks not_allowed)
			(vias allowed)
			(pads allowed)
			(copperpour not_allowed)
			(footprints allowed)
		)
		(placement
			(enabled no)
			(sheetname "")
		)
		(fill
			(thermal_gap 0.5)
			(thermal_bridge_width 0.5)
			(island_removal_mode 0)
		)
		(polygon
			(pts
				(xy 139.919964 -9.721342) (xy 140.478764 -9.721342) (xy 140.478764 -11.524742) (xy 139.919964 -11.524742)
			)
		)
	)
	(zone
		(layer "In12.Cu")
		(hatch none 0.5)
		(connect_pads
			(clearance 0)
		)
		(min_thickness 0.25)
		(keepout
			(tracks not_allowed)
			(vias allowed)
			(pads allowed)
			(copperpour not_allowed)
			(footprints allowed)
		)
		(placement
			(enabled no)
			(sheetname "")
		)
		(fill
			(thermal_gap 0.5)
			(thermal_bridge_width 0.5)
			(island_removal_mode 0)
		)
		(polygon
			(pts
				(xy 355.432614 -125.786642) (xy 353.146614 -125.786642) (xy 353.146614 -125.278642) (xy 355.432614 -125.278642)
			)
		)
	)
	(zone
		(layer "In12.Cu")
		(hatch none 0.5)
		(connect_pads
			(clearance 0)
		)
		(min_thickness 0.25)
		(keepout
			(tracks not_allowed)
			(vias allowed)
			(pads allowed)
			(copperpour not_allowed)
			(footprints allowed)
		)
		(placement
			(enabled no)
			(sheetname "")
		)
		(fill
			(thermal_gap 0.5)
			(thermal_bridge_width 0.5)
			(island_removal_mode 0)
		)
		(polygon
			(pts
				(xy 420.5732 -151.384) (xy 420.5732 -152.146) (xy 421.5638 -152.146) (xy 421.5638 -151.384)
			)
		)
	)
	(zone
		(layer "In12.Cu")
		(hatch none 0.5)
		(connect_pads
			(clearance 0)
		)
		(min_thickness 0.25)
		(keepout
			(tracks not_allowed)
			(vias allowed)
			(pads allowed)
			(copperpour not_allowed)
			(footprints allowed)
		)
		(placement
			(enabled no)
			(sheetname "")
		)
		(fill
			(thermal_gap 0.5)
			(thermal_bridge_width 0.5)
			(island_removal_mode 0)
		)
		(polygon
			(pts
				(xy 57.47004 -151.176482) (xy 58.02884 -151.176482) (xy 58.02884 -152.979882) (xy 57.47004 -152.979882)
			)
		)
	)
	(zone
		(layer "In12.Cu")
		(hatch none 0.5)
		(connect_pads
			(clearance 0)
		)
		(min_thickness 0.25)
		(keepout
			(tracks not_allowed)
			(vias allowed)
			(pads allowed)
			(copperpour not_allowed)
			(footprints allowed)
		)
		(placement
			(enabled no)
			(sheetname "")
		)
		(fill
			(thermal_gap 0.5)
			(thermal_bridge_width 0.5)
			(island_removal_mode 0)
		)
		(polygon
			(pts
				(xy 50.669952 -0.120142) (xy 51.228752 -0.120142) (xy 51.228752 -1.923542) (xy 50.669952 -1.923542)
			)
		)
	)
	(zone
		(layer "In12.Cu")
		(hatch none 0.5)
		(connect_pads
			(clearance 0)
		)
		(min_thickness 0.25)
		(keepout
			(tracks not_allowed)
			(vias allowed)
			(pads allowed)
			(copperpour not_allowed)
			(footprints allowed)
		)
		(placement
			(enabled no)
			(sheetname "")
		)
		(fill
			(thermal_gap 0.5)
			(thermal_bridge_width 0.5)
			(island_removal_mode 0)
		)
		(polygon
			(pts
				(xy 60.019946 -19.322542) (xy 60.578746 -19.322542) (xy 60.578746 -21.125942) (xy 60.019946 -21.125942)
			)
		)
	)
	(zone
		(layer "In12.Cu")
		(hatch none 0.5)
		(connect_pads
			(clearance 0)
		)
		(min_thickness 0.25)
		(keepout
			(tracks not_allowed)
			(vias allowed)
			(pads allowed)
			(copperpour not_allowed)
			(footprints allowed)
		)
		(placement
			(enabled no)
			(sheetname "")
		)
		(fill
			(thermal_gap 0.5)
			(thermal_bridge_width 0.5)
			(island_removal_mode 0)
		)
		(polygon
			(pts
				(xy 92.32011 -0.120142) (xy 92.87891 -0.120142) (xy 92.87891 -1.923542) (xy 92.32011 -1.923542)
			)
		)
	)
	(zone
		(layer "In12.Cu")
		(hatch none 0.5)
		(connect_pads
			(clearance 0)
		)
		(min_thickness 0.25)
		(keepout
			(tracks not_allowed)
			(vias allowed)
			(pads allowed)
			(copperpour not_allowed)
			(footprints allowed)
		)
		(placement
			(enabled no)
			(sheetname "")
		)
		(fill
			(thermal_gap 0.5)
			(thermal_bridge_width 0.5)
			(island_removal_mode 0)
		)
		(polygon
			(pts
				(xy 117.819932 -141.575282) (xy 118.378732 -141.575282) (xy 118.378732 -143.378682) (xy 117.819932 -143.378682)
			)
		)
	)
	(zone
		(layer "In12.Cu")
		(hatch none 0.5)
		(connect_pads
			(clearance 0)
		)
		(min_thickness 0.25)
		(keepout
			(tracks not_allowed)
			(vias allowed)
			(pads allowed)
			(copperpour not_allowed)
			(footprints allowed)
		)
		(placement
			(enabled no)
			(sheetname "")
		)
		(fill
			(thermal_gap 0.5)
			(thermal_bridge_width 0.5)
			(island_removal_mode 0)
		)
		(polygon
			(pts
				(xy 196.970396 -146.576542) (xy 197.529196 -146.576542) (xy 197.529196 -148.379942) (xy 196.970396 -148.379942)
			)
		)
	)
	(zone
		(layer "In12.Cu")
		(hatch none 0.5)
		(connect_pads
			(clearance 0)
		)
		(min_thickness 0.25)
		(keepout
			(tracks not_allowed)
			(vias allowed)
			(pads allowed)
			(copperpour not_allowed)
			(footprints allowed)
		)
		(placement
			(enabled no)
			(sheetname "")
		)
		(fill
			(thermal_gap 0.5)
			(thermal_bridge_width 0.5)
			(island_removal_mode 0)
		)
		(polygon
			(pts
				(xy 118.67007 -14.321282) (xy 119.22887 -14.321282) (xy 119.22887 -16.124682) (xy 118.67007 -16.124682)
			)
		)
	)
	(zone
		(layer "In12.Cu")
		(hatch none 0.5)
		(connect_pads
			(clearance 0)
		)
		(min_thickness 0.25)
		(keepout
			(tracks not_allowed)
			(vias allowed)
			(pads allowed)
			(copperpour not_allowed)
			(footprints allowed)
		)
		(placement
			(enabled no)
			(sheetname "")
		)
		(fill
			(thermal_gap 0.5)
			(thermal_bridge_width 0.5)
			(island_removal_mode 0)
		)
		(polygon
			(pts
				(xy 275.170392 -136.975342) (xy 275.729192 -136.975342) (xy 275.729192 -138.778742) (xy 275.170392 -138.778742)
			)
		)
	)
	(zone
		(layer "In12.Cu")
		(hatch none 0.5)
		(connect_pads
			(clearance 0)
		)
		(min_thickness 0.25)
		(keepout
			(tracks not_allowed)
			(vias allowed)
			(pads allowed)
			(copperpour not_allowed)
			(footprints allowed)
		)
		(placement
			(enabled no)
			(sheetname "")
		)
		(fill
			(thermal_gap 0.5)
			(thermal_bridge_width 0.5)
			(island_removal_mode 0)
		)
		(polygon
			(pts
				(xy 452.247 -115.34902) (xy 452.755 -115.34902) (xy 452.755 -116.74602) (xy 452.247 -116.74602)
			)
		)
	)
	(zone
		(layer "In12.Cu")
		(hatch none 0.5)
		(connect_pads
			(clearance 0)
		)
		(min_thickness 0.25)
		(keepout
			(tracks not_allowed)
			(vias allowed)
			(pads allowed)
			(copperpour not_allowed)
			(footprints allowed)
		)
		(placement
			(enabled no)
			(sheetname "")
		)
		(fill
			(thermal_gap 0.5)
			(thermal_bridge_width 0.5)
			(island_removal_mode 0)
		)
		(polygon
			(pts
				(xy 32.820102 -131.974082) (xy 33.378902 -131.974082) (xy 33.378902 -133.777482) (xy 32.820102 -133.777482)
			)
		)
	)
	(zone
		(layer "In12.Cu")
		(hatch none 0.5)
		(connect_pads
			(clearance 0)
		)
		(min_thickness 0.25)
		(keepout
			(tracks not_allowed)
			(vias allowed)
			(pads allowed)
			(copperpour not_allowed)
			(footprints allowed)
		)
		(placement
			(enabled no)
			(sheetname "")
		)
		(fill
			(thermal_gap 0.5)
			(thermal_bridge_width 0.5)
			(island_removal_mode 0)
		)
		(polygon
			(pts
				(xy 116.970048 -9.721342) (xy 117.528848 -9.721342) (xy 117.528848 -11.524742) (xy 116.970048 -11.524742)
			)
		)
	)
	(zone
		(layer "In12.Cu")
		(hatch none 0.5)
		(connect_pads
			(clearance 0)
		)
		(min_thickness 0.25)
		(keepout
			(tracks not_allowed)
			(vias allowed)
			(pads allowed)
			(copperpour not_allowed)
			(footprints allowed)
		)
		(placement
			(enabled no)
			(sheetname "")
		)
		(fill
			(thermal_gap 0.5)
			(thermal_bridge_width 0.5)
			(island_removal_mode 0)
		)
		(polygon
			(pts
				(xy 385.09194 -29.301694) (xy 386.48894 -29.301694) (xy 386.48894 -29.809694) (xy 385.09194 -29.809694)
			)
		)
	)
	(zone
		(layer "In12.Cu")
		(hatch none 0.5)
		(connect_pads
			(clearance 0)
		)
		(min_thickness 0.25)
		(keepout
			(tracks not_allowed)
			(vias allowed)
			(pads allowed)
			(copperpour not_allowed)
			(footprints allowed)
		)
		(placement
			(enabled no)
			(sheetname "")
		)
		(fill
			(thermal_gap 0.5)
			(thermal_bridge_width 0.5)
			(island_removal_mode 0)
		)
		(polygon
			(pts
				(xy 276.02053 -14.321282) (xy 276.57933 -14.321282) (xy 276.57933 -16.124682) (xy 276.02053 -16.124682)
			)
		)
	)
	(zone
		(layer "In12.Cu")
		(hatch none 0.5)
		(connect_pads
			(clearance 0)
		)
		(min_thickness 0.25)
		(keepout
			(tracks not_allowed)
			(vias allowed)
			(pads allowed)
			(copperpour not_allowed)
			(footprints allowed)
		)
		(placement
			(enabled no)
			(sheetname "")
		)
		(fill
			(thermal_gap 0.5)
			(thermal_bridge_width 0.5)
			(island_removal_mode 0)
		)
		(polygon
			(pts
				(xy 293.87038 -136.975342) (xy 294.42918 -136.975342) (xy 294.42918 -138.778742) (xy 293.87038 -138.778742)
			)
		)
	)
	(zone
		(layer "In12.Cu")
		(hatch none 0.5)
		(connect_pads
			(clearance 0)
		)
		(min_thickness 0.25)
		(keepout
			(tracks not_allowed)
			(vias allowed)
			(pads allowed)
			(copperpour not_allowed)
			(footprints allowed)
		)
		(placement
			(enabled no)
			(sheetname "")
		)
		(fill
			(thermal_gap 0.5)
			(thermal_bridge_width 0.5)
			(island_removal_mode 0)
		)
		(polygon
			(pts
				(xy 77.87005 -141.575282) (xy 78.42885 -141.575282) (xy 78.42885 -143.378682) (xy 77.87005 -143.378682)
			)
		)
	)
	(zone
		(layer "In12.Cu")
		(hatch none 0.5)
		(connect_pads
			(clearance 0)
		)
		(min_thickness 0.25)
		(keepout
			(tracks not_allowed)
			(vias allowed)
			(pads allowed)
			(copperpour not_allowed)
			(footprints allowed)
		)
		(placement
			(enabled no)
			(sheetname "")
		)
		(fill
			(thermal_gap 0.5)
			(thermal_bridge_width 0.5)
			(island_removal_mode 0)
		)
		(polygon
			(pts
				(xy 215.670384 -136.975342) (xy 216.229184 -136.975342) (xy 216.229184 -138.778742) (xy 215.670384 -138.778742)
			)
		)
	)
	(zone
		(layer "In12.Cu")
		(hatch none 0.5)
		(connect_pads
			(clearance 0)
		)
		(min_thickness 0.25)
		(keepout
			(tracks not_allowed)
			(vias allowed)
			(pads allowed)
			(copperpour not_allowed)
			(footprints allowed)
		)
		(placement
			(enabled no)
			(sheetname "")
		)
		(fill
			(thermal_gap 0.5)
			(thermal_bridge_width 0.5)
			(island_removal_mode 0)
		)
		(polygon
			(pts
				(xy 123.769882 -141.575282) (xy 124.328682 -141.575282) (xy 124.328682 -143.378682) (xy 123.769882 -143.378682)
			)
		)
	)
	(zone
		(layer "In12.Cu")
		(hatch none 0.5)
		(connect_pads
			(clearance 0)
		)
		(min_thickness 0.25)
		(keepout
			(tracks not_allowed)
			(vias allowed)
			(pads allowed)
			(copperpour not_allowed)
			(footprints allowed)
		)
		(placement
			(enabled no)
			(sheetname "")
		)
		(fill
			(thermal_gap 0.5)
			(thermal_bridge_width 0.5)
			(island_removal_mode 0)
		)
		(polygon
			(pts
				(xy 297.270424 -136.975342) (xy 297.829224 -136.975342) (xy 297.829224 -138.778742) (xy 297.270424 -138.778742)
			)
		)
	)
	(zone
		(layer "In12.Cu")
		(hatch none 0.5)
		(connect_pads
			(clearance 0)
		)
		(min_thickness 0.25)
		(keepout
			(tracks not_allowed)
			(vias allowed)
			(pads allowed)
			(copperpour not_allowed)
			(footprints allowed)
		)
		(placement
			(enabled no)
			(sheetname "")
		)
		(fill
			(thermal_gap 0.5)
			(thermal_bridge_width 0.5)
			(island_removal_mode 0)
		)
		(polygon
			(pts
				(xy 122.919998 -19.322542) (xy 123.478798 -19.322542) (xy 123.478798 -21.125942) (xy 122.919998 -21.125942)
			)
		)
	)
	(zone
		(layer "In12.Cu")
		(hatch none 0.5)
		(connect_pads
			(clearance 0)
		)
		(min_thickness 0.25)
		(keepout
			(tracks not_allowed)
			(vias allowed)
			(pads allowed)
			(copperpour not_allowed)
			(footprints allowed)
		)
		(placement
			(enabled no)
			(sheetname "")
		)
		(fill
			(thermal_gap 0.5)
			(thermal_bridge_width 0.5)
			(island_removal_mode 0)
		)
		(polygon
			(pts
				(xy 105.070148 -146.576542) (xy 105.628948 -146.576542) (xy 105.628948 -148.379942) (xy 105.070148 -148.379942)
			)
		)
	)
	(zone
		(layer "In12.Cu")
		(hatch none 0.5)
		(connect_pads
			(clearance 0)
		)
		(min_thickness 0.25)
		(keepout
			(tracks not_allowed)
			(vias allowed)
			(pads allowed)
			(copperpour not_allowed)
			(footprints allowed)
		)
		(placement
			(enabled no)
			(sheetname "")
		)
		(fill
			(thermal_gap 0.5)
			(thermal_bridge_width 0.5)
			(island_removal_mode 0)
		)
		(polygon
			(pts
				(xy 60.019946 -136.975342) (xy 60.578746 -136.975342) (xy 60.578746 -138.778742) (xy 60.019946 -138.778742)
			)
		)
	)
	(zone
		(layer "In12.Cu")
		(hatch none 0.5)
		(connect_pads
			(clearance 0)
		)
		(min_thickness 0.25)
		(keepout
			(tracks not_allowed)
			(vias allowed)
			(pads allowed)
			(copperpour not_allowed)
			(footprints allowed)
		)
		(placement
			(enabled no)
			(sheetname "")
		)
		(fill
			(thermal_gap 0.5)
			(thermal_bridge_width 0.5)
			(island_removal_mode 0)
		)
		(polygon
			(pts
				(xy 213.970362 -136.975342) (xy 214.529162 -136.975342) (xy 214.529162 -138.778742) (xy 213.970362 -138.778742)
			)
		)
	)
	(zone
		(layer "In12.Cu")
		(hatch none 0.5)
		(connect_pads
			(clearance 0)
		)
		(min_thickness 0.25)
		(keepout
			(tracks not_allowed)
			(vias allowed)
			(pads allowed)
			(copperpour not_allowed)
			(footprints allowed)
		)
		(placement
			(enabled no)
			(sheetname "")
		)
		(fill
			(thermal_gap 0.5)
			(thermal_bridge_width 0.5)
			(island_removal_mode 0)
		)
		(polygon
			(pts
				(xy 270.07058 -0.120142) (xy 270.62938 -0.120142) (xy 270.62938 -1.923542) (xy 270.07058 -1.923542)
			)
		)
	)
	(zone
		(layer "In12.Cu")
		(hatch none 0.5)
		(connect_pads
			(clearance 0)
		)
		(min_thickness 0.25)
		(keepout
			(tracks not_allowed)
			(vias allowed)
			(pads allowed)
			(copperpour not_allowed)
			(footprints allowed)
		)
		(placement
			(enabled no)
			(sheetname "")
		)
		(fill
			(thermal_gap 0.5)
			(thermal_bridge_width 0.5)
			(island_removal_mode 0)
		)
		(polygon
			(pts
				(xy 145.869914 -23.922482) (xy 146.428714 -23.922482) (xy 146.428714 -25.725882) (xy 145.869914 -25.725882)
			)
		)
	)
	(zone
		(layer "In12.Cu")
		(hatch none 0.5)
		(connect_pads
			(clearance 0)
		)
		(min_thickness 0.25)
		(keepout
			(tracks not_allowed)
			(vias allowed)
			(pads allowed)
			(copperpour not_allowed)
			(footprints allowed)
		)
		(placement
			(enabled no)
			(sheetname "")
		)
		(fill
			(thermal_gap 0.5)
			(thermal_bridge_width 0.5)
			(island_removal_mode 0)
		)
		(polygon
			(pts
				(xy 313.420506 -141.575282) (xy 313.979306 -141.575282) (xy 313.979306 -143.378682) (xy 313.420506 -143.378682)
			)
		)
	)
	(zone
		(layer "In12.Cu")
		(hatch none 0.5)
		(connect_pads
			(clearance 0)
		)
		(min_thickness 0.25)
		(keepout
			(tracks not_allowed)
			(vias allowed)
			(pads allowed)
			(copperpour not_allowed)
			(footprints allowed)
		)
		(placement
			(enabled no)
			(sheetname "")
		)
		(fill
			(thermal_gap 0.5)
			(thermal_bridge_width 0.5)
			(island_removal_mode 0)
		)
		(polygon
			(pts
				(xy 82.119978 -9.721342) (xy 82.678778 -9.721342) (xy 82.678778 -11.524742) (xy 82.119978 -11.524742)
			)
		)
	)
	(zone
		(layer "In12.Cu")
		(hatch none 0.5)
		(connect_pads
			(clearance 0)
		)
		(min_thickness 0.25)
		(keepout
			(tracks not_allowed)
			(vias allowed)
			(pads allowed)
			(copperpour not_allowed)
			(footprints allowed)
		)
		(placement
			(enabled no)
			(sheetname "")
		)
		(fill
			(thermal_gap 0.5)
			(thermal_bridge_width 0.5)
			(island_removal_mode 0)
		)
		(polygon
			(pts
				(xy 235.22051 -131.974082) (xy 235.77931 -131.974082) (xy 235.77931 -133.777482) (xy 235.22051 -133.777482)
			)
		)
	)
	(zone
		(layer "In12.Cu")
		(hatch none 0.5)
		(connect_pads
			(clearance 0)
		)
		(min_thickness 0.25)
		(keepout
			(tracks not_allowed)
			(vias allowed)
			(pads allowed)
			(copperpour not_allowed)
			(footprints allowed)
		)
		(placement
			(enabled no)
			(sheetname "")
		)
		(fill
			(thermal_gap 0.5)
			(thermal_bridge_width 0.5)
			(island_removal_mode 0)
		)
		(polygon
			(pts
				(xy 71.9201 -23.922482) (xy 72.4789 -23.922482) (xy 72.4789 -25.725882) (xy 71.9201 -25.725882)
			)
		)
	)
	(zone
		(layer "In12.Cu")
		(hatch none 0.5)
		(connect_pads
			(clearance 0)
		)
		(min_thickness 0.25)
		(keepout
			(tracks not_allowed)
			(vias allowed)
			(pads allowed)
			(copperpour not_allowed)
			(footprints allowed)
		)
		(placement
			(enabled no)
			(sheetname "")
		)
		(fill
			(thermal_gap 0.5)
			(thermal_bridge_width 0.5)
			(island_removal_mode 0)
		)
		(polygon
			(pts
				(xy 294.720518 -131.974082) (xy 295.279318 -131.974082) (xy 295.279318 -133.777482) (xy 294.720518 -133.777482)
			)
		)
	)
	(zone
		(layer "In12.Cu")
		(hatch none 0.5)
		(connect_pads
			(clearance 0)
		)
		(min_thickness 0.25)
		(keepout
			(tracks not_allowed)
			(vias allowed)
			(pads allowed)
			(copperpour not_allowed)
			(footprints allowed)
		)
		(placement
			(enabled no)
			(sheetname "")
		)
		(fill
			(thermal_gap 0.5)
			(thermal_bridge_width 0.5)
			(island_removal_mode 0)
		)
		(polygon
			(pts
				(xy 215.670384 -19.322542) (xy 216.229184 -19.322542) (xy 216.229184 -21.125942) (xy 215.670384 -21.125942)
			)
		)
	)
	(zone
		(layer "In12.Cu")
		(hatch none 0.5)
		(connect_pads
			(clearance 0)
		)
		(min_thickness 0.25)
		(keepout
			(tracks not_allowed)
			(vias allowed)
			(pads allowed)
			(copperpour not_allowed)
			(footprints allowed)
		)
		(placement
			(enabled no)
			(sheetname "")
		)
		(fill
			(thermal_gap 0.5)
			(thermal_bridge_width 0.5)
			(island_removal_mode 0)
		)
		(polygon
			(pts
				(xy 195.270374 -136.975342) (xy 195.829174 -136.975342) (xy 195.829174 -138.778742) (xy 195.270374 -138.778742)
			)
		)
	)
	(zone
		(layer "In12.Cu")
		(hatch none 0.5)
		(connect_pads
			(clearance 0)
		)
		(min_thickness 0.25)
		(keepout
			(tracks not_allowed)
			(vias allowed)
			(pads allowed)
			(copperpour not_allowed)
			(footprints allowed)
		)
		(placement
			(enabled no)
			(sheetname "")
		)
		(fill
			(thermal_gap 0.5)
			(thermal_bridge_width 0.5)
			(island_removal_mode 0)
		)
		(polygon
			(pts
				(xy 116.11991 -131.974082) (xy 116.67871 -131.974082) (xy 116.67871 -133.777482) (xy 116.11991 -133.777482)
			)
		)
	)
	(zone
		(layer "In12.Cu")
		(hatch none 0.5)
		(connect_pads
			(clearance 0)
		)
		(min_thickness 0.25)
		(keepout
			(tracks not_allowed)
			(vias allowed)
			(pads allowed)
			(copperpour not_allowed)
			(footprints allowed)
		)
		(placement
			(enabled no)
			(sheetname "")
		)
		(fill
			(thermal_gap 0.5)
			(thermal_bridge_width 0.5)
			(island_removal_mode 0)
		)
		(polygon
			(pts
				(xy 232.67035 -9.721342) (xy 233.22915 -9.721342) (xy 233.22915 -11.524742) (xy 232.67035 -11.524742)
			)
		)
	)
	(zone
		(layer "In12.Cu")
		(hatch none 0.5)
		(connect_pads
			(clearance 0)
		)
		(min_thickness 0.25)
		(keepout
			(tracks not_allowed)
			(vias allowed)
			(pads allowed)
			(copperpour not_allowed)
			(footprints allowed)
		)
		(placement
			(enabled no)
			(sheetname "")
		)
		(fill
			(thermal_gap 0.5)
			(thermal_bridge_width 0.5)
			(island_removal_mode 0)
		)
		(polygon
			(pts
				(xy 264.970514 -127.374142) (xy 265.529314 -127.374142) (xy 265.529314 -129.177542) (xy 264.970514 -129.177542)
			)
		)
	)
	(zone
		(layer "In12.Cu")
		(hatch none 0.5)
		(connect_pads
			(clearance 0)
		)
		(min_thickness 0.25)
		(keepout
			(tracks not_allowed)
			(vias allowed)
			(pads allowed)
			(copperpour not_allowed)
			(footprints allowed)
		)
		(placement
			(enabled no)
			(sheetname "")
		)
		(fill
			(thermal_gap 0.5)
			(thermal_bridge_width 0.5)
			(island_removal_mode 0)
		)
		(polygon
			(pts
				(xy 313.420506 -23.922482) (xy 313.979306 -23.922482) (xy 313.979306 -25.725882) (xy 313.420506 -25.725882)
			)
		)
	)
	(zone
		(layer "In12.Cu")
		(hatch none 0.5)
		(connect_pads
			(clearance 0)
		)
		(min_thickness 0.25)
		(keepout
			(tracks not_allowed)
			(vias allowed)
			(pads allowed)
			(copperpour not_allowed)
			(footprints allowed)
		)
		(placement
			(enabled no)
			(sheetname "")
		)
		(fill
			(thermal_gap 0.5)
			(thermal_bridge_width 0.5)
			(island_removal_mode 0)
		)
		(polygon
			(pts
				(xy 56.620156 -127.374142) (xy 57.178956 -127.374142) (xy 57.178956 -129.177542) (xy 56.620156 -129.177542)
			)
		)
	)
	(zone
		(net "PVDDQ_KLM")
		(layer "In12.Cu")
		(hatch none 0.5)
		(connect_pads
			(clearance 0.5)
		)
		(min_thickness 0.25)
		(fill yes
			(thermal_gap 0.5)
			(thermal_bridge_width 0.5)
			(island_removal_mode 0)
		)
		(polygon
			(pts
				(xy 78.920594 -129.2479) (xy 78.7781 -129.390394) (xy 78.7781 -130.482594) (xy 77.8891 -131.371594)
				(xy 77.8891 -131.721606) (xy 78.107794 -131.9403) (xy 93.545406 -131.9403) (xy 93.6371 -131.848606)
				(xy 93.6371 -129.339594) (xy 93.545406 -129.2479)
			)
		)
	)
	(zone
		(layer "In12.Cu")
		(hatch none 0.5)
		(connect_pads
			(clearance 0)
		)
		(min_thickness 0.25)
		(keepout
			(tracks not_allowed)
			(vias allowed)
			(pads allowed)
			(copperpour not_allowed)
			(footprints allowed)
		)
		(placement
			(enabled no)
			(sheetname "")
		)
		(fill
			(thermal_gap 0.5)
			(thermal_bridge_width 0.5)
			(island_removal_mode 0)
		)
		(polygon
			(pts
				(xy 85.520022 -0.120142) (xy 86.078822 -0.120142) (xy 86.078822 -1.923542) (xy 85.520022 -1.923542)
			)
		)
	)
	(zone
		(layer "In12.Cu")
		(hatch none 0.5)
		(connect_pads
			(clearance 0)
		)
		(min_thickness 0.25)
		(keepout
			(tracks not_allowed)
			(vias allowed)
			(pads allowed)
			(copperpour not_allowed)
			(footprints allowed)
		)
		(placement
			(enabled no)
			(sheetname "")
		)
		(fill
			(thermal_gap 0.5)
			(thermal_bridge_width 0.5)
			(island_removal_mode 0)
		)
		(polygon
			(pts
				(xy 309.170324 -23.922482) (xy 309.729124 -23.922482) (xy 309.729124 -25.725882) (xy 309.170324 -25.725882)
			)
		)
	)
	(zone
		(layer "In12.Cu")
		(hatch none 0.5)
		(connect_pads
			(clearance 0)
		)
		(min_thickness 0.25)
		(keepout
			(tracks not_allowed)
			(vias allowed)
			(pads allowed)
			(copperpour not_allowed)
			(footprints allowed)
		)
		(placement
			(enabled no)
			(sheetname "")
		)
		(fill
			(thermal_gap 0.5)
			(thermal_bridge_width 0.5)
			(island_removal_mode 0)
		)
		(polygon
			(pts
				(xy 102.519988 -151.176482) (xy 103.078788 -151.176482) (xy 103.078788 -152.979882) (xy 102.519988 -152.979882)
			)
		)
	)
	(zone
		(layer "In12.Cu")
		(hatch none 0.5)
		(connect_pads
			(clearance 0)
		)
		(min_thickness 0.25)
		(keepout
			(tracks not_allowed)
			(vias allowed)
			(pads allowed)
			(copperpour not_allowed)
			(footprints allowed)
		)
		(placement
			(enabled no)
			(sheetname "")
		)
		(fill
			(thermal_gap 0.5)
			(thermal_bridge_width 0.5)
			(island_removal_mode 0)
		)
		(polygon
			(pts
				(xy 218.220544 -141.575282) (xy 218.779344 -141.575282) (xy 218.779344 -143.378682) (xy 218.220544 -143.378682)
			)
		)
	)
	(zone
		(layer "In12.Cu")
		(hatch none 0.5)
		(connect_pads
			(clearance 0)
		)
		(min_thickness 0.25)
		(keepout
			(tracks not_allowed)
			(vias allowed)
			(pads allowed)
			(copperpour not_allowed)
			(footprints allowed)
		)
		(placement
			(enabled no)
			(sheetname "")
		)
		(fill
			(thermal_gap 0.5)
			(thermal_bridge_width 0.5)
			(island_removal_mode 0)
		)
		(polygon
			(pts
				(xy 293.87038 -9.721342) (xy 294.42918 -9.721342) (xy 294.42918 -11.524742) (xy 293.87038 -11.524742)
			)
		)
	)
	(zone
		(layer "In12.Cu")
		(hatch none 0.5)
		(connect_pads
			(clearance 0)
		)
		(min_thickness 0.25)
		(keepout
			(tracks not_allowed)
			(vias allowed)
			(pads allowed)
			(copperpour not_allowed)
			(footprints allowed)
		)
		(placement
			(enabled no)
			(sheetname "")
		)
		(fill
			(thermal_gap 0.5)
			(thermal_bridge_width 0.5)
			(island_removal_mode 0)
		)
		(polygon
			(pts
				(xy 82.119978 -19.322542) (xy 82.678778 -19.322542) (xy 82.678778 -21.125942) (xy 82.119978 -21.125942)
			)
		)
	)
	(zone
		(layer "In12.Cu")
		(hatch none 0.5)
		(connect_pads
			(clearance 0)
		)
		(min_thickness 0.25)
		(keepout
			(tracks not_allowed)
			(vias allowed)
			(pads allowed)
			(copperpour not_allowed)
			(footprints allowed)
		)
		(placement
			(enabled no)
			(sheetname "")
		)
		(fill
			(thermal_gap 0.5)
			(thermal_bridge_width 0.5)
			(island_removal_mode 0)
		)
		(polygon
			(pts
				(xy 229.27056 -19.322542) (xy 229.82936 -19.322542) (xy 229.82936 -21.125942) (xy 229.27056 -21.125942)
			)
		)
	)
	(zone
		(layer "In12.Cu")
		(hatch none 0.5)
		(connect_pads
			(clearance 0)
		)
		(min_thickness 0.25)
		(keepout
			(tracks not_allowed)
			(vias allowed)
			(pads allowed)
			(copperpour not_allowed)
			(footprints allowed)
		)
		(placement
			(enabled no)
			(sheetname "")
		)
		(fill
			(thermal_gap 0.5)
			(thermal_bridge_width 0.5)
			(island_removal_mode 0)
		)
		(polygon
			(pts
				(xy 222.470472 -141.575282) (xy 223.029272 -141.575282) (xy 223.029272 -143.378682) (xy 222.470472 -143.378682)
			)
		)
	)
	(zone
		(layer "In12.Cu")
		(hatch none 0.5)
		(connect_pads
			(clearance 0)
		)
		(min_thickness 0.25)
		(keepout
			(tracks not_allowed)
			(vias allowed)
			(pads allowed)
			(copperpour not_allowed)
			(footprints allowed)
		)
		(placement
			(enabled no)
			(sheetname "")
		)
		(fill
			(thermal_gap 0.5)
			(thermal_bridge_width 0.5)
			(island_removal_mode 0)
		)
		(polygon
			(pts
				(xy 51.52009 -151.176482) (xy 52.07889 -151.176482) (xy 52.07889 -152.979882) (xy 51.52009 -152.979882)
			)
		)
	)
	(zone
		(layer "In12.Cu")
		(hatch none 0.5)
		(connect_pads
			(clearance 0)
		)
		(min_thickness 0.25)
		(keepout
			(tracks not_allowed)
			(vias allowed)
			(pads allowed)
			(copperpour not_allowed)
			(footprints allowed)
		)
		(placement
			(enabled no)
			(sheetname "")
		)
		(fill
			(thermal_gap 0.5)
			(thermal_bridge_width 0.5)
			(island_removal_mode 0)
		)
		(polygon
			(pts
				(xy 209.720434 -146.576542) (xy 210.279234 -146.576542) (xy 210.279234 -148.379942) (xy 209.720434 -148.379942)
			)
		)
	)
	(zone
		(layer "In12.Cu")
		(hatch none 0.5)
		(connect_pads
			(clearance 0)
		)
		(min_thickness 0.25)
		(keepout
			(tracks not_allowed)
			(vias allowed)
			(pads allowed)
			(copperpour not_allowed)
			(footprints allowed)
		)
		(placement
			(enabled no)
			(sheetname "")
		)
		(fill
			(thermal_gap 0.5)
			(thermal_bridge_width 0.5)
			(island_removal_mode 0)
		)
		(polygon
			(pts
				(xy 137.370058 -136.975342) (xy 137.928858 -136.975342) (xy 137.928858 -138.778742) (xy 137.370058 -138.778742)
			)
		)
	)
	(zone
		(layer "In12.Cu")
		(hatch none 0.5)
		(connect_pads
			(clearance 0)
		)
		(min_thickness 0.25)
		(keepout
			(tracks not_allowed)
			(vias allowed)
			(pads allowed)
			(copperpour not_allowed)
			(footprints allowed)
		)
		(placement
			(enabled no)
			(sheetname "")
		)
		(fill
			(thermal_gap 0.5)
			(thermal_bridge_width 0.5)
			(island_removal_mode 0)
		)
		(polygon
			(pts
				(xy 217.370406 -136.975342) (xy 217.929206 -136.975342) (xy 217.929206 -138.778742) (xy 217.370406 -138.778742)
			)
		)
	)
	(zone
		(layer "In12.Cu")
		(hatch none 0.5)
		(connect_pads
			(clearance 0)
		)
		(min_thickness 0.25)
		(keepout
			(tracks not_allowed)
			(vias allowed)
			(pads allowed)
			(copperpour not_allowed)
			(footprints allowed)
		)
		(placement
			(enabled no)
			(sheetname "")
		)
		(fill
			(thermal_gap 0.5)
			(thermal_bridge_width 0.5)
			(island_removal_mode 0)
		)
		(polygon
			(pts
				(xy 118.67007 -4.720082) (xy 119.22887 -4.720082) (xy 119.22887 -6.523482) (xy 118.67007 -6.523482)
			)
		)
	)
	(zone
		(layer "In12.Cu")
		(hatch none 0.5)
		(connect_pads
			(clearance 0)
		)
		(min_thickness 0.25)
		(keepout
			(tracks not_allowed)
			(vias allowed)
			(pads allowed)
			(copperpour not_allowed)
			(footprints allowed)
		)
		(placement
			(enabled no)
			(sheetname "")
		)
		(fill
			(thermal_gap 0.5)
			(thermal_bridge_width 0.5)
			(island_removal_mode 0)
		)
		(polygon
			(pts
				(xy 238.620554 -146.576542) (xy 239.179354 -146.576542) (xy 239.179354 -148.379942) (xy 238.620554 -148.379942)
			)
		)
	)
	(zone
		(layer "In12.Cu")
		(hatch none 0.5)
		(connect_pads
			(clearance 0)
		)
		(min_thickness 0.25)
		(keepout
			(tracks not_allowed)
			(vias allowed)
			(pads allowed)
			(copperpour not_allowed)
			(footprints allowed)
		)
		(placement
			(enabled no)
			(sheetname "")
		)
		(fill
			(thermal_gap 0.5)
			(thermal_bridge_width 0.5)
			(island_removal_mode 0)
		)
		(polygon
			(pts
				(xy 198.670418 -0.120142) (xy 199.229218 -0.120142) (xy 199.229218 -1.923542) (xy 198.670418 -1.923542)
			)
		)
	)
	(zone
		(layer "In12.Cu")
		(hatch none 0.5)
		(connect_pads
			(clearance 0)
		)
		(min_thickness 0.25)
		(keepout
			(tracks not_allowed)
			(vias allowed)
			(pads allowed)
			(copperpour not_allowed)
			(footprints allowed)
		)
		(placement
			(enabled no)
			(sheetname "")
		)
		(fill
			(thermal_gap 0.5)
			(thermal_bridge_width 0.5)
			(island_removal_mode 0)
		)
		(polygon
			(pts
				(xy 46.420024 -151.176482) (xy 46.978824 -151.176482) (xy 46.978824 -152.979882) (xy 46.420024 -152.979882)
			)
		)
	)
	(zone
		(layer "In12.Cu")
		(hatch none 0.5)
		(connect_pads
			(clearance 0)
		)
		(min_thickness 0.25)
		(keepout
			(tracks not_allowed)
			(vias allowed)
			(pads allowed)
			(copperpour not_allowed)
			(footprints allowed)
		)
		(placement
			(enabled no)
			(sheetname "")
		)
		(fill
			(thermal_gap 0.5)
			(thermal_bridge_width 0.5)
			(island_removal_mode 0)
		)
		(polygon
			(pts
				(xy 298.970446 -0.120142) (xy 299.529246 -0.120142) (xy 299.529246 -1.923542) (xy 298.970446 -1.923542)
			)
		)
	)
	(zone
		(layer "In12.Cu")
		(hatch none 0.5)
		(connect_pads
			(clearance 0)
		)
		(min_thickness 0.25)
		(keepout
			(tracks not_allowed)
			(vias allowed)
			(pads allowed)
			(copperpour not_allowed)
			(footprints allowed)
		)
		(placement
			(enabled no)
			(sheetname "")
		)
		(fill
			(thermal_gap 0.5)
			(thermal_bridge_width 0.5)
			(island_removal_mode 0)
		)
		(polygon
			(pts
				(xy 130.56997 -127.374142) (xy 131.12877 -127.374142) (xy 131.12877 -129.177542) (xy 130.56997 -129.177542)
			)
		)
	)
	(zone
		(layer "In12.Cu")
		(hatch none 0.5)
		(connect_pads
			(clearance 0)
		)
		(min_thickness 0.25)
		(keepout
			(tracks not_allowed)
			(vias allowed)
			(pads allowed)
			(copperpour not_allowed)
			(footprints allowed)
		)
		(placement
			(enabled no)
			(sheetname "")
		)
		(fill
			(thermal_gap 0.5)
			(thermal_bridge_width 0.5)
			(island_removal_mode 0)
		)
		(polygon
			(pts
				(xy 368.970814 -124.643642) (xy 366.684814 -124.643642) (xy 366.684814 -124.135642) (xy 368.970814 -124.135642)
			)
		)
	)
	(zone
		(layer "In12.Cu")
		(hatch none 0.5)
		(connect_pads
			(clearance 0)
		)
		(min_thickness 0.25)
		(keepout
			(tracks not_allowed)
			(vias allowed)
			(pads allowed)
			(copperpour not_allowed)
			(footprints allowed)
		)
		(placement
			(enabled no)
			(sheetname "")
		)
		(fill
			(thermal_gap 0.5)
			(thermal_bridge_width 0.5)
			(island_removal_mode 0)
		)
		(polygon
			(pts
				(xy 301.520352 -23.922482) (xy 302.079152 -23.922482) (xy 302.079152 -25.725882) (xy 301.520352 -25.725882)
			)
		)
	)
	(zone
		(layer "In12.Cu")
		(hatch none 0.5)
		(connect_pads
			(clearance 0)
		)
		(min_thickness 0.25)
		(keepout
			(tracks not_allowed)
			(vias allowed)
			(pads allowed)
			(copperpour not_allowed)
			(footprints allowed)
		)
		(placement
			(enabled no)
			(sheetname "")
		)
		(fill
			(thermal_gap 0.5)
			(thermal_bridge_width 0.5)
			(island_removal_mode 0)
		)
		(polygon
			(pts
				(xy 294.720518 -4.720082) (xy 295.279318 -4.720082) (xy 295.279318 -6.523482) (xy 294.720518 -6.523482)
			)
		)
	)
	(zone
		(layer "In12.Cu")
		(hatch none 0.5)
		(connect_pads
			(clearance 0)
		)
		(min_thickness 0.25)
		(keepout
			(tracks not_allowed)
			(vias allowed)
			(pads allowed)
			(copperpour not_allowed)
			(footprints allowed)
		)
		(placement
			(enabled no)
			(sheetname "")
		)
		(fill
			(thermal_gap 0.5)
			(thermal_bridge_width 0.5)
			(island_removal_mode 0)
		)
		(polygon
			(pts
				(xy 75.320144 -127.374142) (xy 75.878944 -127.374142) (xy 75.878944 -129.177542) (xy 75.320144 -129.177542)
			)
		)
	)
	(zone
		(layer "In12.Cu")
		(hatch none 0.5)
		(connect_pads
			(clearance 0)
		)
		(min_thickness 0.25)
		(keepout
			(tracks not_allowed)
			(vias allowed)
			(pads allowed)
			(copperpour not_allowed)
			(footprints allowed)
		)
		(placement
			(enabled no)
			(sheetname "")
		)
		(fill
			(thermal_gap 0.5)
			(thermal_bridge_width 0.5)
			(island_removal_mode 0)
		)
		(polygon
			(pts
				(xy 144.169892 -151.176482) (xy 144.728692 -151.176482) (xy 144.728692 -152.979882) (xy 144.169892 -152.979882)
			)
		)
	)
	(zone
		(layer "In12.Cu")
		(hatch none 0.5)
		(connect_pads
			(clearance 0)
		)
		(min_thickness 0.25)
		(keepout
			(tracks not_allowed)
			(vias allowed)
			(pads allowed)
			(copperpour not_allowed)
			(footprints allowed)
		)
		(placement
			(enabled no)
			(sheetname "")
		)
		(fill
			(thermal_gap 0.5)
			(thermal_bridge_width 0.5)
			(island_removal_mode 0)
		)
		(polygon
			(pts
				(xy 277.720552 -9.721342) (xy 278.279352 -9.721342) (xy 278.279352 -11.524742) (xy 277.720552 -11.524742)
			)
		)
	)
	(zone
		(layer "In12.Cu")
		(hatch none 0.5)
		(connect_pads
			(clearance 0)
		)
		(min_thickness 0.25)
		(keepout
			(tracks not_allowed)
			(vias allowed)
			(pads allowed)
			(copperpour not_allowed)
			(footprints allowed)
		)
		(placement
			(enabled no)
			(sheetname "")
		)
		(fill
			(thermal_gap 0.5)
			(thermal_bridge_width 0.5)
			(island_removal_mode 0)
		)
		(polygon
			(pts
				(xy 82.970116 -136.975342) (xy 83.528916 -136.975342) (xy 83.528916 -138.778742) (xy 82.970116 -138.778742)
			)
		)
	)
	(zone
		(layer "In12.Cu")
		(hatch none 0.5)
		(connect_pads
			(clearance 0)
		)
		(min_thickness 0.25)
		(keepout
			(tracks not_allowed)
			(vias allowed)
			(pads allowed)
			(copperpour not_allowed)
			(footprints allowed)
		)
		(placement
			(enabled no)
			(sheetname "")
		)
		(fill
			(thermal_gap 0.5)
			(thermal_bridge_width 0.5)
			(island_removal_mode 0)
		)
		(polygon
			(pts
				(xy 240.320576 -136.975342) (xy 240.879376 -136.975342) (xy 240.879376 -138.778742) (xy 240.320576 -138.778742)
			)
		)
	)
	(zone
		(layer "In12.Cu")
		(hatch none 0.5)
		(connect_pads
			(clearance 0)
		)
		(min_thickness 0.25)
		(keepout
			(tracks not_allowed)
			(vias allowed)
			(pads allowed)
			(copperpour not_allowed)
			(footprints allowed)
		)
		(placement
			(enabled no)
			(sheetname "")
		)
		(fill
			(thermal_gap 0.5)
			(thermal_bridge_width 0.5)
			(island_removal_mode 0)
		)
		(polygon
			(pts
				(xy 280.270458 -146.576542) (xy 280.829258 -146.576542) (xy 280.829258 -148.379942) (xy 280.270458 -148.379942)
			)
		)
	)
	(zone
		(layer "In12.Cu")
		(hatch none 0.5)
		(connect_pads
			(clearance 0)
		)
		(min_thickness 0.25)
		(keepout
			(tracks not_allowed)
			(vias allowed)
			(pads allowed)
			(copperpour not_allowed)
			(footprints allowed)
		)
		(placement
			(enabled no)
			(sheetname "")
		)
		(fill
			(thermal_gap 0.5)
			(thermal_bridge_width 0.5)
			(island_removal_mode 0)
		)
		(polygon
			(pts
				(xy 108.469938 -19.322542) (xy 109.028738 -19.322542) (xy 109.028738 -21.125942) (xy 108.469938 -21.125942)
			)
		)
	)
	(zone
		(layer "In12.Cu")
		(hatch none 0.5)
		(connect_pads
			(clearance 0)
		)
		(min_thickness 0.25)
		(keepout
			(tracks not_allowed)
			(vias allowed)
			(pads allowed)
			(copperpour not_allowed)
			(footprints allowed)
		)
		(placement
			(enabled no)
			(sheetname "")
		)
		(fill
			(thermal_gap 0.5)
			(thermal_bridge_width 0.5)
			(island_removal_mode 0)
		)
		(polygon
			(pts
				(xy 250.520454 -136.975342) (xy 251.079254 -136.975342) (xy 251.079254 -138.778742) (xy 250.520454 -138.778742)
			)
		)
	)
	(zone
		(layer "In12.Cu")
		(hatch none 0.5)
		(connect_pads
			(clearance 0)
		)
		(min_thickness 0.25)
		(keepout
			(tracks not_allowed)
			(vias allowed)
			(pads allowed)
			(copperpour not_allowed)
			(footprints allowed)
		)
		(placement
			(enabled no)
			(sheetname "")
		)
		(fill
			(thermal_gap 0.5)
			(thermal_bridge_width 0.5)
			(island_removal_mode 0)
		)
		(polygon
			(pts
				(xy 115.270026 -136.975342) (xy 115.828826 -136.975342) (xy 115.828826 -138.778742) (xy 115.270026 -138.778742)
			)
		)
	)
	(zone
		(layer "In12.Cu")
		(hatch none 0.5)
		(connect_pads
			(clearance 0)
		)
		(min_thickness 0.25)
		(keepout
			(tracks not_allowed)
			(vias allowed)
			(pads allowed)
			(copperpour not_allowed)
			(footprints allowed)
		)
		(placement
			(enabled no)
			(sheetname "")
		)
		(fill
			(thermal_gap 0.5)
			(thermal_bridge_width 0.5)
			(island_removal_mode 0)
		)
		(polygon
			(pts
				(xy 206.32039 -9.721342) (xy 206.87919 -9.721342) (xy 206.87919 -11.524742) (xy 206.32039 -11.524742)
			)
		)
	)
	(zone
		(layer "In12.Cu")
		(hatch none 0.5)
		(connect_pads
			(clearance 0)
		)
		(min_thickness 0.25)
		(keepout
			(tracks not_allowed)
			(vias allowed)
			(pads allowed)
			(copperpour not_allowed)
			(footprints allowed)
		)
		(placement
			(enabled no)
			(sheetname "")
		)
		(fill
			(thermal_gap 0.5)
			(thermal_bridge_width 0.5)
			(island_removal_mode 0)
		)
		(polygon
			(pts
				(xy 303.220374 -19.322542) (xy 303.779174 -19.322542) (xy 303.779174 -21.125942) (xy 303.220374 -21.125942)
			)
		)
	)
	(zone
		(layer "In12.Cu")
		(hatch none 0.5)
		(connect_pads
			(clearance 0)
		)
		(min_thickness 0.25)
		(keepout
			(tracks not_allowed)
			(vias allowed)
			(pads allowed)
			(copperpour not_allowed)
			(footprints allowed)
		)
		(placement
			(enabled no)
			(sheetname "")
		)
		(fill
			(thermal_gap 0.5)
			(thermal_bridge_width 0.5)
			(island_removal_mode 0)
		)
		(polygon
			(pts
				(xy 69.36994 -19.322542) (xy 69.92874 -19.322542) (xy 69.92874 -21.125942) (xy 69.36994 -21.125942)
			)
		)
	)
	(zone
		(layer "In12.Cu")
		(hatch none 0.5)
		(connect_pads
			(clearance 0)
		)
		(min_thickness 0.25)
		(keepout
			(tracks not_allowed)
			(vias allowed)
			(pads allowed)
			(copperpour not_allowed)
			(footprints allowed)
		)
		(placement
			(enabled no)
			(sheetname "")
		)
		(fill
			(thermal_gap 0.5)
			(thermal_bridge_width 0.5)
			(island_removal_mode 0)
		)
		(polygon
			(pts
				(xy 112.72012 -127.374142) (xy 113.27892 -127.374142) (xy 113.27892 -129.177542) (xy 112.72012 -129.177542)
			)
		)
	)
	(zone
		(layer "In12.Cu")
		(hatch none 0.5)
		(connect_pads
			(clearance 0)
		)
		(min_thickness 0.25)
		(keepout
			(tracks not_allowed)
			(vias allowed)
			(pads allowed)
			(copperpour not_allowed)
			(footprints allowed)
		)
		(placement
			(enabled no)
			(sheetname "")
		)
		(fill
			(thermal_gap 0.5)
			(thermal_bridge_width 0.5)
			(island_removal_mode 0)
		)
		(polygon
			(pts
				(xy 82.119978 -4.720082) (xy 82.678778 -4.720082) (xy 82.678778 -6.523482) (xy 82.119978 -6.523482)
			)
		)
	)
	(zone
		(layer "In12.Cu")
		(hatch none 0.5)
		(connect_pads
			(clearance 0)
		)
		(min_thickness 0.25)
		(keepout
			(tracks not_allowed)
			(vias allowed)
			(pads allowed)
			(copperpour not_allowed)
			(footprints allowed)
		)
		(placement
			(enabled no)
			(sheetname "")
		)
		(fill
			(thermal_gap 0.5)
			(thermal_bridge_width 0.5)
			(island_removal_mode 0)
		)
		(polygon
			(pts
				(xy 127.169926 -141.575282) (xy 127.728726 -141.575282) (xy 127.728726 -143.378682) (xy 127.169926 -143.378682)
			)
		)
	)
	(zone
		(layer "In12.Cu")
		(hatch none 0.5)
		(connect_pads
			(clearance 0)
		)
		(min_thickness 0.25)
		(keepout
			(tracks not_allowed)
			(vias allowed)
			(pads allowed)
			(copperpour not_allowed)
			(footprints allowed)
		)
		(placement
			(enabled no)
			(sheetname "")
		)
		(fill
			(thermal_gap 0.5)
			(thermal_bridge_width 0.5)
			(island_removal_mode 0)
		)
		(polygon
			(pts
				(xy 132.269992 -19.322542) (xy 132.828792 -19.322542) (xy 132.828792 -21.125942) (xy 132.269992 -21.125942)
			)
		)
	)
	(zone
		(layer "In12.Cu")
		(hatch none 0.5)
		(connect_pads
			(clearance 0)
		)
		(min_thickness 0.25)
		(keepout
			(tracks not_allowed)
			(vias allowed)
			(pads allowed)
			(copperpour not_allowed)
			(footprints allowed)
		)
		(placement
			(enabled no)
			(sheetname "")
		)
		(fill
			(thermal_gap 0.5)
			(thermal_bridge_width 0.5)
			(island_removal_mode 0)
		)
		(polygon
			(pts
				(xy 201.220578 -127.374142) (xy 201.779378 -127.374142) (xy 201.779378 -129.177542) (xy 201.220578 -129.177542)
			)
		)
	)
	(zone
		(layer "In12.Cu")
		(hatch none 0.5)
		(connect_pads
			(clearance 0)
		)
		(min_thickness 0.25)
		(keepout
			(tracks not_allowed)
			(vias allowed)
			(pads allowed)
			(copperpour not_allowed)
			(footprints allowed)
		)
		(placement
			(enabled no)
			(sheetname "")
		)
		(fill
			(thermal_gap 0.5)
			(thermal_bridge_width 0.5)
			(island_removal_mode 0)
		)
		(polygon
			(pts
				(xy 124.62002 -0.120142) (xy 125.17882 -0.120142) (xy 125.17882 -1.923542) (xy 124.62002 -1.923542)
			)
		)
	)
	(zone
		(layer "In12.Cu")
		(hatch none 0.5)
		(connect_pads
			(clearance 0)
		)
		(min_thickness 0.25)
		(keepout
			(tracks not_allowed)
			(vias allowed)
			(pads allowed)
			(copperpour not_allowed)
			(footprints allowed)
		)
		(placement
			(enabled no)
			(sheetname "")
		)
		(fill
			(thermal_gap 0.5)
			(thermal_bridge_width 0.5)
			(island_removal_mode 0)
		)
		(polygon
			(pts
				(xy 294.720518 -23.922482) (xy 295.279318 -23.922482) (xy 295.279318 -25.725882) (xy 294.720518 -25.725882)
			)
		)
	)
	(zone
		(layer "In12.Cu")
		(hatch none 0.5)
		(connect_pads
			(clearance 0)
		)
		(min_thickness 0.25)
		(keepout
			(tracks not_allowed)
			(vias allowed)
			(pads allowed)
			(copperpour not_allowed)
			(footprints allowed)
		)
		(placement
			(enabled no)
			(sheetname "")
		)
		(fill
			(thermal_gap 0.5)
			(thermal_bridge_width 0.5)
			(island_removal_mode 0)
		)
		(polygon
			(pts
				(xy 353.158806 -59.225434) (xy 353.158806 -61.511434) (xy 352.650806 -61.511434) (xy 352.650806 -59.225434)
			)
		)
	)
	(zone
		(layer "In12.Cu")
		(hatch none 0.5)
		(connect_pads
			(clearance 0)
		)
		(min_thickness 0.25)
		(keepout
			(tracks not_allowed)
			(vias allowed)
			(pads allowed)
			(copperpour not_allowed)
			(footprints allowed)
		)
		(placement
			(enabled no)
			(sheetname "")
		)
		(fill
			(thermal_gap 0.5)
			(thermal_bridge_width 0.5)
			(island_removal_mode 0)
		)
		(polygon
			(pts
				(xy 49.820068 -23.922482) (xy 50.378868 -23.922482) (xy 50.378868 -25.725882) (xy 49.820068 -25.725882)
			)
		)
	)
	(zone
		(layer "In12.Cu")
		(hatch none 0.5)
		(connect_pads
			(clearance 0)
		)
		(min_thickness 0.25)
		(keepout
			(tracks not_allowed)
			(vias allowed)
			(pads allowed)
			(copperpour not_allowed)
			(footprints allowed)
		)
		(placement
			(enabled no)
			(sheetname "")
		)
		(fill
			(thermal_gap 0.5)
			(thermal_bridge_width 0.5)
			(island_removal_mode 0)
		)
		(polygon
			(pts
				(xy 137.370058 -9.721342) (xy 137.928858 -9.721342) (xy 137.928858 -11.524742) (xy 137.370058 -11.524742)
			)
		)
	)
	(zone
		(layer "In12.Cu")
		(hatch none 0.5)
		(connect_pads
			(clearance 0)
		)
		(min_thickness 0.25)
		(keepout
			(tracks not_allowed)
			(vias allowed)
			(pads allowed)
			(copperpour not_allowed)
			(footprints allowed)
		)
		(placement
			(enabled no)
			(sheetname "")
		)
		(fill
			(thermal_gap 0.5)
			(thermal_bridge_width 0.5)
			(island_removal_mode 0)
		)
		(polygon
			(pts
				(xy 203.770484 -141.575282) (xy 204.329284 -141.575282) (xy 204.329284 -143.378682) (xy 203.770484 -143.378682)
			)
		)
	)
	(zone
		(layer "In12.Cu")
		(hatch none 0.5)
		(connect_pads
			(clearance 0)
		)
		(min_thickness 0.25)
		(keepout
			(tracks not_allowed)
			(vias allowed)
			(pads allowed)
			(copperpour not_allowed)
			(footprints allowed)
		)
		(placement
			(enabled no)
			(sheetname "")
		)
		(fill
			(thermal_gap 0.5)
			(thermal_bridge_width 0.5)
			(island_removal_mode 0)
		)
		(polygon
			(pts
				(xy 146.720052 -151.176482) (xy 147.278852 -151.176482) (xy 147.278852 -152.979882) (xy 146.720052 -152.979882)
			)
		)
	)
	(zone
		(layer "In12.Cu")
		(hatch none 0.5)
		(connect_pads
			(clearance 0)
		)
		(min_thickness 0.25)
		(keepout
			(tracks not_allowed)
			(vias allowed)
			(pads allowed)
			(copperpour not_allowed)
			(footprints allowed)
		)
		(placement
			(enabled no)
			(sheetname "")
		)
		(fill
			(thermal_gap 0.5)
			(thermal_bridge_width 0.5)
			(island_removal_mode 0)
		)
		(polygon
			(pts
				(xy 39.619936 -9.721342) (xy 40.178736 -9.721342) (xy 40.178736 -11.524742) (xy 39.619936 -11.524742)
			)
		)
	)
	(zone
		(layer "In12.Cu")
		(hatch none 0.5)
		(connect_pads
			(clearance 0)
		)
		(min_thickness 0.25)
		(keepout
			(tracks not_allowed)
			(vias allowed)
			(pads allowed)
			(copperpour not_allowed)
			(footprints allowed)
		)
		(placement
			(enabled no)
			(sheetname "")
		)
		(fill
			(thermal_gap 0.5)
			(thermal_bridge_width 0.5)
			(island_removal_mode 0)
		)
		(polygon
			(pts
				(xy 88.070182 -19.322542) (xy 88.628982 -19.322542) (xy 88.628982 -21.125942) (xy 88.070182 -21.125942)
			)
		)
	)
	(zone
		(layer "In12.Cu")
		(hatch none 0.5)
		(connect_pads
			(clearance 0)
		)
		(min_thickness 0.25)
		(keepout
			(tracks not_allowed)
			(vias allowed)
			(pads allowed)
			(copperpour not_allowed)
			(footprints allowed)
		)
		(placement
			(enabled no)
			(sheetname "")
		)
		(fill
			(thermal_gap 0.5)
			(thermal_bridge_width 0.5)
			(island_removal_mode 0)
		)
		(polygon
			(pts
				(xy 82.119978 -23.922482) (xy 82.678778 -23.922482) (xy 82.678778 -25.725882) (xy 82.119978 -25.725882)
			)
		)
	)
	(zone
		(layer "In12.Cu")
		(hatch none 0.5)
		(connect_pads
			(clearance 0)
		)
		(min_thickness 0.25)
		(keepout
			(tracks not_allowed)
			(vias allowed)
			(pads allowed)
			(copperpour not_allowed)
			(footprints allowed)
		)
		(placement
			(enabled no)
			(sheetname "")
		)
		(fill
			(thermal_gap 0.5)
			(thermal_bridge_width 0.5)
			(island_removal_mode 0)
		)
		(polygon
			(pts
				(xy 131.420108 -151.176482) (xy 131.978908 -151.176482) (xy 131.978908 -152.979882) (xy 131.420108 -152.979882)
			)
		)
	)
	(zone
		(layer "In12.Cu")
		(hatch none 0.5)
		(connect_pads
			(clearance 0)
		)
		(min_thickness 0.25)
		(keepout
			(tracks not_allowed)
			(vias allowed)
			(pads allowed)
			(copperpour not_allowed)
			(footprints allowed)
		)
		(placement
			(enabled no)
			(sheetname "")
		)
		(fill
			(thermal_gap 0.5)
			(thermal_bridge_width 0.5)
			(island_removal_mode 0)
		)
		(polygon
			(pts
				(xy 142.46987 -141.575282) (xy 143.02867 -141.575282) (xy 143.02867 -143.378682) (xy 142.46987 -143.378682)
			)
		)
	)
	(zone
		(layer "In12.Cu")
		(hatch none 0.5)
		(connect_pads
			(clearance 0)
		)
		(min_thickness 0.25)
		(keepout
			(tracks not_allowed)
			(vias allowed)
			(pads allowed)
			(copperpour not_allowed)
			(footprints allowed)
		)
		(placement
			(enabled no)
			(sheetname "")
		)
		(fill
			(thermal_gap 0.5)
			(thermal_bridge_width 0.5)
			(island_removal_mode 0)
		)
		(polygon
			(pts
				(xy 130.56997 -0.120142) (xy 131.12877 -0.120142) (xy 131.12877 -1.923542) (xy 130.56997 -1.923542)
			)
		)
	)
	(zone
		(layer "In12.Cu")
		(hatch none 0.5)
		(connect_pads
			(clearance 0)
		)
		(min_thickness 0.25)
		(keepout
			(tracks not_allowed)
			(vias allowed)
			(pads allowed)
			(copperpour not_allowed)
			(footprints allowed)
		)
		(placement
			(enabled no)
			(sheetname "")
		)
		(fill
			(thermal_gap 0.5)
			(thermal_bridge_width 0.5)
			(island_removal_mode 0)
		)
		(polygon
			(pts
				(xy 302.37049 -146.576542) (xy 302.92929 -146.576542) (xy 302.92929 -148.379942) (xy 302.37049 -148.379942)
			)
		)
	)
	(zone
		(layer "In12.Cu")
		(hatch none 0.5)
		(connect_pads
			(clearance 0)
		)
		(min_thickness 0.25)
		(keepout
			(tracks not_allowed)
			(vias allowed)
			(pads allowed)
			(copperpour not_allowed)
			(footprints allowed)
		)
		(placement
			(enabled no)
			(sheetname "")
		)
		(fill
			(thermal_gap 0.5)
			(thermal_bridge_width 0.5)
			(island_removal_mode 0)
		)
		(polygon
			(pts
				(xy 87.220044 -127.374142) (xy 87.778844 -127.374142) (xy 87.778844 -129.177542) (xy 87.220044 -129.177542)
			)
		)
	)
	(zone
		(layer "In12.Cu")
		(hatch none 0.5)
		(connect_pads
			(clearance 0)
		)
		(min_thickness 0.25)
		(keepout
			(tracks not_allowed)
			(vias allowed)
			(pads allowed)
			(copperpour not_allowed)
			(footprints allowed)
		)
		(placement
			(enabled no)
			(sheetname "")
		)
		(fill
			(thermal_gap 0.5)
			(thermal_bridge_width 0.5)
			(island_removal_mode 0)
		)
		(polygon
			(pts
				(xy 197.820534 -151.176482) (xy 198.379334 -151.176482) (xy 198.379334 -152.979882) (xy 197.820534 -152.979882)
			)
		)
	)
	(zone
		(layer "In12.Cu")
		(hatch none 0.5)
		(connect_pads
			(clearance 0)
		)
		(min_thickness 0.25)
		(keepout
			(tracks not_allowed)
			(vias allowed)
			(pads allowed)
			(copperpour not_allowed)
			(footprints allowed)
		)
		(placement
			(enabled no)
			(sheetname "")
		)
		(fill
			(thermal_gap 0.5)
			(thermal_bridge_width 0.5)
			(island_removal_mode 0)
		)
		(polygon
			(pts
				(xy 195.270374 -0.120142) (xy 195.829174 -0.120142) (xy 195.829174 -1.923542) (xy 195.270374 -1.923542)
			)
		)
	)
	(zone
		(layer "In12.Cu")
		(hatch none 0.5)
		(connect_pads
			(clearance 0)
		)
		(min_thickness 0.25)
		(keepout
			(tracks not_allowed)
			(vias allowed)
			(pads allowed)
			(copperpour not_allowed)
			(footprints allowed)
		)
		(placement
			(enabled no)
			(sheetname "")
		)
		(fill
			(thermal_gap 0.5)
			(thermal_bridge_width 0.5)
			(island_removal_mode 0)
		)
		(polygon
			(pts
				(xy 308.32044 -9.721342) (xy 308.87924 -9.721342) (xy 308.87924 -11.524742) (xy 308.32044 -11.524742)
			)
		)
	)
	(zone
		(layer "In12.Cu")
		(hatch none 0.5)
		(connect_pads
			(clearance 0)
		)
		(min_thickness 0.25)
		(keepout
			(tracks not_allowed)
			(vias allowed)
			(pads allowed)
			(copperpour not_allowed)
			(footprints allowed)
		)
		(placement
			(enabled no)
			(sheetname "")
		)
		(fill
			(thermal_gap 0.5)
			(thermal_bridge_width 0.5)
			(island_removal_mode 0)
		)
		(polygon
			(pts
				(xy 129.720086 -131.974082) (xy 130.278886 -131.974082) (xy 130.278886 -133.777482) (xy 129.720086 -133.777482)
			)
		)
	)
	(zone
		(layer "In12.Cu")
		(hatch none 0.5)
		(connect_pads
			(clearance 0)
		)
		(min_thickness 0.25)
		(keepout
			(tracks not_allowed)
			(vias allowed)
			(pads allowed)
			(copperpour not_allowed)
			(footprints allowed)
		)
		(placement
			(enabled no)
			(sheetname "")
		)
		(fill
			(thermal_gap 0.5)
			(thermal_bridge_width 0.5)
			(island_removal_mode 0)
		)
		(polygon
			(pts
				(xy 79.570072 -23.922482) (xy 80.128872 -23.922482) (xy 80.128872 -25.725882) (xy 79.570072 -25.725882)
			)
		)
	)
	(zone
		(layer "In12.Cu")
		(hatch none 0.5)
		(connect_pads
			(clearance 0)
		)
		(min_thickness 0.25)
		(keepout
			(tracks not_allowed)
			(vias allowed)
			(pads allowed)
			(copperpour not_allowed)
			(footprints allowed)
		)
		(placement
			(enabled no)
			(sheetname "")
		)
		(fill
			(thermal_gap 0.5)
			(thermal_bridge_width 0.5)
			(island_removal_mode 0)
		)
		(polygon
			(pts
				(xy 44.720002 -4.720082) (xy 45.278802 -4.720082) (xy 45.278802 -6.523482) (xy 44.720002 -6.523482)
			)
		)
	)
	(zone
		(layer "In12.Cu")
		(hatch none 0.5)
		(connect_pads
			(clearance 0)
		)
		(min_thickness 0.25)
		(keepout
			(tracks not_allowed)
			(vias allowed)
			(pads allowed)
			(copperpour not_allowed)
			(footprints allowed)
		)
		(placement
			(enabled no)
			(sheetname "")
		)
		(fill
			(thermal_gap 0.5)
			(thermal_bridge_width 0.5)
			(island_removal_mode 0)
		)
		(polygon
			(pts
				(xy 45.57014 -136.975342) (xy 46.12894 -136.975342) (xy 46.12894 -138.778742) (xy 45.57014 -138.778742)
			)
		)
	)
	(zone
		(layer "In12.Cu")
		(hatch none 0.5)
		(connect_pads
			(clearance 0)
		)
		(min_thickness 0.25)
		(keepout
			(tracks not_allowed)
			(vias allowed)
			(pads allowed)
			(copperpour not_allowed)
			(footprints allowed)
		)
		(placement
			(enabled no)
			(sheetname "")
		)
		(fill
			(thermal_gap 0.5)
			(thermal_bridge_width 0.5)
			(island_removal_mode 0)
		)
		(polygon
			(pts
				(xy 51.52009 -4.720082) (xy 52.07889 -4.720082) (xy 52.07889 -6.523482) (xy 51.52009 -6.523482)
			)
		)
	)
	(zone
		(layer "In12.Cu")
		(hatch none 0.5)
		(connect_pads
			(clearance 0)
		)
		(min_thickness 0.25)
		(keepout
			(tracks not_allowed)
			(vias allowed)
			(pads allowed)
			(copperpour not_allowed)
			(footprints allowed)
		)
		(placement
			(enabled no)
			(sheetname "")
		)
		(fill
			(thermal_gap 0.5)
			(thermal_bridge_width 0.5)
			(island_removal_mode 0)
		)
		(polygon
			(pts
				(xy 108.469938 -0.120142) (xy 109.028738 -0.120142) (xy 109.028738 -1.923542) (xy 108.469938 -1.923542)
			)
		)
	)
	(zone
		(layer "In12.Cu")
		(hatch none 0.5)
		(connect_pads
			(clearance 0)
		)
		(min_thickness 0.25)
		(keepout
			(tracks not_allowed)
			(vias allowed)
			(pads allowed)
			(copperpour not_allowed)
			(footprints allowed)
		)
		(placement
			(enabled no)
			(sheetname "")
		)
		(fill
			(thermal_gap 0.5)
			(thermal_bridge_width 0.5)
			(island_removal_mode 0)
		)
		(polygon
			(pts
				(xy 276.02053 -19.322542) (xy 276.57933 -19.322542) (xy 276.57933 -21.125942) (xy 276.02053 -21.125942)
			)
		)
	)
	(zone
		(layer "In12.Cu")
		(hatch none 0.5)
		(connect_pads
			(clearance 0)
		)
		(min_thickness 0.25)
		(keepout
			(tracks not_allowed)
			(vias allowed)
			(pads allowed)
			(copperpour not_allowed)
			(footprints allowed)
		)
		(placement
			(enabled no)
			(sheetname "")
		)
		(fill
			(thermal_gap 0.5)
			(thermal_bridge_width 0.5)
			(island_removal_mode 0)
		)
		(polygon
			(pts
				(xy 246.270526 -141.575282) (xy 246.829326 -141.575282) (xy 246.829326 -143.378682) (xy 246.270526 -143.378682)
			)
		)
	)
	(zone
		(layer "In12.Cu")
		(hatch none 0.5)
		(connect_pads
			(clearance 0)
		)
		(min_thickness 0.25)
		(keepout
			(tracks not_allowed)
			(vias allowed)
			(pads allowed)
			(copperpour not_allowed)
			(footprints allowed)
		)
		(placement
			(enabled no)
			(sheetname "")
		)
		(fill
			(thermal_gap 0.5)
			(thermal_bridge_width 0.5)
			(island_removal_mode 0)
		)
		(polygon
			(pts
				(xy 219.070428 -151.176482) (xy 219.629228 -151.176482) (xy 219.629228 -152.979882) (xy 219.070428 -152.979882)
			)
		)
	)
	(zone
		(layer "In12.Cu")
		(hatch none 0.5)
		(connect_pads
			(clearance 0)
		)
		(min_thickness 0.25)
		(keepout
			(tracks not_allowed)
			(vias allowed)
			(pads allowed)
			(copperpour not_allowed)
			(footprints allowed)
		)
		(placement
			(enabled no)
			(sheetname "")
		)
		(fill
			(thermal_gap 0.5)
			(thermal_bridge_width 0.5)
			(island_removal_mode 0)
		)
		(polygon
			(pts
				(xy 281.120342 -151.176482) (xy 281.679142 -151.176482) (xy 281.679142 -152.979882) (xy 281.120342 -152.979882)
			)
		)
	)
	(zone
		(layer "In12.Cu")
		(hatch none 0.5)
		(connect_pads
			(clearance 0)
		)
		(min_thickness 0.25)
		(keepout
			(tracks not_allowed)
			(vias allowed)
			(pads allowed)
			(copperpour not_allowed)
			(footprints allowed)
		)
		(placement
			(enabled no)
			(sheetname "")
		)
		(fill
			(thermal_gap 0.5)
			(thermal_bridge_width 0.5)
			(island_removal_mode 0)
		)
		(polygon
			(pts
				(xy 139.919964 -127.374142) (xy 140.478764 -127.374142) (xy 140.478764 -129.177542) (xy 139.919964 -129.177542)
			)
		)
	)
	(zone
		(layer "In12.Cu")
		(hatch none 0.5)
		(connect_pads
			(clearance 0)
		)
		(min_thickness 0.25)
		(keepout
			(tracks not_allowed)
			(vias allowed)
			(pads allowed)
			(copperpour not_allowed)
			(footprints allowed)
		)
		(placement
			(enabled no)
			(sheetname "")
		)
		(fill
			(thermal_gap 0.5)
			(thermal_bridge_width 0.5)
			(island_removal_mode 0)
		)
		(polygon
			(pts
				(xy 84.670138 -146.576542) (xy 85.228938 -146.576542) (xy 85.228938 -148.379942) (xy 84.670138 -148.379942)
			)
		)
	)
	(zone
		(layer "In12.Cu")
		(hatch none 0.5)
		(connect_pads
			(clearance 0)
		)
		(min_thickness 0.25)
		(keepout
			(tracks not_allowed)
			(vias allowed)
			(pads allowed)
			(copperpour not_allowed)
			(footprints allowed)
		)
		(placement
			(enabled no)
			(sheetname "")
		)
		(fill
			(thermal_gap 0.5)
			(thermal_bridge_width 0.5)
			(island_removal_mode 0)
		)
		(polygon
			(pts
				(xy 146.720052 -127.374142) (xy 147.278852 -127.374142) (xy 147.278852 -129.177542) (xy 146.720052 -129.177542)
			)
		)
	)
	(zone
		(layer "In12.Cu")
		(hatch none 0.5)
		(connect_pads
			(clearance 0)
		)
		(min_thickness 0.25)
		(keepout
			(tracks not_allowed)
			(vias allowed)
			(pads allowed)
			(copperpour not_allowed)
			(footprints allowed)
		)
		(placement
			(enabled no)
			(sheetname "")
		)
		(fill
			(thermal_gap 0.5)
			(thermal_bridge_width 0.5)
			(island_removal_mode 0)
		)
		(polygon
			(pts
				(xy 148.420074 -151.176482) (xy 148.978874 -151.176482) (xy 148.978874 -152.979882) (xy 148.420074 -152.979882)
			)
		)
	)
	(zone
		(layer "In12.Cu")
		(hatch none 0.5)
		(connect_pads
			(clearance 0)
		)
		(min_thickness 0.25)
		(keepout
			(tracks not_allowed)
			(vias allowed)
			(pads allowed)
			(copperpour not_allowed)
			(footprints allowed)
		)
		(placement
			(enabled no)
			(sheetname "")
		)
		(fill
			(thermal_gap 0.5)
			(thermal_bridge_width 0.5)
			(island_removal_mode 0)
		)
		(polygon
			(pts
				(xy 102.519988 -9.721342) (xy 103.078788 -9.721342) (xy 103.078788 -11.524742) (xy 102.519988 -11.524742)
			)
		)
	)
	(zone
		(layer "In12.Cu")
		(hatch none 0.5)
		(connect_pads
			(clearance 0)
		)
		(min_thickness 0.25)
		(keepout
			(tracks not_allowed)
			(vias allowed)
			(pads allowed)
			(copperpour not_allowed)
			(footprints allowed)
		)
		(placement
			(enabled no)
			(sheetname "")
		)
		(fill
			(thermal_gap 0.5)
			(thermal_bridge_width 0.5)
			(island_removal_mode 0)
		)
		(polygon
			(pts
				(xy 218.220544 -151.176482) (xy 218.779344 -151.176482) (xy 218.779344 -152.979882) (xy 218.220544 -152.979882)
			)
		)
	)
	(zone
		(layer "In12.Cu")
		(hatch none 0.5)
		(connect_pads
			(clearance 0)
		)
		(min_thickness 0.25)
		(keepout
			(tracks not_allowed)
			(vias allowed)
			(pads allowed)
			(copperpour not_allowed)
			(footprints allowed)
		)
		(placement
			(enabled no)
			(sheetname "")
		)
		(fill
			(thermal_gap 0.5)
			(thermal_bridge_width 0.5)
			(island_removal_mode 0)
		)
		(polygon
			(pts
				(xy 32.820102 -14.321282) (xy 33.378902 -14.321282) (xy 33.378902 -16.124682) (xy 32.820102 -16.124682)
			)
		)
	)
	(zone
		(layer "In12.Cu")
		(hatch none 0.5)
		(connect_pads
			(clearance 0)
		)
		(min_thickness 0.25)
		(keepout
			(tracks not_allowed)
			(vias allowed)
			(pads allowed)
			(copperpour not_allowed)
			(footprints allowed)
		)
		(placement
			(enabled no)
			(sheetname "")
		)
		(fill
			(thermal_gap 0.5)
			(thermal_bridge_width 0.5)
			(island_removal_mode 0)
		)
		(polygon
			(pts
				(xy 254.770382 -136.975342) (xy 255.329182 -136.975342) (xy 255.329182 -138.778742) (xy 254.770382 -138.778742)
			)
		)
	)
	(zone
		(layer "In12.Cu")
		(hatch none 0.5)
		(connect_pads
			(clearance 0)
		)
		(min_thickness 0.25)
		(keepout
			(tracks not_allowed)
			(vias allowed)
			(pads allowed)
			(copperpour not_allowed)
			(footprints allowed)
		)
		(placement
			(enabled no)
			(sheetname "")
		)
		(fill
			(thermal_gap 0.5)
			(thermal_bridge_width 0.5)
			(island_removal_mode 0)
		)
		(polygon
			(pts
				(xy 48.120046 -141.575282) (xy 48.678846 -141.575282) (xy 48.678846 -143.378682) (xy 48.120046 -143.378682)
			)
		)
	)
	(zone
		(layer "In12.Cu")
		(hatch none 0.5)
		(connect_pads
			(clearance 0)
		)
		(min_thickness 0.25)
		(keepout
			(tracks not_allowed)
			(vias allowed)
			(pads allowed)
			(copperpour not_allowed)
			(footprints allowed)
		)
		(placement
			(enabled no)
			(sheetname "")
		)
		(fill
			(thermal_gap 0.5)
			(thermal_bridge_width 0.5)
			(island_removal_mode 0)
		)
		(polygon
			(pts
				(xy 146.720052 -23.922482) (xy 147.278852 -23.922482) (xy 147.278852 -25.725882) (xy 146.720052 -25.725882)
			)
		)
	)
	(zone
		(layer "In12.Cu")
		(hatch none 0.5)
		(connect_pads
			(clearance 0)
		)
		(min_thickness 0.25)
		(keepout
			(tracks not_allowed)
			(vias allowed)
			(pads allowed)
			(copperpour not_allowed)
			(footprints allowed)
		)
		(placement
			(enabled no)
			(sheetname "")
		)
		(fill
			(thermal_gap 0.5)
			(thermal_bridge_width 0.5)
			(island_removal_mode 0)
		)
		(polygon
			(pts
				(xy 143.320008 -146.576542) (xy 143.878808 -146.576542) (xy 143.878808 -148.379942) (xy 143.320008 -148.379942)
			)
		)
	)
	(zone
		(layer "In12.Cu")
		(hatch none 0.5)
		(connect_pads
			(clearance 0)
		)
		(min_thickness 0.25)
		(keepout
			(tracks not_allowed)
			(vias allowed)
			(pads allowed)
			(copperpour not_allowed)
			(footprints allowed)
		)
		(placement
			(enabled no)
			(sheetname "")
		)
		(fill
			(thermal_gap 0.5)
			(thermal_bridge_width 0.5)
			(island_removal_mode 0)
		)
		(polygon
			(pts
				(xy 216.520522 -23.922482) (xy 217.079322 -23.922482) (xy 217.079322 -25.725882) (xy 216.520522 -25.725882)
			)
		)
	)
	(zone
		(layer "In12.Cu")
		(hatch none 0.5)
		(connect_pads
			(clearance 0)
		)
		(min_thickness 0.25)
		(keepout
			(tracks not_allowed)
			(vias allowed)
			(pads allowed)
			(copperpour not_allowed)
			(footprints allowed)
		)
		(placement
			(enabled no)
			(sheetname "")
		)
		(fill
			(thermal_gap 0.5)
			(thermal_bridge_width 0.5)
			(island_removal_mode 0)
		)
		(polygon
			(pts
				(xy 105.070148 -151.176482) (xy 105.628948 -151.176482) (xy 105.628948 -152.979882) (xy 105.070148 -152.979882)
			)
		)
	)
	(zone
		(layer "In12.Cu")
		(hatch none 0.5)
		(connect_pads
			(clearance 0)
		)
		(min_thickness 0.25)
		(keepout
			(tracks not_allowed)
			(vias allowed)
			(pads allowed)
			(copperpour not_allowed)
			(footprints allowed)
		)
		(placement
			(enabled no)
			(sheetname "")
		)
		(fill
			(thermal_gap 0.5)
			(thermal_bridge_width 0.5)
			(island_removal_mode 0)
		)
		(polygon
			(pts
				(xy 257.320542 -127.374142) (xy 257.879342 -127.374142) (xy 257.879342 -129.177542) (xy 257.320542 -129.177542)
			)
		)
	)
	(zone
		(layer "In12.Cu")
		(hatch none 0.5)
		(connect_pads
			(clearance 0)
		)
		(min_thickness 0.25)
		(keepout
			(tracks not_allowed)
			(vias allowed)
			(pads allowed)
			(copperpour not_allowed)
			(footprints allowed)
		)
		(placement
			(enabled no)
			(sheetname "")
		)
		(fill
			(thermal_gap 0.5)
			(thermal_bridge_width 0.5)
			(island_removal_mode 0)
		)
		(polygon
			(pts
				(xy 227.570538 -4.720082) (xy 228.129338 -4.720082) (xy 228.129338 -6.523482) (xy 227.570538 -6.523482)
			)
		)
	)
	(zone
		(layer "In12.Cu")
		(hatch none 0.5)
		(connect_pads
			(clearance 0)
		)
		(min_thickness 0.25)
		(keepout
			(tracks not_allowed)
			(vias allowed)
			(pads allowed)
			(copperpour not_allowed)
			(footprints allowed)
		)
		(placement
			(enabled no)
			(sheetname "")
		)
		(fill
			(thermal_gap 0.5)
			(thermal_bridge_width 0.5)
			(island_removal_mode 0)
		)
		(polygon
			(pts
				(xy 79.570072 -14.321282) (xy 80.128872 -14.321282) (xy 80.128872 -16.124682) (xy 79.570072 -16.124682)
			)
		)
	)
	(zone
		(layer "In12.Cu")
		(hatch none 0.5)
		(connect_pads
			(clearance 0)
		)
		(min_thickness 0.25)
		(keepout
			(tracks not_allowed)
			(vias allowed)
			(pads allowed)
			(copperpour not_allowed)
			(footprints allowed)
		)
		(placement
			(enabled no)
			(sheetname "")
		)
		(fill
			(thermal_gap 0.5)
			(thermal_bridge_width 0.5)
			(island_removal_mode 0)
		)
		(polygon
			(pts
				(xy 49.820068 -131.974082) (xy 50.378868 -131.974082) (xy 50.378868 -133.777482) (xy 49.820068 -133.777482)
			)
		)
	)
	(zone
		(layer "In12.Cu")
		(hatch none 0.5)
		(connect_pads
			(clearance 0)
		)
		(min_thickness 0.25)
		(keepout
			(tracks not_allowed)
			(vias allowed)
			(pads allowed)
			(copperpour not_allowed)
			(footprints allowed)
		)
		(placement
			(enabled no)
			(sheetname "")
		)
		(fill
			(thermal_gap 0.5)
			(thermal_bridge_width 0.5)
			(island_removal_mode 0)
		)
		(polygon
			(pts
				(xy 142.46987 -131.974082) (xy 143.02867 -131.974082) (xy 143.02867 -133.777482) (xy 142.46987 -133.777482)
			)
		)
	)
	(zone
		(layer "In12.Cu")
		(hatch none 0.5)
		(connect_pads
			(clearance 0)
		)
		(min_thickness 0.25)
		(keepout
			(tracks not_allowed)
			(vias allowed)
			(pads allowed)
			(copperpour not_allowed)
			(footprints allowed)
		)
		(placement
			(enabled no)
			(sheetname "")
		)
		(fill
			(thermal_gap 0.5)
			(thermal_bridge_width 0.5)
			(island_removal_mode 0)
		)
		(polygon
			(pts
				(xy 111.020098 -136.975342) (xy 111.578898 -136.975342) (xy 111.578898 -138.778742) (xy 111.020098 -138.778742)
			)
		)
	)
	(zone
		(layer "In12.Cu")
		(hatch none 0.5)
		(connect_pads
			(clearance 0)
		)
		(min_thickness 0.25)
		(keepout
			(tracks not_allowed)
			(vias allowed)
			(pads allowed)
			(copperpour not_allowed)
			(footprints allowed)
		)
		(placement
			(enabled no)
			(sheetname "")
		)
		(fill
			(thermal_gap 0.5)
			(thermal_bridge_width 0.5)
			(island_removal_mode 0)
		)
		(polygon
			(pts
				(xy 296.42054 -4.720082) (xy 296.97934 -4.720082) (xy 296.97934 -6.523482) (xy 296.42054 -6.523482)
			)
		)
	)
	(zone
		(layer "In12.Cu")
		(hatch none 0.5)
		(connect_pads
			(clearance 0)
		)
		(min_thickness 0.25)
		(keepout
			(tracks not_allowed)
			(vias allowed)
			(pads allowed)
			(copperpour not_allowed)
			(footprints allowed)
		)
		(placement
			(enabled no)
			(sheetname "")
		)
		(fill
			(thermal_gap 0.5)
			(thermal_bridge_width 0.5)
			(island_removal_mode 0)
		)
		(polygon
			(pts
				(xy 53.220112 -151.176482) (xy 53.778912 -151.176482) (xy 53.778912 -152.979882) (xy 53.220112 -152.979882)
			)
		)
	)
	(zone
		(layer "In12.Cu")
		(hatch none 0.5)
		(connect_pads
			(clearance 0)
		)
		(min_thickness 0.25)
		(keepout
			(tracks not_allowed)
			(vias allowed)
			(pads allowed)
			(copperpour not_allowed)
			(footprints allowed)
		)
		(placement
			(enabled no)
			(sheetname "")
		)
		(fill
			(thermal_gap 0.5)
			(thermal_bridge_width 0.5)
			(island_removal_mode 0)
		)
		(polygon
			(pts
				(xy 281.97048 -127.374142) (xy 282.52928 -127.374142) (xy 282.52928 -129.177542) (xy 281.97048 -129.177542)
			)
		)
	)
	(zone
		(layer "In12.Cu")
		(hatch none 0.5)
		(connect_pads
			(clearance 0)
		)
		(min_thickness 0.25)
		(keepout
			(tracks not_allowed)
			(vias allowed)
			(pads allowed)
			(copperpour not_allowed)
			(footprints allowed)
		)
		(placement
			(enabled no)
			(sheetname "")
		)
		(fill
			(thermal_gap 0.5)
			(thermal_bridge_width 0.5)
			(island_removal_mode 0)
		)
		(polygon
			(pts
				(xy 138.219942 -136.975342) (xy 138.778742 -136.975342) (xy 138.778742 -138.778742) (xy 138.219942 -138.778742)
			)
		)
	)
	(zone
		(layer "In12.Cu")
		(hatch none 0.5)
		(connect_pads
			(clearance 0)
		)
		(min_thickness 0.25)
		(keepout
			(tracks not_allowed)
			(vias allowed)
			(pads allowed)
			(copperpour not_allowed)
			(footprints allowed)
		)
		(placement
			(enabled no)
			(sheetname "")
		)
		(fill
			(thermal_gap 0.5)
			(thermal_bridge_width 0.5)
			(island_removal_mode 0)
		)
		(polygon
			(pts
				(xy 63.41999 -14.321282) (xy 63.97879 -14.321282) (xy 63.97879 -16.124682) (xy 63.41999 -16.124682)
			)
		)
	)
	(zone
		(layer "In12.Cu")
		(hatch none 0.5)
		(connect_pads
			(clearance 0)
		)
		(min_thickness 0.25)
		(keepout
			(tracks not_allowed)
			(vias allowed)
			(pads allowed)
			(copperpour not_allowed)
			(footprints allowed)
		)
		(placement
			(enabled no)
			(sheetname "")
		)
		(fill
			(thermal_gap 0.5)
			(thermal_bridge_width 0.5)
			(island_removal_mode 0)
		)
		(polygon
			(pts
				(xy 243.720366 -136.975342) (xy 244.279166 -136.975342) (xy 244.279166 -138.778742) (xy 243.720366 -138.778742)
			)
		)
	)
	(zone
		(layer "In12.Cu")
		(hatch none 0.5)
		(connect_pads
			(clearance 0)
		)
		(min_thickness 0.25)
		(keepout
			(tracks not_allowed)
			(vias allowed)
			(pads allowed)
			(copperpour not_allowed)
			(footprints allowed)
		)
		(placement
			(enabled no)
			(sheetname "")
		)
		(fill
			(thermal_gap 0.5)
			(thermal_bridge_width 0.5)
			(island_removal_mode 0)
		)
		(polygon
			(pts
				(xy 37.920168 -146.576542) (xy 38.478968 -146.576542) (xy 38.478968 -148.379942) (xy 37.920168 -148.379942)
			)
		)
	)
	(zone
		(layer "In12.Cu")
		(hatch none 0.5)
		(connect_pads
			(clearance 0)
		)
		(min_thickness 0.25)
		(keepout
			(tracks not_allowed)
			(vias allowed)
			(pads allowed)
			(copperpour not_allowed)
			(footprints allowed)
		)
		(placement
			(enabled no)
			(sheetname "")
		)
		(fill
			(thermal_gap 0.5)
			(thermal_bridge_width 0.5)
			(island_removal_mode 0)
		)
		(polygon
			(pts
				(xy 47.270162 -127.374142) (xy 47.828962 -127.374142) (xy 47.828962 -129.177542) (xy 47.270162 -129.177542)
			)
		)
	)
	(zone
		(layer "In12.Cu")
		(hatch none 0.5)
		(connect_pads
			(clearance 0)
		)
		(min_thickness 0.25)
		(keepout
			(tracks not_allowed)
			(vias allowed)
			(pads allowed)
			(copperpour not_allowed)
			(footprints allowed)
		)
		(placement
			(enabled no)
			(sheetname "")
		)
		(fill
			(thermal_gap 0.5)
			(thermal_bridge_width 0.5)
			(island_removal_mode 0)
		)
		(polygon
			(pts
				(xy 88.920066 -4.720082) (xy 89.478866 -4.720082) (xy 89.478866 -6.523482) (xy 88.920066 -6.523482)
			)
		)
	)
	(zone
		(layer "In12.Cu")
		(hatch none 0.5)
		(connect_pads
			(clearance 0)
		)
		(min_thickness 0.25)
		(keepout
			(tracks not_allowed)
			(vias allowed)
			(pads allowed)
			(copperpour not_allowed)
			(footprints allowed)
		)
		(placement
			(enabled no)
			(sheetname "")
		)
		(fill
			(thermal_gap 0.5)
			(thermal_bridge_width 0.5)
			(island_removal_mode 0)
		)
		(polygon
			(pts
				(xy 77.02042 -19.322542) (xy 77.57922 -19.322542) (xy 77.57922 -21.125942) (xy 77.02042 -21.125942)
			)
		)
	)
	(zone
		(layer "In12.Cu")
		(hatch none 0.5)
		(connect_pads
			(clearance 0)
		)
		(min_thickness 0.25)
		(keepout
			(tracks not_allowed)
			(vias allowed)
			(pads allowed)
			(copperpour not_allowed)
			(footprints allowed)
		)
		(placement
			(enabled no)
			(sheetname "")
		)
		(fill
			(thermal_gap 0.5)
			(thermal_bridge_width 0.5)
			(island_removal_mode 0)
		)
		(polygon
			(pts
				(xy 75.320144 -146.576542) (xy 75.878944 -146.576542) (xy 75.878944 -148.379942) (xy 75.320144 -148.379942)
			)
		)
	)
	(zone
		(layer "In12.Cu")
		(hatch none 0.5)
		(connect_pads
			(clearance 0)
		)
		(min_thickness 0.25)
		(keepout
			(tracks not_allowed)
			(vias allowed)
			(pads allowed)
			(copperpour not_allowed)
			(footprints allowed)
		)
		(placement
			(enabled no)
			(sheetname "")
		)
		(fill
			(thermal_gap 0.5)
			(thermal_bridge_width 0.5)
			(island_removal_mode 0)
		)
		(polygon
			(pts
				(xy 119.519954 -136.975342) (xy 120.078754 -136.975342) (xy 120.078754 -138.778742) (xy 119.519954 -138.778742)
			)
		)
	)
	(zone
		(layer "In12.Cu")
		(hatch none 0.5)
		(connect_pads
			(clearance 0)
		)
		(min_thickness 0.25)
		(keepout
			(tracks not_allowed)
			(vias allowed)
			(pads allowed)
			(copperpour not_allowed)
			(footprints allowed)
		)
		(placement
			(enabled no)
			(sheetname "")
		)
		(fill
			(thermal_gap 0.5)
			(thermal_bridge_width 0.5)
			(island_removal_mode 0)
		)
		(polygon
			(pts
				(xy 460.4004 -51.314858) (xy 460.9084 -51.314858) (xy 460.9084 -52.711858) (xy 460.4004 -52.711858)
			)
		)
	)
	(zone
		(layer "In12.Cu")
		(hatch none 0.5)
		(connect_pads
			(clearance 0)
		)
		(min_thickness 0.25)
		(keepout
			(tracks not_allowed)
			(vias allowed)
			(pads allowed)
			(copperpour not_allowed)
			(footprints allowed)
		)
		(placement
			(enabled no)
			(sheetname "")
		)
		(fill
			(thermal_gap 0.5)
			(thermal_bridge_width 0.5)
			(island_removal_mode 0)
		)
		(polygon
			(pts
				(xy 43.01998 -146.576542) (xy 43.57878 -146.576542) (xy 43.57878 -148.379942) (xy 43.01998 -148.379942)
			)
		)
	)
	(zone
		(layer "In12.Cu")
		(hatch none 0.5)
		(connect_pads
			(clearance 0)
		)
		(min_thickness 0.25)
		(keepout
			(tracks not_allowed)
			(vias allowed)
			(pads allowed)
			(copperpour not_allowed)
			(footprints allowed)
		)
		(placement
			(enabled no)
			(sheetname "")
		)
		(fill
			(thermal_gap 0.5)
			(thermal_bridge_width 0.5)
			(island_removal_mode 0)
		)
		(polygon
			(pts
				(xy 231.820466 -4.720082) (xy 232.379266 -4.720082) (xy 232.379266 -6.523482) (xy 231.820466 -6.523482)
			)
		)
	)
	(zone
		(layer "In12.Cu")
		(hatch none 0.5)
		(connect_pads
			(clearance 0)
		)
		(min_thickness 0.25)
		(keepout
			(tracks not_allowed)
			(vias allowed)
			(pads allowed)
			(copperpour not_allowed)
			(footprints allowed)
		)
		(placement
			(enabled no)
			(sheetname "")
		)
		(fill
			(thermal_gap 0.5)
			(thermal_bridge_width 0.5)
			(island_removal_mode 0)
		)
		(polygon
			(pts
				(xy 144.169892 -131.974082) (xy 144.728692 -131.974082) (xy 144.728692 -133.777482) (xy 144.169892 -133.777482)
			)
		)
	)
	(zone
		(layer "In12.Cu")
		(hatch none 0.5)
		(connect_pads
			(clearance 0)
		)
		(min_thickness 0.25)
		(keepout
			(tracks not_allowed)
			(vias allowed)
			(pads allowed)
			(copperpour not_allowed)
			(footprints allowed)
		)
		(placement
			(enabled no)
			(sheetname "")
		)
		(fill
			(thermal_gap 0.5)
			(thermal_bridge_width 0.5)
			(island_removal_mode 0)
		)
		(polygon
			(pts
				(xy 219.070428 -141.575282) (xy 219.629228 -141.575282) (xy 219.629228 -143.378682) (xy 219.070428 -143.378682)
			)
		)
	)
	(zone
		(layer "In12.Cu")
		(hatch none 0.5)
		(connect_pads
			(clearance 0)
		)
		(min_thickness 0.25)
		(keepout
			(tracks not_allowed)
			(vias allowed)
			(pads allowed)
			(copperpour not_allowed)
			(footprints allowed)
		)
		(placement
			(enabled no)
			(sheetname "")
		)
		(fill
			(thermal_gap 0.5)
			(thermal_bridge_width 0.5)
			(island_removal_mode 0)
		)
		(polygon
			(pts
				(xy 310.020462 -136.975342) (xy 310.579262 -136.975342) (xy 310.579262 -138.778742) (xy 310.020462 -138.778742)
			)
		)
	)
	(zone
		(layer "In12.Cu")
		(hatch none 0.5)
		(connect_pads
			(clearance 0)
		)
		(min_thickness 0.25)
		(keepout
			(tracks not_allowed)
			(vias allowed)
			(pads allowed)
			(copperpour not_allowed)
			(footprints allowed)
		)
		(placement
			(enabled no)
			(sheetname "")
		)
		(fill
			(thermal_gap 0.5)
			(thermal_bridge_width 0.5)
			(island_removal_mode 0)
		)
		(polygon
			(pts
				(xy 68.520056 -14.321282) (xy 69.078856 -14.321282) (xy 69.078856 -16.124682) (xy 68.520056 -16.124682)
			)
		)
	)
	(zone
		(layer "In12.Cu")
		(hatch none 0.5)
		(connect_pads
			(clearance 0)
		)
		(min_thickness 0.25)
		(keepout
			(tracks not_allowed)
			(vias allowed)
			(pads allowed)
			(copperpour not_allowed)
			(footprints allowed)
		)
		(placement
			(enabled no)
			(sheetname "")
		)
		(fill
			(thermal_gap 0.5)
			(thermal_bridge_width 0.5)
			(island_removal_mode 0)
		)
		(polygon
			(pts
				(xy 131.420108 -4.720082) (xy 131.978908 -4.720082) (xy 131.978908 -6.523482) (xy 131.420108 -6.523482)
			)
		)
	)
	(zone
		(layer "In12.Cu")
		(hatch none 0.5)
		(connect_pads
			(clearance 0)
		)
		(min_thickness 0.25)
		(keepout
			(tracks not_allowed)
			(vias allowed)
			(pads allowed)
			(copperpour not_allowed)
			(footprints allowed)
		)
		(placement
			(enabled no)
			(sheetname "")
		)
		(fill
			(thermal_gap 0.5)
			(thermal_bridge_width 0.5)
			(island_removal_mode 0)
		)
		(polygon
			(pts
				(xy 206.32039 -19.322542) (xy 206.87919 -19.322542) (xy 206.87919 -21.125942) (xy 206.32039 -21.125942)
			)
		)
	)
	(zone
		(layer "In12.Cu")
		(hatch none 0.5)
		(connect_pads
			(clearance 0)
		)
		(min_thickness 0.25)
		(keepout
			(tracks not_allowed)
			(vias allowed)
			(pads allowed)
			(copperpour not_allowed)
			(footprints allowed)
		)
		(placement
			(enabled no)
			(sheetname "")
		)
		(fill
			(thermal_gap 0.5)
			(thermal_bridge_width 0.5)
			(island_removal_mode 0)
		)
		(polygon
			(pts
				(xy 125.469904 -141.575282) (xy 126.028704 -141.575282) (xy 126.028704 -143.378682) (xy 125.469904 -143.378682)
			)
		)
	)
	(zone
		(layer "In12.Cu")
		(hatch none 0.5)
		(connect_pads
			(clearance 0)
		)
		(min_thickness 0.25)
		(keepout
			(tracks not_allowed)
			(vias allowed)
			(pads allowed)
			(copperpour not_allowed)
			(footprints allowed)
		)
		(placement
			(enabled no)
			(sheetname "")
		)
		(fill
			(thermal_gap 0.5)
			(thermal_bridge_width 0.5)
			(island_removal_mode 0)
		)
		(polygon
			(pts
				(xy 46.420024 -4.720082) (xy 46.978824 -4.720082) (xy 46.978824 -6.523482) (xy 46.420024 -6.523482)
			)
		)
	)
	(zone
		(layer "In12.Cu")
		(hatch none 0.5)
		(connect_pads
			(clearance 0)
		)
		(min_thickness 0.25)
		(keepout
			(tracks not_allowed)
			(vias allowed)
			(pads allowed)
			(copperpour not_allowed)
			(footprints allowed)
		)
		(placement
			(enabled no)
			(sheetname "")
		)
		(fill
			(thermal_gap 0.5)
			(thermal_bridge_width 0.5)
			(island_removal_mode 0)
		)
		(polygon
			(pts
				(xy 420.5732 -146.558) (xy 420.5732 -147.32) (xy 421.5638 -147.32) (xy 421.5638 -146.558)
			)
		)
	)
	(zone
		(layer "In12.Cu")
		(hatch none 0.5)
		(connect_pads
			(clearance 0)
		)
		(min_thickness 0.25)
		(keepout
			(tracks not_allowed)
			(vias allowed)
			(pads allowed)
			(copperpour not_allowed)
			(footprints allowed)
		)
		(placement
			(enabled no)
			(sheetname "")
		)
		(fill
			(thermal_gap 0.5)
			(thermal_bridge_width 0.5)
			(island_removal_mode 0)
		)
		(polygon
			(pts
				(xy 219.070428 -19.322542) (xy 219.629228 -19.322542) (xy 219.629228 -21.125942) (xy 219.070428 -21.125942)
			)
		)
	)
	(zone
		(layer "In12.Cu")
		(hatch none 0.5)
		(connect_pads
			(clearance 0)
		)
		(min_thickness 0.25)
		(keepout
			(tracks not_allowed)
			(vias allowed)
			(pads allowed)
			(copperpour not_allowed)
			(footprints allowed)
		)
		(placement
			(enabled no)
			(sheetname "")
		)
		(fill
			(thermal_gap 0.5)
			(thermal_bridge_width 0.5)
			(island_removal_mode 0)
		)
		(polygon
			(pts
				(xy 112.72012 -19.322542) (xy 113.27892 -19.322542) (xy 113.27892 -21.125942) (xy 112.72012 -21.125942)
			)
		)
	)
	(zone
		(layer "In12.Cu")
		(hatch none 0.5)
		(connect_pads
			(clearance 0)
		)
		(min_thickness 0.25)
		(keepout
			(tracks not_allowed)
			(vias allowed)
			(pads allowed)
			(copperpour not_allowed)
			(footprints allowed)
		)
		(placement
			(enabled no)
			(sheetname "")
		)
		(fill
			(thermal_gap 0.5)
			(thermal_bridge_width 0.5)
			(island_removal_mode 0)
		)
		(polygon
			(pts
				(xy 125.469904 -23.922482) (xy 126.028704 -23.922482) (xy 126.028704 -25.725882) (xy 125.469904 -25.725882)
			)
		)
	)
	(zone
		(layer "In12.Cu")
		(hatch none 0.5)
		(connect_pads
			(clearance 0)
		)
		(min_thickness 0.25)
		(keepout
			(tracks not_allowed)
			(vias allowed)
			(pads allowed)
			(copperpour not_allowed)
			(footprints allowed)
		)
		(placement
			(enabled no)
			(sheetname "")
		)
		(fill
			(thermal_gap 0.5)
			(thermal_bridge_width 0.5)
			(island_removal_mode 0)
		)
		(polygon
			(pts
				(xy 277.720552 -4.720082) (xy 278.279352 -4.720082) (xy 278.279352 -6.523482) (xy 277.720552 -6.523482)
			)
		)
	)
	(zone
		(layer "In12.Cu")
		(hatch none 0.5)
		(connect_pads
			(clearance 0)
		)
		(min_thickness 0.25)
		(keepout
			(tracks not_allowed)
			(vias allowed)
			(pads allowed)
			(copperpour not_allowed)
			(footprints allowed)
		)
		(placement
			(enabled no)
			(sheetname "")
		)
		(fill
			(thermal_gap 0.5)
			(thermal_bridge_width 0.5)
			(island_removal_mode 0)
		)
		(polygon
			(pts
				(xy 67.669918 -0.120142) (xy 68.228718 -0.120142) (xy 68.228718 -1.923542) (xy 67.669918 -1.923542)
			)
		)
	)
	(zone
		(layer "In12.Cu")
		(hatch none 0.5)
		(connect_pads
			(clearance 0)
		)
		(min_thickness 0.25)
		(keepout
			(tracks not_allowed)
			(vias allowed)
			(pads allowed)
			(copperpour not_allowed)
			(footprints allowed)
		)
		(placement
			(enabled no)
			(sheetname "")
		)
		(fill
			(thermal_gap 0.5)
			(thermal_bridge_width 0.5)
			(island_removal_mode 0)
		)
		(polygon
			(pts
				(xy 47.270162 -9.721342) (xy 47.828962 -9.721342) (xy 47.828962 -11.524742) (xy 47.270162 -11.524742)
			)
		)
	)
	(zone
		(layer "In12.Cu")
		(hatch none 0.5)
		(connect_pads
			(clearance 0)
		)
		(min_thickness 0.25)
		(keepout
			(tracks not_allowed)
			(vias allowed)
			(pads allowed)
			(copperpour not_allowed)
			(footprints allowed)
		)
		(placement
			(enabled no)
			(sheetname "")
		)
		(fill
			(thermal_gap 0.5)
			(thermal_bridge_width 0.5)
			(island_removal_mode 0)
		)
		(polygon
			(pts
				(xy 147.569936 -136.975342) (xy 148.128736 -136.975342) (xy 148.128736 -138.778742) (xy 147.569936 -138.778742)
			)
		)
	)
	(zone
		(layer "In12.Cu")
		(hatch none 0.5)
		(connect_pads
			(clearance 0)
		)
		(min_thickness 0.25)
		(keepout
			(tracks not_allowed)
			(vias allowed)
			(pads allowed)
			(copperpour not_allowed)
			(footprints allowed)
		)
		(placement
			(enabled no)
			(sheetname "")
		)
		(fill
			(thermal_gap 0.5)
			(thermal_bridge_width 0.5)
			(island_removal_mode 0)
		)
		(polygon
			(pts
				(xy 47.270162 -19.322542) (xy 47.828962 -19.322542) (xy 47.828962 -21.125942) (xy 47.270162 -21.125942)
			)
		)
	)
	(zone
		(layer "In12.Cu")
		(hatch none 0.5)
		(connect_pads
			(clearance 0)
		)
		(min_thickness 0.25)
		(keepout
			(tracks not_allowed)
			(vias allowed)
			(pads allowed)
			(copperpour not_allowed)
			(footprints allowed)
		)
		(placement
			(enabled no)
			(sheetname "")
		)
		(fill
			(thermal_gap 0.5)
			(thermal_bridge_width 0.5)
			(island_removal_mode 0)
		)
		(polygon
			(pts
				(xy 61.719968 -19.322542) (xy 62.278768 -19.322542) (xy 62.278768 -21.125942) (xy 61.719968 -21.125942)
			)
		)
	)
	(zone
		(layer "In12.Cu")
		(hatch none 0.5)
		(connect_pads
			(clearance 0)
		)
		(min_thickness 0.25)
		(keepout
			(tracks not_allowed)
			(vias allowed)
			(pads allowed)
			(copperpour not_allowed)
			(footprints allowed)
		)
		(placement
			(enabled no)
			(sheetname "")
		)
		(fill
			(thermal_gap 0.5)
			(thermal_bridge_width 0.5)
			(island_removal_mode 0)
		)
		(polygon
			(pts
				(xy 463.5754 -51.289458) (xy 464.0834 -51.289458) (xy 464.0834 -52.686458) (xy 463.5754 -52.686458)
			)
		)
	)
	(zone
		(layer "In12.Cu")
		(hatch none 0.5)
		(connect_pads
			(clearance 0)
		)
		(min_thickness 0.25)
		(keepout
			(tracks not_allowed)
			(vias allowed)
			(pads allowed)
			(copperpour not_allowed)
			(footprints allowed)
		)
		(placement
			(enabled no)
			(sheetname "")
		)
		(fill
			(thermal_gap 0.5)
			(thermal_bridge_width 0.5)
			(island_removal_mode 0)
		)
		(polygon
			(pts
				(xy 149.269958 -9.721342) (xy 149.828758 -9.721342) (xy 149.828758 -11.524742) (xy 149.269958 -11.524742)
			)
		)
	)
	(zone
		(layer "In12.Cu")
		(hatch none 0.5)
		(connect_pads
			(clearance 0)
		)
		(min_thickness 0.25)
		(keepout
			(tracks not_allowed)
			(vias allowed)
			(pads allowed)
			(copperpour not_allowed)
			(footprints allowed)
		)
		(placement
			(enabled no)
			(sheetname "")
		)
		(fill
			(thermal_gap 0.5)
			(thermal_bridge_width 0.5)
			(island_removal_mode 0)
		)
		(polygon
			(pts
				(xy 250.520454 -19.322542) (xy 251.079254 -19.322542) (xy 251.079254 -21.125942) (xy 250.520454 -21.125942)
			)
		)
	)
	(zone
		(layer "In12.Cu")
		(hatch none 0.5)
		(connect_pads
			(clearance 0)
		)
		(min_thickness 0.25)
		(keepout
			(tracks not_allowed)
			(vias allowed)
			(pads allowed)
			(copperpour not_allowed)
			(footprints allowed)
		)
		(placement
			(enabled no)
			(sheetname "")
		)
		(fill
			(thermal_gap 0.5)
			(thermal_bridge_width 0.5)
			(island_removal_mode 0)
		)
		(polygon
			(pts
				(xy 119.519954 -146.576542) (xy 120.078754 -146.576542) (xy 120.078754 -148.379942) (xy 119.519954 -148.379942)
			)
		)
	)
	(zone
		(layer "In12.Cu")
		(hatch none 0.5)
		(connect_pads
			(clearance 0)
		)
		(min_thickness 0.25)
		(keepout
			(tracks not_allowed)
			(vias allowed)
			(pads allowed)
			(copperpour not_allowed)
			(footprints allowed)
		)
		(placement
			(enabled no)
			(sheetname "")
		)
		(fill
			(thermal_gap 0.5)
			(thermal_bridge_width 0.5)
			(island_removal_mode 0)
		)
		(polygon
			(pts
				(xy 228.420422 -0.120142) (xy 228.979222 -0.120142) (xy 228.979222 -1.923542) (xy 228.420422 -1.923542)
			)
		)
	)
	(zone
		(layer "In12.Cu")
		(hatch none 0.5)
		(connect_pads
			(clearance 0)
		)
		(min_thickness 0.25)
		(keepout
			(tracks not_allowed)
			(vias allowed)
			(pads allowed)
			(copperpour not_allowed)
			(footprints allowed)
		)
		(placement
			(enabled no)
			(sheetname "")
		)
		(fill
			(thermal_gap 0.5)
			(thermal_bridge_width 0.5)
			(island_removal_mode 0)
		)
		(polygon
			(pts
				(xy 33.669986 -0.120142) (xy 34.228786 -0.120142) (xy 34.228786 -1.923542) (xy 33.669986 -1.923542)
			)
		)
	)
	(zone
		(layer "In12.Cu")
		(hatch none 0.5)
		(connect_pads
			(clearance 0)
		)
		(min_thickness 0.25)
		(keepout
			(tracks not_allowed)
			(vias allowed)
			(pads allowed)
			(copperpour not_allowed)
			(footprints allowed)
		)
		(placement
			(enabled no)
			(sheetname "")
		)
		(fill
			(thermal_gap 0.5)
			(thermal_bridge_width 0.5)
			(island_removal_mode 0)
		)
		(polygon
			(pts
				(xy 40.470074 -4.720082) (xy 41.028874 -4.720082) (xy 41.028874 -6.523482) (xy 40.470074 -6.523482)
			)
		)
	)
	(zone
		(layer "In12.Cu")
		(hatch none 0.5)
		(connect_pads
			(clearance 0)
		)
		(min_thickness 0.25)
		(keepout
			(tracks not_allowed)
			(vias allowed)
			(pads allowed)
			(copperpour not_allowed)
			(footprints allowed)
		)
		(placement
			(enabled no)
			(sheetname "")
		)
		(fill
			(thermal_gap 0.5)
			(thermal_bridge_width 0.5)
			(island_removal_mode 0)
		)
		(polygon
			(pts
				(xy 136.51992 -131.974082) (xy 137.07872 -131.974082) (xy 137.07872 -133.777482) (xy 136.51992 -133.777482)
			)
		)
	)
	(zone
		(layer "In12.Cu")
		(hatch none 0.5)
		(connect_pads
			(clearance 0)
		)
		(min_thickness 0.25)
		(keepout
			(tracks not_allowed)
			(vias allowed)
			(pads allowed)
			(copperpour not_allowed)
			(footprints allowed)
		)
		(placement
			(enabled no)
			(sheetname "")
		)
		(fill
			(thermal_gap 0.5)
			(thermal_bridge_width 0.5)
			(island_removal_mode 0)
		)
		(polygon
			(pts
				(xy 88.920066 -131.974082) (xy 89.478866 -131.974082) (xy 89.478866 -133.777482) (xy 88.920066 -133.777482)
			)
		)
	)
	(zone
		(layer "In12.Cu")
		(hatch none 0.5)
		(connect_pads
			(clearance 0)
		)
		(min_thickness 0.25)
		(keepout
			(tracks not_allowed)
			(vias allowed)
			(pads allowed)
			(copperpour not_allowed)
			(footprints allowed)
		)
		(placement
			(enabled no)
			(sheetname "")
		)
		(fill
			(thermal_gap 0.5)
			(thermal_bridge_width 0.5)
			(island_removal_mode 0)
		)
		(polygon
			(pts
				(xy 13.58646 -106.34218) (xy 14.98346 -106.34218) (xy 14.98346 -106.85018) (xy 13.58646 -106.85018)
			)
		)
	)
	(zone
		(layer "In12.Cu")
		(hatch none 0.5)
		(connect_pads
			(clearance 0)
		)
		(min_thickness 0.25)
		(keepout
			(tracks not_allowed)
			(vias allowed)
			(pads allowed)
			(copperpour not_allowed)
			(footprints allowed)
		)
		(placement
			(enabled no)
			(sheetname "")
		)
		(fill
			(thermal_gap 0.5)
			(thermal_bridge_width 0.5)
			(island_removal_mode 0)
		)
		(polygon
			(pts
				(xy 35.370008 -141.575282) (xy 35.928808 -141.575282) (xy 35.928808 -143.378682) (xy 35.370008 -143.378682)
			)
		)
	)
	(zone
		(layer "In12.Cu")
		(hatch none 0.5)
		(connect_pads
			(clearance 0)
		)
		(min_thickness 0.25)
		(keepout
			(tracks not_allowed)
			(vias allowed)
			(pads allowed)
			(copperpour not_allowed)
			(footprints allowed)
		)
		(placement
			(enabled no)
			(sheetname "")
		)
		(fill
			(thermal_gap 0.5)
			(thermal_bridge_width 0.5)
			(island_removal_mode 0)
		)
		(polygon
			(pts
				(xy 410.1592 -141.6558) (xy 410.1592 -142.4178) (xy 411.1498 -142.4178) (xy 411.1498 -141.6558)
			)
		)
	)
	(zone
		(layer "In12.Cu")
		(hatch none 0.5)
		(connect_pads
			(clearance 0)
		)
		(min_thickness 0.25)
		(keepout
			(tracks not_allowed)
			(vias allowed)
			(pads allowed)
			(copperpour not_allowed)
			(footprints allowed)
		)
		(placement
			(enabled no)
			(sheetname "")
		)
		(fill
			(thermal_gap 0.5)
			(thermal_bridge_width 0.5)
			(island_removal_mode 0)
		)
		(polygon
			(pts
				(xy 122.919998 -127.374142) (xy 123.478798 -127.374142) (xy 123.478798 -129.177542) (xy 122.919998 -129.177542)
			)
		)
	)
	(zone
		(layer "In12.Cu")
		(hatch none 0.5)
		(connect_pads
			(clearance 0)
		)
		(min_thickness 0.25)
		(keepout
			(tracks not_allowed)
			(vias allowed)
			(pads allowed)
			(copperpour not_allowed)
			(footprints allowed)
		)
		(placement
			(enabled no)
			(sheetname "")
		)
		(fill
			(thermal_gap 0.5)
			(thermal_bridge_width 0.5)
			(island_removal_mode 0)
		)
		(polygon
			(pts
				(xy 281.120342 -14.321282) (xy 281.679142 -14.321282) (xy 281.679142 -16.124682) (xy 281.120342 -16.124682)
			)
		)
	)
	(zone
		(layer "In12.Cu")
		(hatch none 0.5)
		(connect_pads
			(clearance 0)
		)
		(min_thickness 0.25)
		(keepout
			(tracks not_allowed)
			(vias allowed)
			(pads allowed)
			(copperpour not_allowed)
			(footprints allowed)
		)
		(placement
			(enabled no)
			(sheetname "")
		)
		(fill
			(thermal_gap 0.5)
			(thermal_bridge_width 0.5)
			(island_removal_mode 0)
		)
		(polygon
			(pts
				(xy 286.220408 -19.322542) (xy 286.779208 -19.322542) (xy 286.779208 -21.125942) (xy 286.220408 -21.125942)
			)
		)
	)
	(zone
		(layer "In12.Cu")
		(hatch none 0.5)
		(connect_pads
			(clearance 0)
		)
		(min_thickness 0.25)
		(keepout
			(tracks not_allowed)
			(vias allowed)
			(pads allowed)
			(copperpour not_allowed)
			(footprints allowed)
		)
		(placement
			(enabled no)
			(sheetname "")
		)
		(fill
			(thermal_gap 0.5)
			(thermal_bridge_width 0.5)
			(island_removal_mode 0)
		)
		(polygon
			(pts
				(xy 242.870482 -131.974082) (xy 243.429282 -131.974082) (xy 243.429282 -133.777482) (xy 242.870482 -133.777482)
			)
		)
	)
	(zone
		(layer "In12.Cu")
		(hatch none 0.5)
		(connect_pads
			(clearance 0)
		)
		(min_thickness 0.25)
		(keepout
			(tracks not_allowed)
			(vias allowed)
			(pads allowed)
			(copperpour not_allowed)
			(footprints allowed)
		)
		(placement
			(enabled no)
			(sheetname "")
		)
		(fill
			(thermal_gap 0.5)
			(thermal_bridge_width 0.5)
			(island_removal_mode 0)
		)
		(polygon
			(pts
				(xy 54.920134 -127.374142) (xy 55.478934 -127.374142) (xy 55.478934 -129.177542) (xy 54.920134 -129.177542)
			)
		)
	)
	(zone
		(layer "In12.Cu")
		(hatch none 0.5)
		(connect_pads
			(clearance 0)
		)
		(min_thickness 0.25)
		(keepout
			(tracks not_allowed)
			(vias allowed)
			(pads allowed)
			(copperpour not_allowed)
			(footprints allowed)
		)
		(placement
			(enabled no)
			(sheetname "")
		)
		(fill
			(thermal_gap 0.5)
			(thermal_bridge_width 0.5)
			(island_removal_mode 0)
		)
		(polygon
			(pts
				(xy 40.470074 -14.321282) (xy 41.028874 -14.321282) (xy 41.028874 -16.124682) (xy 40.470074 -16.124682)
			)
		)
	)
	(zone
		(layer "In12.Cu")
		(hatch none 0.5)
		(connect_pads
			(clearance 0)
		)
		(min_thickness 0.25)
		(keepout
			(tracks not_allowed)
			(vias allowed)
			(pads allowed)
			(copperpour not_allowed)
			(footprints allowed)
		)
		(placement
			(enabled no)
			(sheetname "")
		)
		(fill
			(thermal_gap 0.5)
			(thermal_bridge_width 0.5)
			(island_removal_mode 0)
		)
		(polygon
			(pts
				(xy 86.37016 -23.922482) (xy 86.92896 -23.922482) (xy 86.92896 -25.725882) (xy 86.37016 -25.725882)
			)
		)
	)
	(zone
		(layer "In12.Cu")
		(hatch none 0.5)
		(connect_pads
			(clearance 0)
		)
		(min_thickness 0.25)
		(keepout
			(tracks not_allowed)
			(vias allowed)
			(pads allowed)
			(copperpour not_allowed)
			(footprints allowed)
		)
		(placement
			(enabled no)
			(sheetname "")
		)
		(fill
			(thermal_gap 0.5)
			(thermal_bridge_width 0.5)
			(island_removal_mode 0)
		)
		(polygon
			(pts
				(xy 252.220476 -131.974082) (xy 252.779276 -131.974082) (xy 252.779276 -133.777482) (xy 252.220476 -133.777482)
			)
		)
	)
	(zone
		(layer "In12.Cu")
		(hatch none 0.5)
		(connect_pads
			(clearance 0)
		)
		(min_thickness 0.25)
		(keepout
			(tracks not_allowed)
			(vias allowed)
			(pads allowed)
			(copperpour not_allowed)
			(footprints allowed)
		)
		(placement
			(enabled no)
			(sheetname "")
		)
		(fill
			(thermal_gap 0.5)
			(thermal_bridge_width 0.5)
			(island_removal_mode 0)
		)
		(polygon
			(pts
				(xy 270.07058 -131.974082) (xy 270.62938 -131.974082) (xy 270.62938 -133.777482) (xy 270.07058 -133.777482)
			)
		)
	)
	(zone
		(layer "In12.Cu")
		(hatch none 0.5)
		(connect_pads
			(clearance 0)
		)
		(min_thickness 0.25)
		(keepout
			(tracks not_allowed)
			(vias allowed)
			(pads allowed)
			(copperpour not_allowed)
			(footprints allowed)
		)
		(placement
			(enabled no)
			(sheetname "")
		)
		(fill
			(thermal_gap 0.5)
			(thermal_bridge_width 0.5)
			(island_removal_mode 0)
		)
		(polygon
			(pts
				(xy 199.520556 -23.922482) (xy 200.079356 -23.922482) (xy 200.079356 -25.725882) (xy 199.520556 -25.725882)
			)
		)
	)
	(zone
		(layer "In12.Cu")
		(hatch none 0.5)
		(connect_pads
			(clearance 0)
		)
		(min_thickness 0.25)
		(keepout
			(tracks not_allowed)
			(vias allowed)
			(pads allowed)
			(copperpour not_allowed)
			(footprints allowed)
		)
		(placement
			(enabled no)
			(sheetname "")
		)
		(fill
			(thermal_gap 0.5)
			(thermal_bridge_width 0.5)
			(island_removal_mode 0)
		)
		(polygon
			(pts
				(xy 103.370126 -23.922482) (xy 103.928926 -23.922482) (xy 103.928926 -25.725882) (xy 103.370126 -25.725882)
			)
		)
	)
	(zone
		(layer "In12.Cu")
		(hatch none 0.5)
		(connect_pads
			(clearance 0)
		)
		(min_thickness 0.25)
		(keepout
			(tracks not_allowed)
			(vias allowed)
			(pads allowed)
			(copperpour not_allowed)
			(footprints allowed)
		)
		(placement
			(enabled no)
			(sheetname "")
		)
		(fill
			(thermal_gap 0.5)
			(thermal_bridge_width 0.5)
			(island_removal_mode 0)
		)
		(polygon
			(pts
				(xy 234.370372 -127.374142) (xy 234.929172 -127.374142) (xy 234.929172 -129.177542) (xy 234.370372 -129.177542)
			)
		)
	)
	(zone
		(layer "In12.Cu")
		(hatch none 0.5)
		(connect_pads
			(clearance 0)
		)
		(min_thickness 0.25)
		(keepout
			(tracks not_allowed)
			(vias allowed)
			(pads allowed)
			(copperpour not_allowed)
			(footprints allowed)
		)
		(placement
			(enabled no)
			(sheetname "")
		)
		(fill
			(thermal_gap 0.5)
			(thermal_bridge_width 0.5)
			(island_removal_mode 0)
		)
		(polygon
			(pts
				(xy 273.47037 -0.120142) (xy 274.02917 -0.120142) (xy 274.02917 -1.923542) (xy 273.47037 -1.923542)
			)
		)
	)
	(zone
		(layer "In12.Cu")
		(hatch none 0.5)
		(connect_pads
			(clearance 0)
		)
		(min_thickness 0.25)
		(keepout
			(tracks not_allowed)
			(vias allowed)
			(pads allowed)
			(copperpour not_allowed)
			(footprints allowed)
		)
		(placement
			(enabled no)
			(sheetname "")
		)
		(fill
			(thermal_gap 0.5)
			(thermal_bridge_width 0.5)
			(island_removal_mode 0)
		)
		(polygon
			(pts
				(xy 116.11991 -23.922482) (xy 116.67871 -23.922482) (xy 116.67871 -25.725882) (xy 116.11991 -25.725882)
			)
		)
	)
	(zone
		(layer "In12.Cu")
		(hatch none 0.5)
		(connect_pads
			(clearance 0)
		)
		(min_thickness 0.25)
		(keepout
			(tracks not_allowed)
			(vias allowed)
			(pads allowed)
			(copperpour not_allowed)
			(footprints allowed)
		)
		(placement
			(enabled no)
			(sheetname "")
		)
		(fill
			(thermal_gap 0.5)
			(thermal_bridge_width 0.5)
			(island_removal_mode 0)
		)
		(polygon
			(pts
				(xy 202.9206 -146.576542) (xy 203.4794 -146.576542) (xy 203.4794 -148.379942) (xy 202.9206 -148.379942)
			)
		)
	)
	(zone
		(layer "In12.Cu")
		(hatch none 0.5)
		(connect_pads
			(clearance 0)
		)
		(min_thickness 0.25)
		(keepout
			(tracks not_allowed)
			(vias allowed)
			(pads allowed)
			(copperpour not_allowed)
			(footprints allowed)
		)
		(placement
			(enabled no)
			(sheetname "")
		)
		(fill
			(thermal_gap 0.5)
			(thermal_bridge_width 0.5)
			(island_removal_mode 0)
		)
		(polygon
			(pts
				(xy 86.37016 -151.176482) (xy 86.92896 -151.176482) (xy 86.92896 -152.979882) (xy 86.37016 -152.979882)
			)
		)
	)
	(zone
		(layer "In12.Cu")
		(hatch none 0.5)
		(connect_pads
			(clearance 0)
		)
		(min_thickness 0.25)
		(keepout
			(tracks not_allowed)
			(vias allowed)
			(pads allowed)
			(copperpour not_allowed)
			(footprints allowed)
		)
		(placement
			(enabled no)
			(sheetname "")
		)
		(fill
			(thermal_gap 0.5)
			(thermal_bridge_width 0.5)
			(island_removal_mode 0)
		)
		(polygon
			(pts
				(xy 312.570368 -136.975342) (xy 313.129168 -136.975342) (xy 313.129168 -138.778742) (xy 312.570368 -138.778742)
			)
		)
	)
	(zone
		(layer "In12.Cu")
		(hatch none 0.5)
		(connect_pads
			(clearance 0)
		)
		(min_thickness 0.25)
		(keepout
			(tracks not_allowed)
			(vias allowed)
			(pads allowed)
			(copperpour not_allowed)
			(footprints allowed)
		)
		(placement
			(enabled no)
			(sheetname "")
		)
		(fill
			(thermal_gap 0.5)
			(thermal_bridge_width 0.5)
			(island_removal_mode 0)
		)
		(polygon
			(pts
				(xy 72.769984 -131.974082) (xy 73.328784 -131.974082) (xy 73.328784 -133.777482) (xy 72.769984 -133.777482)
			)
		)
	)
	(zone
		(layer "In12.Cu")
		(hatch none 0.5)
		(connect_pads
			(clearance 0)
		)
		(min_thickness 0.25)
		(keepout
			(tracks not_allowed)
			(vias allowed)
			(pads allowed)
			(copperpour not_allowed)
			(footprints allowed)
		)
		(placement
			(enabled no)
			(sheetname "")
		)
		(fill
			(thermal_gap 0.5)
			(thermal_bridge_width 0.5)
			(island_removal_mode 0)
		)
		(polygon
			(pts
				(xy 264.970514 -19.322542) (xy 265.529314 -19.322542) (xy 265.529314 -21.125942) (xy 264.970514 -21.125942)
			)
		)
	)
	(zone
		(layer "In12.Cu")
		(hatch none 0.5)
		(connect_pads
			(clearance 0)
		)
		(min_thickness 0.25)
		(keepout
			(tracks not_allowed)
			(vias allowed)
			(pads allowed)
			(copperpour not_allowed)
			(footprints allowed)
		)
		(placement
			(enabled no)
			(sheetname "")
		)
		(fill
			(thermal_gap 0.5)
			(thermal_bridge_width 0.5)
			(island_removal_mode 0)
		)
		(polygon
			(pts
				(xy 238.620554 -19.322542) (xy 239.179354 -19.322542) (xy 239.179354 -21.125942) (xy 238.620554 -21.125942)
			)
		)
	)
	(zone
		(layer "In12.Cu")
		(hatch none 0.5)
		(connect_pads
			(clearance 0)
		)
		(min_thickness 0.25)
		(keepout
			(tracks not_allowed)
			(vias allowed)
			(pads allowed)
			(copperpour not_allowed)
			(footprints allowed)
		)
		(placement
			(enabled no)
			(sheetname "")
		)
		(fill
			(thermal_gap 0.5)
			(thermal_bridge_width 0.5)
			(island_removal_mode 0)
		)
		(polygon
			(pts
				(xy 362.925614 -125.812042) (xy 360.639614 -125.812042) (xy 360.639614 -125.304042) (xy 362.925614 -125.304042)
			)
		)
	)
	(zone
		(layer "In12.Cu")
		(hatch none 0.5)
		(connect_pads
			(clearance 0)
		)
		(min_thickness 0.25)
		(keepout
			(tracks not_allowed)
			(vias allowed)
			(pads allowed)
			(copperpour not_allowed)
			(footprints allowed)
		)
		(placement
			(enabled no)
			(sheetname "")
		)
		(fill
			(thermal_gap 0.5)
			(thermal_bridge_width 0.5)
			(island_removal_mode 0)
		)
		(polygon
			(pts
				(xy 101.670104 -146.576542) (xy 102.228904 -146.576542) (xy 102.228904 -148.379942) (xy 101.670104 -148.379942)
			)
		)
	)
	(zone
		(layer "In12.Cu")
		(hatch none 0.5)
		(connect_pads
			(clearance 0)
		)
		(min_thickness 0.25)
		(keepout
			(tracks not_allowed)
			(vias allowed)
			(pads allowed)
			(copperpour not_allowed)
			(footprints allowed)
		)
		(placement
			(enabled no)
			(sheetname "")
		)
		(fill
			(thermal_gap 0.5)
			(thermal_bridge_width 0.5)
			(island_removal_mode 0)
		)
		(polygon
			(pts
				(xy 205.470506 -23.922482) (xy 206.029306 -23.922482) (xy 206.029306 -25.725882) (xy 205.470506 -25.725882)
			)
		)
	)
	(zone
		(layer "In12.Cu")
		(hatch none 0.5)
		(connect_pads
			(clearance 0)
		)
		(min_thickness 0.25)
		(keepout
			(tracks not_allowed)
			(vias allowed)
			(pads allowed)
			(copperpour not_allowed)
			(footprints allowed)
		)
		(placement
			(enabled no)
			(sheetname "")
		)
		(fill
			(thermal_gap 0.5)
			(thermal_bridge_width 0.5)
			(island_removal_mode 0)
		)
		(polygon
			(pts
				(xy 202.9206 -19.322542) (xy 203.4794 -19.322542) (xy 203.4794 -21.125942) (xy 202.9206 -21.125942)
			)
		)
	)
	(zone
		(layer "In12.Cu")
		(hatch none 0.5)
		(connect_pads
			(clearance 0)
		)
		(min_thickness 0.25)
		(keepout
			(tracks not_allowed)
			(vias allowed)
			(pads allowed)
			(copperpour not_allowed)
			(footprints allowed)
		)
		(placement
			(enabled no)
			(sheetname "")
		)
		(fill
			(thermal_gap 0.5)
			(thermal_bridge_width 0.5)
			(island_removal_mode 0)
		)
		(polygon
			(pts
				(xy 271.770602 -151.176482) (xy 272.329402 -151.176482) (xy 272.329402 -152.979882) (xy 271.770602 -152.979882)
			)
		)
	)
	(zone
		(layer "In12.Cu")
		(hatch none 0.5)
		(connect_pads
			(clearance 0)
		)
		(min_thickness 0.25)
		(keepout
			(tracks not_allowed)
			(vias allowed)
			(pads allowed)
			(copperpour not_allowed)
			(footprints allowed)
		)
		(placement
			(enabled no)
			(sheetname "")
		)
		(fill
			(thermal_gap 0.5)
			(thermal_bridge_width 0.5)
			(island_removal_mode 0)
		)
		(polygon
			(pts
				(xy 293.87038 -146.576542) (xy 294.42918 -146.576542) (xy 294.42918 -148.379942) (xy 293.87038 -148.379942)
			)
		)
	)
	(zone
		(layer "In12.Cu")
		(hatch none 0.5)
		(connect_pads
			(clearance 0)
		)
		(min_thickness 0.25)
		(keepout
			(tracks not_allowed)
			(vias allowed)
			(pads allowed)
			(copperpour not_allowed)
			(footprints allowed)
		)
		(placement
			(enabled no)
			(sheetname "")
		)
		(fill
			(thermal_gap 0.5)
			(thermal_bridge_width 0.5)
			(island_removal_mode 0)
		)
		(polygon
			(pts
				(xy 52.369974 -146.576542) (xy 52.928774 -146.576542) (xy 52.928774 -148.379942) (xy 52.369974 -148.379942)
			)
		)
	)
	(zone
		(layer "In12.Cu")
		(hatch none 0.5)
		(connect_pads
			(clearance 0)
		)
		(min_thickness 0.25)
		(keepout
			(tracks not_allowed)
			(vias allowed)
			(pads allowed)
			(copperpour not_allowed)
			(footprints allowed)
		)
		(placement
			(enabled no)
			(sheetname "")
		)
		(fill
			(thermal_gap 0.5)
			(thermal_bridge_width 0.5)
			(island_removal_mode 0)
		)
		(polygon
			(pts
				(xy 242.020852 -0.120142) (xy 242.579652 -0.120142) (xy 242.579652 -1.923542) (xy 242.020852 -1.923542)
			)
		)
	)
	(zone
		(layer "In12.Cu")
		(hatch none 0.5)
		(connect_pads
			(clearance 0)
		)
		(min_thickness 0.25)
		(keepout
			(tracks not_allowed)
			(vias allowed)
			(pads allowed)
			(copperpour not_allowed)
			(footprints allowed)
		)
		(placement
			(enabled no)
			(sheetname "")
		)
		(fill
			(thermal_gap 0.5)
			(thermal_bridge_width 0.5)
			(island_removal_mode 0)
		)
		(polygon
			(pts
				(xy 35.370008 -146.576542) (xy 35.928808 -146.576542) (xy 35.928808 -148.379942) (xy 35.370008 -148.379942)
			)
		)
	)
	(zone
		(layer "In12.Cu")
		(hatch none 0.5)
		(connect_pads
			(clearance 0)
		)
		(min_thickness 0.25)
		(keepout
			(tracks not_allowed)
			(vias allowed)
			(pads allowed)
			(copperpour not_allowed)
			(footprints allowed)
		)
		(placement
			(enabled no)
			(sheetname "")
		)
		(fill
			(thermal_gap 0.5)
			(thermal_bridge_width 0.5)
			(island_removal_mode 0)
		)
		(polygon
			(pts
				(xy 128.020064 -146.576542) (xy 128.578864 -146.576542) (xy 128.578864 -148.379942) (xy 128.020064 -148.379942)
			)
		)
	)
	(zone
		(layer "In12.Cu")
		(hatch none 0.5)
		(connect_pads
			(clearance 0)
		)
		(min_thickness 0.25)
		(keepout
			(tracks not_allowed)
			(vias allowed)
			(pads allowed)
			(copperpour not_allowed)
			(footprints allowed)
		)
		(placement
			(enabled no)
			(sheetname "")
		)
		(fill
			(thermal_gap 0.5)
			(thermal_bridge_width 0.5)
			(island_removal_mode 0)
		)
		(polygon
			(pts
				(xy 132.269992 -9.721342) (xy 132.828792 -9.721342) (xy 132.828792 -11.524742) (xy 132.269992 -11.524742)
			)
		)
	)
	(zone
		(layer "In12.Cu")
		(hatch none 0.5)
		(connect_pads
			(clearance 0)
		)
		(min_thickness 0.25)
		(keepout
			(tracks not_allowed)
			(vias allowed)
			(pads allowed)
			(copperpour not_allowed)
			(footprints allowed)
		)
		(placement
			(enabled no)
			(sheetname "")
		)
		(fill
			(thermal_gap 0.5)
			(thermal_bridge_width 0.5)
			(island_removal_mode 0)
		)
		(polygon
			(pts
				(xy 88.920066 -14.321282) (xy 89.478866 -14.321282) (xy 89.478866 -16.124682) (xy 88.920066 -16.124682)
			)
		)
	)
	(zone
		(layer "In12.Cu")
		(hatch none 0.5)
		(connect_pads
			(clearance 0)
		)
		(min_thickness 0.25)
		(keepout
			(tracks not_allowed)
			(vias allowed)
			(pads allowed)
			(copperpour not_allowed)
			(footprints allowed)
		)
		(placement
			(enabled no)
			(sheetname "")
		)
		(fill
			(thermal_gap 0.5)
			(thermal_bridge_width 0.5)
			(island_removal_mode 0)
		)
		(polygon
			(pts
				(xy 43.01998 -9.721342) (xy 43.57878 -9.721342) (xy 43.57878 -11.524742) (xy 43.01998 -11.524742)
			)
		)
	)
	(zone
		(layer "In12.Cu")
		(hatch none 0.5)
		(connect_pads
			(clearance 0)
		)
		(min_thickness 0.25)
		(keepout
			(tracks not_allowed)
			(vias allowed)
			(pads allowed)
			(copperpour not_allowed)
			(footprints allowed)
		)
		(placement
			(enabled no)
			(sheetname "")
		)
		(fill
			(thermal_gap 0.5)
			(thermal_bridge_width 0.5)
			(island_removal_mode 0)
		)
		(polygon
			(pts
				(xy 40.470074 -141.575282) (xy 41.028874 -141.575282) (xy 41.028874 -143.378682) (xy 40.470074 -143.378682)
			)
		)
	)
	(zone
		(layer "In12.Cu")
		(hatch none 0.5)
		(connect_pads
			(clearance 0)
		)
		(min_thickness 0.25)
		(keepout
			(tracks not_allowed)
			(vias allowed)
			(pads allowed)
			(copperpour not_allowed)
			(footprints allowed)
		)
		(placement
			(enabled no)
			(sheetname "")
		)
		(fill
			(thermal_gap 0.5)
			(thermal_bridge_width 0.5)
			(island_removal_mode 0)
		)
		(polygon
			(pts
				(xy 268.370558 -131.974082) (xy 268.929358 -131.974082) (xy 268.929358 -133.777482) (xy 268.370558 -133.777482)
			)
		)
	)
	(zone
		(layer "In12.Cu")
		(hatch none 0.5)
		(connect_pads
			(clearance 0)
		)
		(min_thickness 0.25)
		(keepout
			(tracks not_allowed)
			(vias allowed)
			(pads allowed)
			(copperpour not_allowed)
			(footprints allowed)
		)
		(placement
			(enabled no)
			(sheetname "")
		)
		(fill
			(thermal_gap 0.5)
			(thermal_bridge_width 0.5)
			(island_removal_mode 0)
		)
		(polygon
			(pts
				(xy 124.62002 -127.374142) (xy 125.17882 -127.374142) (xy 125.17882 -129.177542) (xy 124.62002 -129.177542)
			)
		)
	)
	(zone
		(layer "In12.Cu")
		(hatch none 0.5)
		(connect_pads
			(clearance 0)
		)
		(min_thickness 0.25)
		(keepout
			(tracks not_allowed)
			(vias allowed)
			(pads allowed)
			(copperpour not_allowed)
			(footprints allowed)
		)
		(placement
			(enabled no)
			(sheetname "")
		)
		(fill
			(thermal_gap 0.5)
			(thermal_bridge_width 0.5)
			(island_removal_mode 0)
		)
		(polygon
			(pts
				(xy 76.170282 -151.176482) (xy 76.729082 -151.176482) (xy 76.729082 -152.979882) (xy 76.170282 -152.979882)
			)
		)
	)
	(zone
		(layer "In12.Cu")
		(hatch none 0.5)
		(connect_pads
			(clearance 0)
		)
		(min_thickness 0.25)
		(keepout
			(tracks not_allowed)
			(vias allowed)
			(pads allowed)
			(copperpour not_allowed)
			(footprints allowed)
		)
		(placement
			(enabled no)
			(sheetname "")
		)
		(fill
			(thermal_gap 0.5)
			(thermal_bridge_width 0.5)
			(island_removal_mode 0)
		)
		(polygon
			(pts
				(xy 116.970048 -127.374142) (xy 117.528848 -127.374142) (xy 117.528848 -129.177542) (xy 116.970048 -129.177542)
			)
		)
	)
	(zone
		(layer "In12.Cu")
		(hatch none 0.5)
		(connect_pads
			(clearance 0)
		)
		(min_thickness 0.25)
		(keepout
			(tracks not_allowed)
			(vias allowed)
			(pads allowed)
			(copperpour not_allowed)
			(footprints allowed)
		)
		(placement
			(enabled no)
			(sheetname "")
		)
		(fill
			(thermal_gap 0.5)
			(thermal_bridge_width 0.5)
			(island_removal_mode 0)
		)
		(polygon
			(pts
				(xy 213.120478 -131.974082) (xy 213.679278 -131.974082) (xy 213.679278 -133.777482) (xy 213.120478 -133.777482)
			)
		)
	)
	(zone
		(layer "In12.Cu")
		(hatch none 0.5)
		(connect_pads
			(clearance 0)
		)
		(min_thickness 0.25)
		(keepout
			(tracks not_allowed)
			(vias allowed)
			(pads allowed)
			(copperpour not_allowed)
			(footprints allowed)
		)
		(placement
			(enabled no)
			(sheetname "")
		)
		(fill
			(thermal_gap 0.5)
			(thermal_bridge_width 0.5)
			(island_removal_mode 0)
		)
		(polygon
			(pts
				(xy 16.56842 -107.69092) (xy 17.96542 -107.69092) (xy 17.96542 -108.19892) (xy 16.56842 -108.19892)
			)
		)
	)
	(zone
		(layer "In12.Cu")
		(hatch none 0.5)
		(connect_pads
			(clearance 0)
		)
		(min_thickness 0.25)
		(keepout
			(tracks not_allowed)
			(vias allowed)
			(pads allowed)
			(copperpour not_allowed)
			(footprints allowed)
		)
		(placement
			(enabled no)
			(sheetname "")
		)
		(fill
			(thermal_gap 0.5)
			(thermal_bridge_width 0.5)
			(island_removal_mode 0)
		)
		(polygon
			(pts
				(xy 209.720434 -14.321282) (xy 210.279234 -14.321282) (xy 210.279234 -16.124682) (xy 209.720434 -16.124682)
			)
		)
	)
	(zone
		(layer "In12.Cu")
		(hatch none 0.5)
		(connect_pads
			(clearance 0)
		)
		(min_thickness 0.25)
		(keepout
			(tracks not_allowed)
			(vias allowed)
			(pads allowed)
			(copperpour not_allowed)
			(footprints allowed)
		)
		(placement
			(enabled no)
			(sheetname "")
		)
		(fill
			(thermal_gap 0.5)
			(thermal_bridge_width 0.5)
			(island_removal_mode 0)
		)
		(polygon
			(pts
				(xy 253.920498 -151.176482) (xy 254.479298 -151.176482) (xy 254.479298 -152.979882) (xy 253.920498 -152.979882)
			)
		)
	)
	(zone
		(layer "In12.Cu")
		(hatch none 0.5)
		(connect_pads
			(clearance 0)
		)
		(min_thickness 0.25)
		(keepout
			(tracks not_allowed)
			(vias allowed)
			(pads allowed)
			(copperpour not_allowed)
			(footprints allowed)
		)
		(placement
			(enabled no)
			(sheetname "")
		)
		(fill
			(thermal_gap 0.5)
			(thermal_bridge_width 0.5)
			(island_removal_mode 0)
		)
		(polygon
			(pts
				(xy 196.970396 -9.721342) (xy 197.529196 -9.721342) (xy 197.529196 -11.524742) (xy 196.970396 -11.524742)
			)
		)
	)
	(zone
		(layer "In12.Cu")
		(hatch none 0.5)
		(connect_pads
			(clearance 0)
		)
		(min_thickness 0.25)
		(keepout
			(tracks not_allowed)
			(vias allowed)
			(pads allowed)
			(copperpour not_allowed)
			(footprints allowed)
		)
		(placement
			(enabled no)
			(sheetname "")
		)
		(fill
			(thermal_gap 0.5)
			(thermal_bridge_width 0.5)
			(island_removal_mode 0)
		)
		(polygon
			(pts
				(xy 304.920396 -127.374142) (xy 305.479196 -127.374142) (xy 305.479196 -129.177542) (xy 304.920396 -129.177542)
			)
		)
	)
	(zone
		(layer "In12.Cu")
		(hatch none 0.5)
		(connect_pads
			(clearance 0)
		)
		(min_thickness 0.25)
		(keepout
			(tracks not_allowed)
			(vias allowed)
			(pads allowed)
			(copperpour not_allowed)
			(footprints allowed)
		)
		(placement
			(enabled no)
			(sheetname "")
		)
		(fill
			(thermal_gap 0.5)
			(thermal_bridge_width 0.5)
			(island_removal_mode 0)
		)
		(polygon
			(pts
				(xy 233.520488 -23.922482) (xy 234.079288 -23.922482) (xy 234.079288 -25.725882) (xy 233.520488 -25.725882)
			)
		)
	)
	(zone
		(layer "In12.Cu")
		(hatch none 0.5)
		(connect_pads
			(clearance 0)
		)
		(min_thickness 0.25)
		(keepout
			(tracks not_allowed)
			(vias allowed)
			(pads allowed)
			(copperpour not_allowed)
			(footprints allowed)
		)
		(placement
			(enabled no)
			(sheetname "")
		)
		(fill
			(thermal_gap 0.5)
			(thermal_bridge_width 0.5)
			(island_removal_mode 0)
		)
		(polygon
			(pts
				(xy 341.920068 -76.551536) (xy 341.920068 -78.837536) (xy 341.412068 -78.837536) (xy 341.412068 -76.551536)
			)
		)
	)
	(zone
		(layer "In12.Cu")
		(hatch none 0.5)
		(connect_pads
			(clearance 0)
		)
		(min_thickness 0.25)
		(keepout
			(tracks not_allowed)
			(vias allowed)
			(pads allowed)
			(copperpour not_allowed)
			(footprints allowed)
		)
		(placement
			(enabled no)
			(sheetname "")
		)
		(fill
			(thermal_gap 0.5)
			(thermal_bridge_width 0.5)
			(island_removal_mode 0)
		)
		(polygon
			(pts
				(xy 435.00675 -141.939264) (xy 435.76875 -141.939264) (xy 435.76875 -140.948664) (xy 435.00675 -140.948664)
			)
		)
	)
	(zone
		(layer "In12.Cu")
		(hatch none 0.5)
		(connect_pads
			(clearance 0)
		)
		(min_thickness 0.25)
		(keepout
			(tracks not_allowed)
			(vias allowed)
			(pads allowed)
			(copperpour not_allowed)
			(footprints allowed)
		)
		(placement
			(enabled no)
			(sheetname "")
		)
		(fill
			(thermal_gap 0.5)
			(thermal_bridge_width 0.5)
			(island_removal_mode 0)
		)
		(polygon
			(pts
				(xy 196.970396 -136.975342) (xy 197.529196 -136.975342) (xy 197.529196 -138.778742) (xy 196.970396 -138.778742)
			)
		)
	)
	(zone
		(layer "In12.Cu")
		(hatch none 0.5)
		(connect_pads
			(clearance 0)
		)
		(min_thickness 0.25)
		(keepout
			(tracks not_allowed)
			(vias allowed)
			(pads allowed)
			(copperpour not_allowed)
			(footprints allowed)
		)
		(placement
			(enabled no)
			(sheetname "")
		)
		(fill
			(thermal_gap 0.5)
			(thermal_bridge_width 0.5)
			(island_removal_mode 0)
		)
		(polygon
			(pts
				(xy 140.770102 -131.974082) (xy 141.328902 -131.974082) (xy 141.328902 -133.777482) (xy 140.770102 -133.777482)
			)
		)
	)
	(zone
		(layer "In12.Cu")
		(hatch none 0.5)
		(connect_pads
			(clearance 0)
		)
		(min_thickness 0.25)
		(keepout
			(tracks not_allowed)
			(vias allowed)
			(pads allowed)
			(copperpour not_allowed)
			(footprints allowed)
		)
		(placement
			(enabled no)
			(sheetname "")
		)
		(fill
			(thermal_gap 0.5)
			(thermal_bridge_width 0.5)
			(island_removal_mode 0)
		)
		(polygon
			(pts
				(xy 112.72012 -9.721342) (xy 113.27892 -9.721342) (xy 113.27892 -11.524742) (xy 112.72012 -11.524742)
			)
		)
	)
	(zone
		(layer "In12.Cu")
		(hatch none 0.5)
		(connect_pads
			(clearance 0)
		)
		(min_thickness 0.25)
		(keepout
			(tracks not_allowed)
			(vias allowed)
			(pads allowed)
			(copperpour not_allowed)
			(footprints allowed)
		)
		(placement
			(enabled no)
			(sheetname "")
		)
		(fill
			(thermal_gap 0.5)
			(thermal_bridge_width 0.5)
			(island_removal_mode 0)
		)
		(polygon
			(pts
				(xy 118.67007 -0.120142) (xy 119.22887 -0.120142) (xy 119.22887 -1.923542) (xy 118.67007 -1.923542)
			)
		)
	)
	(zone
		(layer "In12.Cu")
		(hatch none 0.5)
		(connect_pads
			(clearance 0)
		)
		(min_thickness 0.25)
		(keepout
			(tracks not_allowed)
			(vias allowed)
			(pads allowed)
			(copperpour not_allowed)
			(footprints allowed)
		)
		(placement
			(enabled no)
			(sheetname "")
		)
		(fill
			(thermal_gap 0.5)
			(thermal_bridge_width 0.5)
			(island_removal_mode 0)
		)
		(polygon
			(pts
				(xy 279.42032 -141.575282) (xy 279.97912 -141.575282) (xy 279.97912 -143.378682) (xy 279.42032 -143.378682)
			)
		)
	)
	(zone
		(layer "In12.Cu")
		(hatch none 0.5)
		(connect_pads
			(clearance 0)
		)
		(min_thickness 0.25)
		(keepout
			(tracks not_allowed)
			(vias allowed)
			(pads allowed)
			(copperpour not_allowed)
			(footprints allowed)
		)
		(placement
			(enabled no)
			(sheetname "")
		)
		(fill
			(thermal_gap 0.5)
			(thermal_bridge_width 0.5)
			(island_removal_mode 0)
		)
		(polygon
			(pts
				(xy 311.720484 -127.374142) (xy 312.279284 -127.374142) (xy 312.279284 -129.177542) (xy 311.720484 -129.177542)
			)
		)
	)
	(zone
		(layer "In12.Cu")
		(hatch none 0.5)
		(connect_pads
			(clearance 0)
		)
		(min_thickness 0.25)
		(keepout
			(tracks not_allowed)
			(vias allowed)
			(pads allowed)
			(copperpour not_allowed)
			(footprints allowed)
		)
		(placement
			(enabled no)
			(sheetname "")
		)
		(fill
			(thermal_gap 0.5)
			(thermal_bridge_width 0.5)
			(island_removal_mode 0)
		)
		(polygon
			(pts
				(xy 45.57014 -0.120142) (xy 46.12894 -0.120142) (xy 46.12894 -1.923542) (xy 45.57014 -1.923542)
			)
		)
	)
	(zone
		(layer "In12.Cu")
		(hatch none 0.5)
		(connect_pads
			(clearance 0)
		)
		(min_thickness 0.25)
		(keepout
			(tracks not_allowed)
			(vias allowed)
			(pads allowed)
			(copperpour not_allowed)
			(footprints allowed)
		)
		(placement
			(enabled no)
			(sheetname "")
		)
		(fill
			(thermal_gap 0.5)
			(thermal_bridge_width 0.5)
			(island_removal_mode 0)
		)
		(polygon
			(pts
				(xy 268.370558 -14.321282) (xy 268.929358 -14.321282) (xy 268.929358 -16.124682) (xy 268.370558 -16.124682)
			)
		)
	)
	(zone
		(layer "In12.Cu")
		(hatch none 0.5)
		(connect_pads
			(clearance 0)
		)
		(min_thickness 0.25)
		(keepout
			(tracks not_allowed)
			(vias allowed)
			(pads allowed)
			(copperpour not_allowed)
			(footprints allowed)
		)
		(placement
			(enabled no)
			(sheetname "")
		)
		(fill
			(thermal_gap 0.5)
			(thermal_bridge_width 0.5)
			(island_removal_mode 0)
		)
		(polygon
			(pts
				(xy 287.070546 -14.321282) (xy 287.629346 -14.321282) (xy 287.629346 -16.124682) (xy 287.070546 -16.124682)
			)
		)
	)
	(zone
		(layer "In12.Cu")
		(hatch none 0.5)
		(connect_pads
			(clearance 0)
		)
		(min_thickness 0.25)
		(keepout
			(tracks not_allowed)
			(vias allowed)
			(pads allowed)
			(copperpour not_allowed)
			(footprints allowed)
		)
		(placement
			(enabled no)
			(sheetname "")
		)
		(fill
			(thermal_gap 0.5)
			(thermal_bridge_width 0.5)
			(island_removal_mode 0)
		)
		(polygon
			(pts
				(xy 286.220408 -127.374142) (xy 286.779208 -127.374142) (xy 286.779208 -129.177542) (xy 286.220408 -129.177542)
			)
		)
	)
	(zone
		(layer "In12.Cu")
		(hatch none 0.5)
		(connect_pads
			(clearance 0)
		)
		(min_thickness 0.25)
		(keepout
			(tracks not_allowed)
			(vias allowed)
			(pads allowed)
			(copperpour not_allowed)
			(footprints allowed)
		)
		(placement
			(enabled no)
			(sheetname "")
		)
		(fill
			(thermal_gap 0.5)
			(thermal_bridge_width 0.5)
			(island_removal_mode 0)
		)
		(polygon
			(pts
				(xy 223.320356 -136.975342) (xy 223.879156 -136.975342) (xy 223.879156 -138.778742) (xy 223.320356 -138.778742)
			)
		)
	)
	(zone
		(layer "In12.Cu")
		(hatch none 0.5)
		(connect_pads
			(clearance 0)
		)
		(min_thickness 0.25)
		(keepout
			(tracks not_allowed)
			(vias allowed)
			(pads allowed)
			(copperpour not_allowed)
			(footprints allowed)
		)
		(placement
			(enabled no)
			(sheetname "")
		)
		(fill
			(thermal_gap 0.5)
			(thermal_bridge_width 0.5)
			(island_removal_mode 0)
		)
		(polygon
			(pts
				(xy 274.320508 -14.321282) (xy 274.879308 -14.321282) (xy 274.879308 -16.124682) (xy 274.320508 -16.124682)
			)
		)
	)
	(zone
		(layer "In12.Cu")
		(hatch none 0.5)
		(connect_pads
			(clearance 0)
		)
		(min_thickness 0.25)
		(keepout
			(tracks not_allowed)
			(vias allowed)
			(pads allowed)
			(copperpour not_allowed)
			(footprints allowed)
		)
		(placement
			(enabled no)
			(sheetname "")
		)
		(fill
			(thermal_gap 0.5)
			(thermal_bridge_width 0.5)
			(island_removal_mode 0)
		)
		(polygon
			(pts
				(xy 128.020064 -151.176482) (xy 128.578864 -151.176482) (xy 128.578864 -152.979882) (xy 128.020064 -152.979882)
			)
		)
	)
	(zone
		(layer "In12.Cu")
		(hatch none 0.5)
		(connect_pads
			(clearance 0)
		)
		(min_thickness 0.25)
		(keepout
			(tracks not_allowed)
			(vias allowed)
			(pads allowed)
			(copperpour not_allowed)
			(footprints allowed)
		)
		(placement
			(enabled no)
			(sheetname "")
		)
		(fill
			(thermal_gap 0.5)
			(thermal_bridge_width 0.5)
			(island_removal_mode 0)
		)
		(polygon
			(pts
				(xy 239.470438 -4.720082) (xy 240.029238 -4.720082) (xy 240.029238 -6.523482) (xy 239.470438 -6.523482)
			)
		)
	)
	(zone
		(layer "In12.Cu")
		(hatch none 0.5)
		(connect_pads
			(clearance 0)
		)
		(min_thickness 0.25)
		(keepout
			(tracks not_allowed)
			(vias allowed)
			(pads allowed)
			(copperpour not_allowed)
			(footprints allowed)
		)
		(placement
			(enabled no)
			(sheetname "")
		)
		(fill
			(thermal_gap 0.5)
			(thermal_bridge_width 0.5)
			(island_removal_mode 0)
		)
		(polygon
			(pts
				(xy 246.270526 -151.176482) (xy 246.829326 -151.176482) (xy 246.829326 -152.979882) (xy 246.270526 -152.979882)
			)
		)
	)
	(zone
		(layer "In12.Cu")
		(hatch none 0.5)
		(connect_pads
			(clearance 0)
		)
		(min_thickness 0.25)
		(keepout
			(tracks not_allowed)
			(vias allowed)
			(pads allowed)
			(copperpour not_allowed)
			(footprints allowed)
		)
		(placement
			(enabled no)
			(sheetname "")
		)
		(fill
			(thermal_gap 0.5)
			(thermal_bridge_width 0.5)
			(island_removal_mode 0)
		)
		(polygon
			(pts
				(xy 281.120342 -141.575282) (xy 281.679142 -141.575282) (xy 281.679142 -143.378682) (xy 281.120342 -143.378682)
			)
		)
	)
	(zone
		(layer "In12.Cu")
		(hatch none 0.5)
		(connect_pads
			(clearance 0)
		)
		(min_thickness 0.25)
		(keepout
			(tracks not_allowed)
			(vias allowed)
			(pads allowed)
			(copperpour not_allowed)
			(footprints allowed)
		)
		(placement
			(enabled no)
			(sheetname "")
		)
		(fill
			(thermal_gap 0.5)
			(thermal_bridge_width 0.5)
			(island_removal_mode 0)
		)
		(polygon
			(pts
				(xy 129.720086 -151.176482) (xy 130.278886 -151.176482) (xy 130.278886 -152.979882) (xy 129.720086 -152.979882)
			)
		)
	)
	(zone
		(layer "In12.Cu")
		(hatch none 0.5)
		(connect_pads
			(clearance 0)
		)
		(min_thickness 0.25)
		(keepout
			(tracks not_allowed)
			(vias allowed)
			(pads allowed)
			(copperpour not_allowed)
			(footprints allowed)
		)
		(placement
			(enabled no)
			(sheetname "")
		)
		(fill
			(thermal_gap 0.5)
			(thermal_bridge_width 0.5)
			(island_removal_mode 0)
		)
		(polygon
			(pts
				(xy 230.970582 -19.322542) (xy 231.529382 -19.322542) (xy 231.529382 -21.125942) (xy 230.970582 -21.125942)
			)
		)
	)
	(zone
		(layer "In12.Cu")
		(hatch none 0.5)
		(connect_pads
			(clearance 0)
		)
		(min_thickness 0.25)
		(keepout
			(tracks not_allowed)
			(vias allowed)
			(pads allowed)
			(copperpour not_allowed)
			(footprints allowed)
		)
		(placement
			(enabled no)
			(sheetname "")
		)
		(fill
			(thermal_gap 0.5)
			(thermal_bridge_width 0.5)
			(island_removal_mode 0)
		)
		(polygon
			(pts
				(xy 315.970412 -19.322542) (xy 316.529212 -19.322542) (xy 316.529212 -21.125942) (xy 315.970412 -21.125942)
			)
		)
	)
	(zone
		(layer "In12.Cu")
		(hatch none 0.5)
		(connect_pads
			(clearance 0)
		)
		(min_thickness 0.25)
		(keepout
			(tracks not_allowed)
			(vias allowed)
			(pads allowed)
			(copperpour not_allowed)
			(footprints allowed)
		)
		(placement
			(enabled no)
			(sheetname "")
		)
		(fill
			(thermal_gap 0.5)
			(thermal_bridge_width 0.5)
			(island_removal_mode 0)
		)
		(polygon
			(pts
				(xy 133.119876 -4.720082) (xy 133.678676 -4.720082) (xy 133.678676 -6.523482) (xy 133.119876 -6.523482)
			)
		)
	)
	(zone
		(layer "In12.Cu")
		(hatch none 0.5)
		(connect_pads
			(clearance 0)
		)
		(min_thickness 0.25)
		(keepout
			(tracks not_allowed)
			(vias allowed)
			(pads allowed)
			(copperpour not_allowed)
			(footprints allowed)
		)
		(placement
			(enabled no)
			(sheetname "")
		)
		(fill
			(thermal_gap 0.5)
			(thermal_bridge_width 0.5)
			(island_removal_mode 0)
		)
		(polygon
			(pts
				(xy 87.220044 -136.975342) (xy 87.778844 -136.975342) (xy 87.778844 -138.778742) (xy 87.220044 -138.778742)
			)
		)
	)
	(zone
		(layer "In12.Cu")
		(hatch none 0.5)
		(connect_pads
			(clearance 0)
		)
		(min_thickness 0.25)
		(keepout
			(tracks not_allowed)
			(vias allowed)
			(pads allowed)
			(copperpour not_allowed)
			(footprints allowed)
		)
		(placement
			(enabled no)
			(sheetname "")
		)
		(fill
			(thermal_gap 0.5)
			(thermal_bridge_width 0.5)
			(island_removal_mode 0)
		)
		(polygon
			(pts
				(xy 114.419888 -131.974082) (xy 114.978688 -131.974082) (xy 114.978688 -133.777482) (xy 114.419888 -133.777482)
			)
		)
	)
	(zone
		(layer "In12.Cu")
		(hatch none 0.5)
		(connect_pads
			(clearance 0)
		)
		(min_thickness 0.25)
		(keepout
			(tracks not_allowed)
			(vias allowed)
			(pads allowed)
			(copperpour not_allowed)
			(footprints allowed)
		)
		(placement
			(enabled no)
			(sheetname "")
		)
		(fill
			(thermal_gap 0.5)
			(thermal_bridge_width 0.5)
			(island_removal_mode 0)
		)
		(polygon
			(pts
				(xy 209.720434 -151.176482) (xy 210.279234 -151.176482) (xy 210.279234 -152.979882) (xy 209.720434 -152.979882)
			)
		)
	)
	(zone
		(layer "In12.Cu")
		(hatch none 0.5)
		(connect_pads
			(clearance 0)
		)
		(min_thickness 0.25)
		(keepout
			(tracks not_allowed)
			(vias allowed)
			(pads allowed)
			(copperpour not_allowed)
			(footprints allowed)
		)
		(placement
			(enabled no)
			(sheetname "")
		)
		(fill
			(thermal_gap 0.5)
			(thermal_bridge_width 0.5)
			(island_removal_mode 0)
		)
		(polygon
			(pts
				(xy 102.519988 -23.922482) (xy 103.078788 -23.922482) (xy 103.078788 -25.725882) (xy 102.519988 -25.725882)
			)
		)
	)
	(zone
		(layer "In12.Cu")
		(hatch none 0.5)
		(connect_pads
			(clearance 0)
		)
		(min_thickness 0.25)
		(keepout
			(tracks not_allowed)
			(vias allowed)
			(pads allowed)
			(copperpour not_allowed)
			(footprints allowed)
		)
		(placement
			(enabled no)
			(sheetname "")
		)
		(fill
			(thermal_gap 0.5)
			(thermal_bridge_width 0.5)
			(island_removal_mode 0)
		)
		(polygon
			(pts
				(xy 75.320144 -0.120142) (xy 75.878944 -0.120142) (xy 75.878944 -1.923542) (xy 75.320144 -1.923542)
			)
		)
	)
	(zone
		(layer "In12.Cu")
		(hatch none 0.5)
		(connect_pads
			(clearance 0)
		)
		(min_thickness 0.25)
		(keepout
			(tracks not_allowed)
			(vias allowed)
			(pads allowed)
			(copperpour not_allowed)
			(footprints allowed)
		)
		(placement
			(enabled no)
			(sheetname "")
		)
		(fill
			(thermal_gap 0.5)
			(thermal_bridge_width 0.5)
			(island_removal_mode 0)
		)
		(polygon
			(pts
				(xy 128.020064 -9.721342) (xy 128.578864 -9.721342) (xy 128.578864 -11.524742) (xy 128.020064 -11.524742)
			)
		)
	)
	(zone
		(layer "In12.Cu")
		(hatch none 0.5)
		(connect_pads
			(clearance 0)
		)
		(min_thickness 0.25)
		(keepout
			(tracks not_allowed)
			(vias allowed)
			(pads allowed)
			(copperpour not_allowed)
			(footprints allowed)
		)
		(placement
			(enabled no)
			(sheetname "")
		)
		(fill
			(thermal_gap 0.5)
			(thermal_bridge_width 0.5)
			(island_removal_mode 0)
		)
		(polygon
			(pts
				(xy 121.219976 -136.975342) (xy 121.778776 -136.975342) (xy 121.778776 -138.778742) (xy 121.219976 -138.778742)
			)
		)
	)
	(zone
		(layer "In12.Cu")
		(hatch none 0.5)
		(connect_pads
			(clearance 0)
		)
		(min_thickness 0.25)
		(keepout
			(tracks not_allowed)
			(vias allowed)
			(pads allowed)
			(copperpour not_allowed)
			(footprints allowed)
		)
		(placement
			(enabled no)
			(sheetname "")
		)
		(fill
			(thermal_gap 0.5)
			(thermal_bridge_width 0.5)
			(island_removal_mode 0)
		)
		(polygon
			(pts
				(xy 237.770416 -127.374142) (xy 238.329216 -127.374142) (xy 238.329216 -129.177542) (xy 237.770416 -129.177542)
			)
		)
	)
	(zone
		(layer "In12.Cu")
		(hatch none 0.5)
		(connect_pads
			(clearance 0)
		)
		(min_thickness 0.25)
		(keepout
			(tracks not_allowed)
			(vias allowed)
			(pads allowed)
			(copperpour not_allowed)
			(footprints allowed)
		)
		(placement
			(enabled no)
			(sheetname "")
		)
		(fill
			(thermal_gap 0.5)
			(thermal_bridge_width 0.5)
			(island_removal_mode 0)
		)
		(polygon
			(pts
				(xy 211.420456 -131.974082) (xy 211.979256 -131.974082) (xy 211.979256 -133.777482) (xy 211.420456 -133.777482)
			)
		)
	)
	(zone
		(layer "In12.Cu")
		(hatch none 0.5)
		(connect_pads
			(clearance 0)
		)
		(min_thickness 0.25)
		(keepout
			(tracks not_allowed)
			(vias allowed)
			(pads allowed)
			(copperpour not_allowed)
			(footprints allowed)
		)
		(placement
			(enabled no)
			(sheetname "")
		)
		(fill
			(thermal_gap 0.5)
			(thermal_bridge_width 0.5)
			(island_removal_mode 0)
		)
		(polygon
			(pts
				(xy 72.769984 -9.721342) (xy 73.328784 -9.721342) (xy 73.328784 -11.524742) (xy 72.769984 -11.524742)
			)
		)
	)
	(zone
		(layer "In12.Cu")
		(hatch none 0.5)
		(connect_pads
			(clearance 0)
		)
		(min_thickness 0.25)
		(keepout
			(tracks not_allowed)
			(vias allowed)
			(pads allowed)
			(copperpour not_allowed)
			(footprints allowed)
		)
		(placement
			(enabled no)
			(sheetname "")
		)
		(fill
			(thermal_gap 0.5)
			(thermal_bridge_width 0.5)
			(island_removal_mode 0)
		)
		(polygon
			(pts
				(xy 138.219942 -19.322542) (xy 138.778742 -19.322542) (xy 138.778742 -21.125942) (xy 138.219942 -21.125942)
			)
		)
	)
	(zone
		(layer "In12.Cu")
		(hatch none 0.5)
		(connect_pads
			(clearance 0)
		)
		(min_thickness 0.25)
		(keepout
			(tracks not_allowed)
			(vias allowed)
			(pads allowed)
			(copperpour not_allowed)
			(footprints allowed)
		)
		(placement
			(enabled no)
			(sheetname "")
		)
		(fill
			(thermal_gap 0.5)
			(thermal_bridge_width 0.5)
			(island_removal_mode 0)
		)
		(polygon
			(pts
				(xy 221.620588 -136.975342) (xy 222.179388 -136.975342) (xy 222.179388 -138.778742) (xy 221.620588 -138.778742)
			)
		)
	)
	(zone
		(layer "In12.Cu")
		(hatch none 0.5)
		(connect_pads
			(clearance 0)
		)
		(min_thickness 0.25)
		(keepout
			(tracks not_allowed)
			(vias allowed)
			(pads allowed)
			(copperpour not_allowed)
			(footprints allowed)
		)
		(placement
			(enabled no)
			(sheetname "")
		)
		(fill
			(thermal_gap 0.5)
			(thermal_bridge_width 0.5)
			(island_removal_mode 0)
		)
		(polygon
			(pts
				(xy 108.469938 -136.975342) (xy 109.028738 -136.975342) (xy 109.028738 -138.778742) (xy 108.469938 -138.778742)
			)
		)
	)
	(zone
		(layer "In12.Cu")
		(hatch none 0.5)
		(connect_pads
			(clearance 0)
		)
		(min_thickness 0.25)
		(keepout
			(tracks not_allowed)
			(vias allowed)
			(pads allowed)
			(copperpour not_allowed)
			(footprints allowed)
		)
		(placement
			(enabled no)
			(sheetname "")
		)
		(fill
			(thermal_gap 0.5)
			(thermal_bridge_width 0.5)
			(island_removal_mode 0)
		)
		(polygon
			(pts
				(xy 201.220578 -9.721342) (xy 201.779378 -9.721342) (xy 201.779378 -11.524742) (xy 201.220578 -11.524742)
			)
		)
	)
	(zone
		(layer "In12.Cu")
		(hatch none 0.5)
		(connect_pads
			(clearance 0)
		)
		(min_thickness 0.25)
		(keepout
			(tracks not_allowed)
			(vias allowed)
			(pads allowed)
			(copperpour not_allowed)
			(footprints allowed)
		)
		(placement
			(enabled no)
			(sheetname "")
		)
		(fill
			(thermal_gap 0.5)
			(thermal_bridge_width 0.5)
			(island_removal_mode 0)
		)
		(polygon
			(pts
				(xy 107.620054 -141.575282) (xy 108.178854 -141.575282) (xy 108.178854 -143.378682) (xy 107.620054 -143.378682)
			)
		)
	)
	(zone
		(layer "In12.Cu")
		(hatch none 0.5)
		(connect_pads
			(clearance 0)
		)
		(min_thickness 0.25)
		(keepout
			(tracks not_allowed)
			(vias allowed)
			(pads allowed)
			(copperpour not_allowed)
			(footprints allowed)
		)
		(placement
			(enabled no)
			(sheetname "")
		)
		(fill
			(thermal_gap 0.5)
			(thermal_bridge_width 0.5)
			(island_removal_mode 0)
		)
		(polygon
			(pts
				(xy 238.620554 -0.120142) (xy 239.179354 -0.120142) (xy 239.179354 -1.923542) (xy 238.620554 -1.923542)
			)
		)
	)
	(zone
		(layer "In12.Cu")
		(hatch none 0.5)
		(connect_pads
			(clearance 0)
		)
		(min_thickness 0.25)
		(keepout
			(tracks not_allowed)
			(vias allowed)
			(pads allowed)
			(copperpour not_allowed)
			(footprints allowed)
		)
		(placement
			(enabled no)
			(sheetname "")
		)
		(fill
			(thermal_gap 0.5)
			(thermal_bridge_width 0.5)
			(island_removal_mode 0)
		)
		(polygon
			(pts
				(xy 116.11991 -151.176482) (xy 116.67871 -151.176482) (xy 116.67871 -152.979882) (xy 116.11991 -152.979882)
			)
		)
	)
	(zone
		(layer "In12.Cu")
		(hatch none 0.5)
		(connect_pads
			(clearance 0)
		)
		(min_thickness 0.25)
		(keepout
			(tracks not_allowed)
			(vias allowed)
			(pads allowed)
			(copperpour not_allowed)
			(footprints allowed)
		)
		(placement
			(enabled no)
			(sheetname "")
		)
		(fill
			(thermal_gap 0.5)
			(thermal_bridge_width 0.5)
			(island_removal_mode 0)
		)
		(polygon
			(pts
				(xy 242.020852 -136.975342) (xy 242.579652 -136.975342) (xy 242.579652 -138.778742) (xy 242.020852 -138.778742)
			)
		)
	)
	(zone
		(layer "In12.Cu")
		(hatch none 0.5)
		(connect_pads
			(clearance 0)
		)
		(min_thickness 0.25)
		(keepout
			(tracks not_allowed)
			(vias allowed)
			(pads allowed)
			(copperpour not_allowed)
			(footprints allowed)
		)
		(placement
			(enabled no)
			(sheetname "")
		)
		(fill
			(thermal_gap 0.5)
			(thermal_bridge_width 0.5)
			(island_removal_mode 0)
		)
		(polygon
			(pts
				(xy 115.270026 -146.576542) (xy 115.828826 -146.576542) (xy 115.828826 -148.379942) (xy 115.270026 -148.379942)
			)
		)
	)
	(zone
		(layer "In12.Cu")
		(hatch none 0.5)
		(connect_pads
			(clearance 0)
		)
		(min_thickness 0.25)
		(keepout
			(tracks not_allowed)
			(vias allowed)
			(pads allowed)
			(copperpour not_allowed)
			(footprints allowed)
		)
		(placement
			(enabled no)
			(sheetname "")
		)
		(fill
			(thermal_gap 0.5)
			(thermal_bridge_width 0.5)
			(island_removal_mode 0)
		)
		(polygon
			(pts
				(xy 241.170714 -14.321282) (xy 241.729514 -14.321282) (xy 241.729514 -16.124682) (xy 241.170714 -16.124682)
			)
		)
	)
	(zone
		(layer "In12.Cu")
		(hatch none 0.5)
		(connect_pads
			(clearance 0)
		)
		(min_thickness 0.25)
		(keepout
			(tracks not_allowed)
			(vias allowed)
			(pads allowed)
			(copperpour not_allowed)
			(footprints allowed)
		)
		(placement
			(enabled no)
			(sheetname "")
		)
		(fill
			(thermal_gap 0.5)
			(thermal_bridge_width 0.5)
			(island_removal_mode 0)
		)
		(polygon
			(pts
				(xy 203.770484 -14.321282) (xy 204.329284 -14.321282) (xy 204.329284 -16.124682) (xy 203.770484 -16.124682)
			)
		)
	)
	(zone
		(layer "In12.Cu")
		(hatch none 0.5)
		(connect_pads
			(clearance 0)
		)
		(min_thickness 0.25)
		(keepout
			(tracks not_allowed)
			(vias allowed)
			(pads allowed)
			(copperpour not_allowed)
			(footprints allowed)
		)
		(placement
			(enabled no)
			(sheetname "")
		)
		(fill
			(thermal_gap 0.5)
			(thermal_bridge_width 0.5)
			(island_removal_mode 0)
		)
		(polygon
			(pts
				(xy 241.170714 -141.575282) (xy 241.729514 -141.575282) (xy 241.729514 -143.378682) (xy 241.170714 -143.378682)
			)
		)
	)
	(zone
		(layer "In12.Cu")
		(hatch none 0.5)
		(connect_pads
			(clearance 0)
		)
		(min_thickness 0.25)
		(keepout
			(tracks not_allowed)
			(vias allowed)
			(pads allowed)
			(copperpour not_allowed)
			(footprints allowed)
		)
		(placement
			(enabled no)
			(sheetname "")
		)
		(fill
			(thermal_gap 0.5)
			(thermal_bridge_width 0.5)
			(island_removal_mode 0)
		)
		(polygon
			(pts
				(xy 282.820364 -151.176482) (xy 283.379164 -151.176482) (xy 283.379164 -152.979882) (xy 282.820364 -152.979882)
			)
		)
	)
	(zone
		(layer "In12.Cu")
		(hatch none 0.5)
		(connect_pads
			(clearance 0)
		)
		(min_thickness 0.25)
		(keepout
			(tracks not_allowed)
			(vias allowed)
			(pads allowed)
			(copperpour not_allowed)
			(footprints allowed)
		)
		(placement
			(enabled no)
			(sheetname "")
		)
		(fill
			(thermal_gap 0.5)
			(thermal_bridge_width 0.5)
			(island_removal_mode 0)
		)
		(polygon
			(pts
				(xy 202.9206 -136.975342) (xy 203.4794 -136.975342) (xy 203.4794 -138.778742) (xy 202.9206 -138.778742)
			)
		)
	)
	(zone
		(layer "In12.Cu")
		(hatch none 0.5)
		(connect_pads
			(clearance 0)
		)
		(min_thickness 0.25)
		(keepout
			(tracks not_allowed)
			(vias allowed)
			(pads allowed)
			(copperpour not_allowed)
			(footprints allowed)
		)
		(placement
			(enabled no)
			(sheetname "")
		)
		(fill
			(thermal_gap 0.5)
			(thermal_bridge_width 0.5)
			(island_removal_mode 0)
		)
		(polygon
			(pts
				(xy 77.87005 -151.176482) (xy 78.42885 -151.176482) (xy 78.42885 -152.979882) (xy 77.87005 -152.979882)
			)
		)
	)
	(zone
		(layer "In12.Cu")
		(hatch none 0.5)
		(connect_pads
			(clearance 0)
		)
		(min_thickness 0.25)
		(keepout
			(tracks not_allowed)
			(vias allowed)
			(pads allowed)
			(copperpour not_allowed)
			(footprints allowed)
		)
		(placement
			(enabled no)
			(sheetname "")
		)
		(fill
			(thermal_gap 0.5)
			(thermal_bridge_width 0.5)
			(island_removal_mode 0)
		)
		(polygon
			(pts
				(xy 268.370558 -23.922482) (xy 268.929358 -23.922482) (xy 268.929358 -25.725882) (xy 268.370558 -25.725882)
			)
		)
	)
	(zone
		(layer "In12.Cu")
		(hatch none 0.5)
		(connect_pads
			(clearance 0)
		)
		(min_thickness 0.25)
		(keepout
			(tracks not_allowed)
			(vias allowed)
			(pads allowed)
			(copperpour not_allowed)
			(footprints allowed)
		)
		(placement
			(enabled no)
			(sheetname "")
		)
		(fill
			(thermal_gap 0.5)
			(thermal_bridge_width 0.5)
			(island_removal_mode 0)
		)
		(polygon
			(pts
				(xy 110.16996 -146.576542) (xy 110.72876 -146.576542) (xy 110.72876 -148.379942) (xy 110.16996 -148.379942)
			)
		)
	)
	(zone
		(layer "In12.Cu")
		(hatch none 0.5)
		(connect_pads
			(clearance 0)
		)
		(min_thickness 0.25)
		(keepout
			(tracks not_allowed)
			(vias allowed)
			(pads allowed)
			(copperpour not_allowed)
			(footprints allowed)
		)
		(placement
			(enabled no)
			(sheetname "")
		)
		(fill
			(thermal_gap 0.5)
			(thermal_bridge_width 0.5)
			(island_removal_mode 0)
		)
		(polygon
			(pts
				(xy 201.220578 -0.120142) (xy 201.779378 -0.120142) (xy 201.779378 -1.923542) (xy 201.220578 -1.923542)
			)
		)
	)
	(zone
		(layer "In12.Cu")
		(hatch none 0.5)
		(connect_pads
			(clearance 0)
		)
		(min_thickness 0.25)
		(keepout
			(tracks not_allowed)
			(vias allowed)
			(pads allowed)
			(copperpour not_allowed)
			(footprints allowed)
		)
		(placement
			(enabled no)
			(sheetname "")
		)
		(fill
			(thermal_gap 0.5)
			(thermal_bridge_width 0.5)
			(island_removal_mode 0)
		)
		(polygon
			(pts
				(xy 196.970396 -19.322542) (xy 197.529196 -19.322542) (xy 197.529196 -21.125942) (xy 196.970396 -21.125942)
			)
		)
	)
	(zone
		(layer "In12.Cu")
		(hatch none 0.5)
		(connect_pads
			(clearance 0)
		)
		(min_thickness 0.25)
		(keepout
			(tracks not_allowed)
			(vias allowed)
			(pads allowed)
			(copperpour not_allowed)
			(footprints allowed)
		)
		(placement
			(enabled no)
			(sheetname "")
		)
		(fill
			(thermal_gap 0.5)
			(thermal_bridge_width 0.5)
			(island_removal_mode 0)
		)
		(polygon
			(pts
				(xy 257.320542 -9.721342) (xy 257.879342 -9.721342) (xy 257.879342 -11.524742) (xy 257.320542 -11.524742)
			)
		)
	)
	(zone
		(layer "In12.Cu")
		(hatch none 0.5)
		(connect_pads
			(clearance 0)
		)
		(min_thickness 0.25)
		(keepout
			(tracks not_allowed)
			(vias allowed)
			(pads allowed)
			(copperpour not_allowed)
			(footprints allowed)
		)
		(placement
			(enabled no)
			(sheetname "")
		)
		(fill
			(thermal_gap 0.5)
			(thermal_bridge_width 0.5)
			(island_removal_mode 0)
		)
		(polygon
			(pts
				(xy 209.720434 -136.975342) (xy 210.279234 -136.975342) (xy 210.279234 -138.778742) (xy 209.720434 -138.778742)
			)
		)
	)
	(zone
		(layer "In12.Cu")
		(hatch none 0.5)
		(connect_pads
			(clearance 0)
		)
		(min_thickness 0.25)
		(keepout
			(tracks not_allowed)
			(vias allowed)
			(pads allowed)
			(copperpour not_allowed)
			(footprints allowed)
		)
		(placement
			(enabled no)
			(sheetname "")
		)
		(fill
			(thermal_gap 0.5)
			(thermal_bridge_width 0.5)
			(island_removal_mode 0)
		)
		(polygon
			(pts
				(xy 286.220408 -0.120142) (xy 286.779208 -0.120142) (xy 286.779208 -1.923542) (xy 286.220408 -1.923542)
			)
		)
	)
	(zone
		(layer "In12.Cu")
		(hatch none 0.5)
		(connect_pads
			(clearance 0)
		)
		(min_thickness 0.25)
		(keepout
			(tracks not_allowed)
			(vias allowed)
			(pads allowed)
			(copperpour not_allowed)
			(footprints allowed)
		)
		(placement
			(enabled no)
			(sheetname "")
		)
		(fill
			(thermal_gap 0.5)
			(thermal_bridge_width 0.5)
			(island_removal_mode 0)
		)
		(polygon
			(pts
				(xy 211.420456 -151.176482) (xy 211.979256 -151.176482) (xy 211.979256 -152.979882) (xy 211.420456 -152.979882)
			)
		)
	)
	(zone
		(layer "In12.Cu")
		(hatch none 0.5)
		(connect_pads
			(clearance 0)
		)
		(min_thickness 0.25)
		(keepout
			(tracks not_allowed)
			(vias allowed)
			(pads allowed)
			(copperpour not_allowed)
			(footprints allowed)
		)
		(placement
			(enabled no)
			(sheetname "")
		)
		(fill
			(thermal_gap 0.5)
			(thermal_bridge_width 0.5)
			(island_removal_mode 0)
		)
		(polygon
			(pts
				(xy 120.370092 -141.575282) (xy 120.928892 -141.575282) (xy 120.928892 -143.378682) (xy 120.370092 -143.378682)
			)
		)
	)
	(zone
		(layer "In12.Cu")
		(hatch none 0.5)
		(connect_pads
			(clearance 0)
		)
		(min_thickness 0.25)
		(keepout
			(tracks not_allowed)
			(vias allowed)
			(pads allowed)
			(copperpour not_allowed)
			(footprints allowed)
		)
		(placement
			(enabled no)
			(sheetname "")
		)
		(fill
			(thermal_gap 0.5)
			(thermal_bridge_width 0.5)
			(island_removal_mode 0)
		)
		(polygon
			(pts
				(xy 465.074 -115.34902) (xy 465.582 -115.34902) (xy 465.582 -116.74602) (xy 465.074 -116.74602)
			)
		)
	)
	(zone
		(layer "In12.Cu")
		(hatch none 0.5)
		(connect_pads
			(clearance 0)
		)
		(min_thickness 0.25)
		(keepout
			(tracks not_allowed)
			(vias allowed)
			(pads allowed)
			(copperpour not_allowed)
			(footprints allowed)
		)
		(placement
			(enabled no)
			(sheetname "")
		)
		(fill
			(thermal_gap 0.5)
			(thermal_bridge_width 0.5)
			(island_removal_mode 0)
		)
		(polygon
			(pts
				(xy 252.220476 -0.120142) (xy 252.779276 -0.120142) (xy 252.779276 -1.923542) (xy 252.220476 -1.923542)
			)
		)
	)
	(zone
		(layer "In12.Cu")
		(hatch none 0.5)
		(connect_pads
			(clearance 0)
		)
		(min_thickness 0.25)
		(keepout
			(tracks not_allowed)
			(vias allowed)
			(pads allowed)
			(copperpour not_allowed)
			(footprints allowed)
		)
		(placement
			(enabled no)
			(sheetname "")
		)
		(fill
			(thermal_gap 0.5)
			(thermal_bridge_width 0.5)
			(island_removal_mode 0)
		)
		(polygon
			(pts
				(xy 102.519988 -19.322542) (xy 103.078788 -19.322542) (xy 103.078788 -21.125942) (xy 102.519988 -21.125942)
			)
		)
	)
	(zone
		(layer "In12.Cu")
		(hatch none 0.5)
		(connect_pads
			(clearance 0)
		)
		(min_thickness 0.25)
		(keepout
			(tracks not_allowed)
			(vias allowed)
			(pads allowed)
			(copperpour not_allowed)
			(footprints allowed)
		)
		(placement
			(enabled no)
			(sheetname "")
		)
		(fill
			(thermal_gap 0.5)
			(thermal_bridge_width 0.5)
			(island_removal_mode 0)
		)
		(polygon
			(pts
				(xy 312.570368 -19.322542) (xy 313.129168 -19.322542) (xy 313.129168 -21.125942) (xy 312.570368 -21.125942)
			)
		)
	)
	(zone
		(layer "In12.Cu")
		(hatch none 0.5)
		(connect_pads
			(clearance 0)
		)
		(min_thickness 0.25)
		(keepout
			(tracks not_allowed)
			(vias allowed)
			(pads allowed)
			(copperpour not_allowed)
			(footprints allowed)
		)
		(placement
			(enabled no)
			(sheetname "")
		)
		(fill
			(thermal_gap 0.5)
			(thermal_bridge_width 0.5)
			(island_removal_mode 0)
		)
		(polygon
			(pts
				(xy 150.96998 -136.975342) (xy 151.52878 -136.975342) (xy 151.52878 -138.778742) (xy 150.96998 -138.778742)
			)
		)
	)
	(zone
		(layer "In12.Cu")
		(hatch none 0.5)
		(connect_pads
			(clearance 0)
		)
		(min_thickness 0.25)
		(keepout
			(tracks not_allowed)
			(vias allowed)
			(pads allowed)
			(copperpour not_allowed)
			(footprints allowed)
		)
		(placement
			(enabled no)
			(sheetname "")
		)
		(fill
			(thermal_gap 0.5)
			(thermal_bridge_width 0.5)
			(island_removal_mode 0)
		)
		(polygon
			(pts
				(xy 123.769882 -4.720082) (xy 124.328682 -4.720082) (xy 124.328682 -6.523482) (xy 123.769882 -6.523482)
			)
		)
	)
	(zone
		(layer "In12.Cu")
		(hatch none 0.5)
		(connect_pads
			(clearance 0)
		)
		(min_thickness 0.25)
		(keepout
			(tracks not_allowed)
			(vias allowed)
			(pads allowed)
			(copperpour not_allowed)
			(footprints allowed)
		)
		(placement
			(enabled no)
			(sheetname "")
		)
		(fill
			(thermal_gap 0.5)
			(thermal_bridge_width 0.5)
			(island_removal_mode 0)
		)
		(polygon
			(pts
				(xy 301.520352 -131.974082) (xy 302.079152 -131.974082) (xy 302.079152 -133.777482) (xy 301.520352 -133.777482)
			)
		)
	)
	(zone
		(layer "In12.Cu")
		(hatch none 0.5)
		(connect_pads
			(clearance 0)
		)
		(min_thickness 0.25)
		(keepout
			(tracks not_allowed)
			(vias allowed)
			(pads allowed)
			(copperpour not_allowed)
			(footprints allowed)
		)
		(placement
			(enabled no)
			(sheetname "")
		)
		(fill
			(thermal_gap 0.5)
			(thermal_bridge_width 0.5)
			(island_removal_mode 0)
		)
		(polygon
			(pts
				(xy 254.770382 -23.922482) (xy 255.329182 -23.922482) (xy 255.329182 -25.725882) (xy 254.770382 -25.725882)
			)
		)
	)
	(zone
		(layer "In12.Cu")
		(hatch none 0.5)
		(connect_pads
			(clearance 0)
		)
		(min_thickness 0.25)
		(keepout
			(tracks not_allowed)
			(vias allowed)
			(pads allowed)
			(copperpour not_allowed)
			(footprints allowed)
		)
		(placement
			(enabled no)
			(sheetname "")
		)
		(fill
			(thermal_gap 0.5)
			(thermal_bridge_width 0.5)
			(island_removal_mode 0)
		)
		(polygon
			(pts
				(xy 226.7204 -146.576542) (xy 227.2792 -146.576542) (xy 227.2792 -148.379942) (xy 226.7204 -148.379942)
			)
		)
	)
	(zone
		(layer "In12.Cu")
		(hatch none 0.5)
		(connect_pads
			(clearance 0)
		)
		(min_thickness 0.25)
		(keepout
			(tracks not_allowed)
			(vias allowed)
			(pads allowed)
			(copperpour not_allowed)
			(footprints allowed)
		)
		(placement
			(enabled no)
			(sheetname "")
		)
		(fill
			(thermal_gap 0.5)
			(thermal_bridge_width 0.5)
			(island_removal_mode 0)
		)
		(polygon
			(pts
				(xy 67.669918 -136.975342) (xy 68.228718 -136.975342) (xy 68.228718 -138.778742) (xy 67.669918 -138.778742)
			)
		)
	)
	(zone
		(layer "In12.Cu")
		(hatch none 0.5)
		(connect_pads
			(clearance 0)
		)
		(min_thickness 0.25)
		(keepout
			(tracks not_allowed)
			(vias allowed)
			(pads allowed)
			(copperpour not_allowed)
			(footprints allowed)
		)
		(placement
			(enabled no)
			(sheetname "")
		)
		(fill
			(thermal_gap 0.5)
			(thermal_bridge_width 0.5)
			(island_removal_mode 0)
		)
		(polygon
			(pts
				(xy 227.570538 -14.321282) (xy 228.129338 -14.321282) (xy 228.129338 -16.124682) (xy 227.570538 -16.124682)
			)
		)
	)
	(zone
		(layer "In12.Cu")
		(hatch none 0.5)
		(connect_pads
			(clearance 0)
		)
		(min_thickness 0.25)
		(keepout
			(tracks not_allowed)
			(vias allowed)
			(pads allowed)
			(copperpour not_allowed)
			(footprints allowed)
		)
		(placement
			(enabled no)
			(sheetname "")
		)
		(fill
			(thermal_gap 0.5)
			(thermal_bridge_width 0.5)
			(island_removal_mode 0)
		)
		(polygon
			(pts
				(xy 283.670502 -146.576542) (xy 284.229302 -146.576542) (xy 284.229302 -148.379942) (xy 283.670502 -148.379942)
			)
		)
	)
	(zone
		(layer "In12.Cu")
		(hatch none 0.5)
		(connect_pads
			(clearance 0)
		)
		(min_thickness 0.25)
		(keepout
			(tracks not_allowed)
			(vias allowed)
			(pads allowed)
			(copperpour not_allowed)
			(footprints allowed)
		)
		(placement
			(enabled no)
			(sheetname "")
		)
		(fill
			(thermal_gap 0.5)
			(thermal_bridge_width 0.5)
			(island_removal_mode 0)
		)
		(polygon
			(pts
				(xy 139.07008 -151.176482) (xy 139.62888 -151.176482) (xy 139.62888 -152.979882) (xy 139.07008 -152.979882)
			)
		)
	)
	(zone
		(layer "In12.Cu")
		(hatch none 0.5)
		(connect_pads
			(clearance 0)
		)
		(min_thickness 0.25)
		(keepout
			(tracks not_allowed)
			(vias allowed)
			(pads allowed)
			(copperpour not_allowed)
			(footprints allowed)
		)
		(placement
			(enabled no)
			(sheetname "")
		)
		(fill
			(thermal_gap 0.5)
			(thermal_bridge_width 0.5)
			(island_removal_mode 0)
		)
		(polygon
			(pts
				(xy 252.220476 -146.576542) (xy 252.779276 -146.576542) (xy 252.779276 -148.379942) (xy 252.220476 -148.379942)
			)
		)
	)
	(zone
		(layer "In12.Cu")
		(hatch none 0.5)
		(connect_pads
			(clearance 0)
		)
		(min_thickness 0.25)
		(keepout
			(tracks not_allowed)
			(vias allowed)
			(pads allowed)
			(copperpour not_allowed)
			(footprints allowed)
		)
		(placement
			(enabled no)
			(sheetname "")
		)
		(fill
			(thermal_gap 0.5)
			(thermal_bridge_width 0.5)
			(island_removal_mode 0)
		)
		(polygon
			(pts
				(xy 246.270526 -4.720082) (xy 246.829326 -4.720082) (xy 246.829326 -6.523482) (xy 246.270526 -6.523482)
			)
		)
	)
	(zone
		(layer "In12.Cu")
		(hatch none 0.5)
		(connect_pads
			(clearance 0)
		)
		(min_thickness 0.25)
		(keepout
			(tracks not_allowed)
			(vias allowed)
			(pads allowed)
			(copperpour not_allowed)
			(footprints allowed)
		)
		(placement
			(enabled no)
			(sheetname "")
		)
		(fill
			(thermal_gap 0.5)
			(thermal_bridge_width 0.5)
			(island_removal_mode 0)
		)
		(polygon
			(pts
				(xy 111.020098 -131.974082) (xy 111.578898 -131.974082) (xy 111.578898 -133.777482) (xy 111.020098 -133.777482)
			)
		)
	)
	(zone
		(layer "In12.Cu")
		(hatch none 0.5)
		(connect_pads
			(clearance 0)
		)
		(min_thickness 0.25)
		(keepout
			(tracks not_allowed)
			(vias allowed)
			(pads allowed)
			(copperpour not_allowed)
			(footprints allowed)
		)
		(placement
			(enabled no)
			(sheetname "")
		)
		(fill
			(thermal_gap 0.5)
			(thermal_bridge_width 0.5)
			(island_removal_mode 0)
		)
		(polygon
			(pts
				(xy 248.820432 -141.575282) (xy 249.379232 -141.575282) (xy 249.379232 -143.378682) (xy 248.820432 -143.378682)
			)
		)
	)
	(zone
		(layer "In12.Cu")
		(hatch none 0.5)
		(connect_pads
			(clearance 0)
		)
		(min_thickness 0.25)
		(keepout
			(tracks not_allowed)
			(vias allowed)
			(pads allowed)
			(copperpour not_allowed)
			(footprints allowed)
		)
		(placement
			(enabled no)
			(sheetname "")
		)
		(fill
			(thermal_gap 0.5)
			(thermal_bridge_width 0.5)
			(island_removal_mode 0)
		)
		(polygon
			(pts
				(xy 307.470302 -151.176482) (xy 308.029102 -151.176482) (xy 308.029102 -152.979882) (xy 307.470302 -152.979882)
			)
		)
	)
	(zone
		(layer "In12.Cu")
		(hatch none 0.5)
		(connect_pads
			(clearance 0)
		)
		(min_thickness 0.25)
		(keepout
			(tracks not_allowed)
			(vias allowed)
			(pads allowed)
			(copperpour not_allowed)
			(footprints allowed)
		)
		(placement
			(enabled no)
			(sheetname "")
		)
		(fill
			(thermal_gap 0.5)
			(thermal_bridge_width 0.5)
			(island_removal_mode 0)
		)
		(polygon
			(pts
				(xy 77.02042 -9.721342) (xy 77.57922 -9.721342) (xy 77.57922 -11.524742) (xy 77.02042 -11.524742)
			)
		)
	)
	(zone
		(net "PVDDQ_KLM")
		(layer "In12.Cu")
		(hatch none 0.5)
		(connect_pads
			(clearance 0.5)
		)
		(min_thickness 0.25)
		(fill yes
			(thermal_gap 0.5)
			(thermal_bridge_width 0.5)
			(island_removal_mode 0)
		)
		(polygon
			(pts
				(xy 100.256594 -129.1717) (xy 100.0887 -129.339594) (xy 100.0887 -130.731006) (xy 100.6729 -131.315206)
				(xy 100.6729 -131.797806) (xy 100.840794 -131.9657) (xy 113.128806 -131.9657) (xy 113.3729 -131.721606)
				(xy 113.3729 -130.761994) (xy 113.1189 -130.507994) (xy 113.1189 -129.943606) (xy 113.3221 -129.740406)
				(xy 113.3221 -129.364994) (xy 113.128806 -129.1717)
			)
		)
	)
	(zone
		(layer "In12.Cu")
		(hatch none 0.5)
		(connect_pads
			(clearance 0)
		)
		(min_thickness 0.25)
		(keepout
			(tracks not_allowed)
			(vias allowed)
			(pads allowed)
			(copperpour not_allowed)
			(footprints allowed)
		)
		(placement
			(enabled no)
			(sheetname "")
		)
		(fill
			(thermal_gap 0.5)
			(thermal_bridge_width 0.5)
			(island_removal_mode 0)
		)
		(polygon
			(pts
				(xy 30.269942 -127.374142) (xy 30.828742 -127.374142) (xy 30.828742 -129.177542) (xy 30.269942 -129.177542)
			)
		)
	)
	(zone
		(layer "In12.Cu")
		(hatch none 0.5)
		(connect_pads
			(clearance 0)
		)
		(min_thickness 0.25)
		(keepout
			(tracks not_allowed)
			(vias allowed)
			(pads allowed)
			(copperpour not_allowed)
			(footprints allowed)
		)
		(placement
			(enabled no)
			(sheetname "")
		)
		(fill
			(thermal_gap 0.5)
			(thermal_bridge_width 0.5)
			(island_removal_mode 0)
		)
		(polygon
			(pts
				(xy 249.67057 -9.721342) (xy 250.22937 -9.721342) (xy 250.22937 -11.524742) (xy 249.67057 -11.524742)
			)
		)
	)
	(zone
		(layer "In12.Cu")
		(hatch none 0.5)
		(connect_pads
			(clearance 0)
		)
		(min_thickness 0.25)
		(keepout
			(tracks not_allowed)
			(vias allowed)
			(pads allowed)
			(copperpour not_allowed)
			(footprints allowed)
		)
		(placement
			(enabled no)
			(sheetname "")
		)
		(fill
			(thermal_gap 0.5)
			(thermal_bridge_width 0.5)
			(island_removal_mode 0)
		)
		(polygon
			(pts
				(xy 288.770314 -14.321282) (xy 289.329114 -14.321282) (xy 289.329114 -16.124682) (xy 288.770314 -16.124682)
			)
		)
	)
	(zone
		(layer "In12.Cu")
		(hatch none 0.5)
		(connect_pads
			(clearance 0)
		)
		(min_thickness 0.25)
		(keepout
			(tracks not_allowed)
			(vias allowed)
			(pads allowed)
			(copperpour not_allowed)
			(footprints allowed)
		)
		(placement
			(enabled no)
			(sheetname "")
		)
		(fill
			(thermal_gap 0.5)
			(thermal_bridge_width 0.5)
			(island_removal_mode 0)
		)
		(polygon
			(pts
				(xy 420.5732 -154.559) (xy 420.5732 -155.321) (xy 421.5638 -155.321) (xy 421.5638 -154.559)
			)
		)
	)
	(zone
		(layer "In12.Cu")
		(hatch none 0.5)
		(connect_pads
			(clearance 0)
		)
		(min_thickness 0.25)
		(keepout
			(tracks not_allowed)
			(vias allowed)
			(pads allowed)
			(copperpour not_allowed)
			(footprints allowed)
		)
		(placement
			(enabled no)
			(sheetname "")
		)
		(fill
			(thermal_gap 0.5)
			(thermal_bridge_width 0.5)
			(island_removal_mode 0)
		)
		(polygon
			(pts
				(xy 234.370372 -146.576542) (xy 234.929172 -146.576542) (xy 234.929172 -148.379942) (xy 234.370372 -148.379942)
			)
		)
	)
	(zone
		(layer "In12.Cu")
		(hatch none 0.5)
		(connect_pads
			(clearance 0)
		)
		(min_thickness 0.25)
		(keepout
			(tracks not_allowed)
			(vias allowed)
			(pads allowed)
			(copperpour not_allowed)
			(footprints allowed)
		)
		(placement
			(enabled no)
			(sheetname "")
		)
		(fill
			(thermal_gap 0.5)
			(thermal_bridge_width 0.5)
			(island_removal_mode 0)
		)
		(polygon
			(pts
				(xy 67.669918 -9.721342) (xy 68.228718 -9.721342) (xy 68.228718 -11.524742) (xy 67.669918 -11.524742)
			)
		)
	)
	(zone
		(layer "In12.Cu")
		(hatch none 0.5)
		(connect_pads
			(clearance 0)
		)
		(min_thickness 0.25)
		(keepout
			(tracks not_allowed)
			(vias allowed)
			(pads allowed)
			(copperpour not_allowed)
			(footprints allowed)
		)
		(placement
			(enabled no)
			(sheetname "")
		)
		(fill
			(thermal_gap 0.5)
			(thermal_bridge_width 0.5)
			(island_removal_mode 0)
		)
		(polygon
			(pts
				(xy 115.270026 -127.374142) (xy 115.828826 -127.374142) (xy 115.828826 -129.177542) (xy 115.270026 -129.177542)
			)
		)
	)
	(zone
		(layer "In12.Cu")
		(hatch none 0.5)
		(connect_pads
			(clearance 0)
		)
		(min_thickness 0.25)
		(keepout
			(tracks not_allowed)
			(vias allowed)
			(pads allowed)
			(copperpour not_allowed)
			(footprints allowed)
		)
		(placement
			(enabled no)
			(sheetname "")
		)
		(fill
			(thermal_gap 0.5)
			(thermal_bridge_width 0.5)
			(island_removal_mode 0)
		)
		(polygon
			(pts
				(xy 198.670418 -127.374142) (xy 199.229218 -127.374142) (xy 199.229218 -129.177542) (xy 198.670418 -129.177542)
			)
		)
	)
	(zone
		(layer "In12.Cu")
		(hatch none 0.5)
		(connect_pads
			(clearance 0)
		)
		(min_thickness 0.25)
		(keepout
			(tracks not_allowed)
			(vias allowed)
			(pads allowed)
			(copperpour not_allowed)
			(footprints allowed)
		)
		(placement
			(enabled no)
			(sheetname "")
		)
		(fill
			(thermal_gap 0.5)
			(thermal_bridge_width 0.5)
			(island_removal_mode 0)
		)
		(polygon
			(pts
				(xy 147.569936 -127.374142) (xy 148.128736 -127.374142) (xy 148.128736 -129.177542) (xy 147.569936 -129.177542)
			)
		)
	)
	(zone
		(layer "In12.Cu")
		(hatch none 0.5)
		(connect_pads
			(clearance 0)
		)
		(min_thickness 0.25)
		(keepout
			(tracks not_allowed)
			(vias allowed)
			(pads allowed)
			(copperpour not_allowed)
			(footprints allowed)
		)
		(placement
			(enabled no)
			(sheetname "")
		)
		(fill
			(thermal_gap 0.5)
			(thermal_bridge_width 0.5)
			(island_removal_mode 0)
		)
		(polygon
			(pts
				(xy 70.220078 -151.176482) (xy 70.778878 -151.176482) (xy 70.778878 -152.979882) (xy 70.220078 -152.979882)
			)
		)
	)
	(zone
		(layer "In12.Cu")
		(hatch none 0.5)
		(connect_pads
			(clearance 0)
		)
		(min_thickness 0.25)
		(keepout
			(tracks not_allowed)
			(vias allowed)
			(pads allowed)
			(copperpour not_allowed)
			(footprints allowed)
		)
		(placement
			(enabled no)
			(sheetname "")
		)
		(fill
			(thermal_gap 0.5)
			(thermal_bridge_width 0.5)
			(island_removal_mode 0)
		)
		(polygon
			(pts
				(xy 313.420506 -14.321282) (xy 313.979306 -14.321282) (xy 313.979306 -16.124682) (xy 313.420506 -16.124682)
			)
		)
	)
	(zone
		(layer "In12.Cu")
		(hatch none 0.5)
		(connect_pads
			(clearance 0)
		)
		(min_thickness 0.25)
		(keepout
			(tracks not_allowed)
			(vias allowed)
			(pads allowed)
			(copperpour not_allowed)
			(footprints allowed)
		)
		(placement
			(enabled no)
			(sheetname "")
		)
		(fill
			(thermal_gap 0.5)
			(thermal_bridge_width 0.5)
			(island_removal_mode 0)
		)
		(polygon
			(pts
				(xy 211.420456 -141.575282) (xy 211.979256 -141.575282) (xy 211.979256 -143.378682) (xy 211.420456 -143.378682)
			)
		)
	)
	(zone
		(layer "In12.Cu")
		(hatch none 0.5)
		(connect_pads
			(clearance 0)
		)
		(min_thickness 0.25)
		(keepout
			(tracks not_allowed)
			(vias allowed)
			(pads allowed)
			(copperpour not_allowed)
			(footprints allowed)
		)
		(placement
			(enabled no)
			(sheetname "")
		)
		(fill
			(thermal_gap 0.5)
			(thermal_bridge_width 0.5)
			(island_removal_mode 0)
		)
		(polygon
			(pts
				(xy 48.120046 -131.974082) (xy 48.678846 -131.974082) (xy 48.678846 -133.777482) (xy 48.120046 -133.777482)
			)
		)
	)
	(zone
		(layer "In12.Cu")
		(hatch none 0.5)
		(connect_pads
			(clearance 0)
		)
		(min_thickness 0.25)
		(keepout
			(tracks not_allowed)
			(vias allowed)
			(pads allowed)
			(copperpour not_allowed)
			(footprints allowed)
		)
		(placement
			(enabled no)
			(sheetname "")
		)
		(fill
			(thermal_gap 0.5)
			(thermal_bridge_width 0.5)
			(island_removal_mode 0)
		)
		(polygon
			(pts
				(xy 285.370524 -4.720082) (xy 285.929324 -4.720082) (xy 285.929324 -6.523482) (xy 285.370524 -6.523482)
			)
		)
	)
	(zone
		(layer "In12.Cu")
		(hatch none 0.5)
		(connect_pads
			(clearance 0)
		)
		(min_thickness 0.25)
		(keepout
			(tracks not_allowed)
			(vias allowed)
			(pads allowed)
			(copperpour not_allowed)
			(footprints allowed)
		)
		(placement
			(enabled no)
			(sheetname "")
		)
		(fill
			(thermal_gap 0.5)
			(thermal_bridge_width 0.5)
			(island_removal_mode 0)
		)
		(polygon
			(pts
				(xy 138.219942 -0.120142) (xy 138.778742 -0.120142) (xy 138.778742 -1.923542) (xy 138.219942 -1.923542)
			)
		)
	)
	(zone
		(layer "In12.Cu")
		(hatch none 0.5)
		(connect_pads
			(clearance 0)
		)
		(min_thickness 0.25)
		(keepout
			(tracks not_allowed)
			(vias allowed)
			(pads allowed)
			(copperpour not_allowed)
			(footprints allowed)
		)
		(placement
			(enabled no)
			(sheetname "")
		)
		(fill
			(thermal_gap 0.5)
			(thermal_bridge_width 0.5)
			(island_removal_mode 0)
		)
		(polygon
			(pts
				(xy 49.820068 -14.321282) (xy 50.378868 -14.321282) (xy 50.378868 -16.124682) (xy 49.820068 -16.124682)
			)
		)
	)
	(zone
		(layer "In12.Cu")
		(hatch none 0.5)
		(connect_pads
			(clearance 0)
		)
		(min_thickness 0.25)
		(keepout
			(tracks not_allowed)
			(vias allowed)
			(pads allowed)
			(copperpour not_allowed)
			(footprints allowed)
		)
		(placement
			(enabled no)
			(sheetname "")
		)
		(fill
			(thermal_gap 0.5)
			(thermal_bridge_width 0.5)
			(island_removal_mode 0)
		)
		(polygon
			(pts
				(xy 307.470302 -14.321282) (xy 308.029102 -14.321282) (xy 308.029102 -16.124682) (xy 307.470302 -16.124682)
			)
		)
	)
	(zone
		(layer "In12.Cu")
		(hatch none 0.5)
		(connect_pads
			(clearance 0)
		)
		(min_thickness 0.25)
		(keepout
			(tracks not_allowed)
			(vias allowed)
			(pads allowed)
			(copperpour not_allowed)
			(footprints allowed)
		)
		(placement
			(enabled no)
			(sheetname "")
		)
		(fill
			(thermal_gap 0.5)
			(thermal_bridge_width 0.5)
			(island_removal_mode 0)
		)
		(polygon
			(pts
				(xy 118.67007 -19.322542) (xy 119.22887 -19.322542) (xy 119.22887 -21.125942) (xy 118.67007 -21.125942)
			)
		)
	)
	(zone
		(layer "In12.Cu")
		(hatch none 0.5)
		(connect_pads
			(clearance 0)
		)
		(min_thickness 0.25)
		(keepout
			(tracks not_allowed)
			(vias allowed)
			(pads allowed)
			(copperpour not_allowed)
			(footprints allowed)
		)
		(placement
			(enabled no)
			(sheetname "")
		)
		(fill
			(thermal_gap 0.5)
			(thermal_bridge_width 0.5)
			(island_removal_mode 0)
		)
		(polygon
			(pts
				(xy 247.970548 -127.374142) (xy 248.529348 -127.374142) (xy 248.529348 -129.177542) (xy 247.970548 -129.177542)
			)
		)
	)
	(zone
		(layer "In12.Cu")
		(hatch none 0.5)
		(connect_pads
			(clearance 0)
		)
		(min_thickness 0.25)
		(keepout
			(tracks not_allowed)
			(vias allowed)
			(pads allowed)
			(copperpour not_allowed)
			(footprints allowed)
		)
		(placement
			(enabled no)
			(sheetname "")
		)
		(fill
			(thermal_gap 0.5)
			(thermal_bridge_width 0.5)
			(island_removal_mode 0)
		)
		(polygon
			(pts
				(xy 219.070428 -23.922482) (xy 219.629228 -23.922482) (xy 219.629228 -25.725882) (xy 219.070428 -25.725882)
			)
		)
	)
	(zone
		(layer "In12.Cu")
		(hatch none 0.5)
		(connect_pads
			(clearance 0)
		)
		(min_thickness 0.25)
		(keepout
			(tracks not_allowed)
			(vias allowed)
			(pads allowed)
			(copperpour not_allowed)
			(footprints allowed)
		)
		(placement
			(enabled no)
			(sheetname "")
		)
		(fill
			(thermal_gap 0.5)
			(thermal_bridge_width 0.5)
			(island_removal_mode 0)
		)
		(polygon
			(pts
				(xy 83.82 -151.176482) (xy 84.3788 -151.176482) (xy 84.3788 -152.979882) (xy 83.82 -152.979882)
			)
		)
	)
	(zone
		(layer "In12.Cu")
		(hatch none 0.5)
		(connect_pads
			(clearance 0)
		)
		(min_thickness 0.25)
		(keepout
			(tracks not_allowed)
			(vias allowed)
			(pads allowed)
			(copperpour not_allowed)
			(footprints allowed)
		)
		(placement
			(enabled no)
			(sheetname "")
		)
		(fill
			(thermal_gap 0.5)
			(thermal_bridge_width 0.5)
			(island_removal_mode 0)
		)
		(polygon
			(pts
				(xy 234.370372 -9.721342) (xy 234.929172 -9.721342) (xy 234.929172 -11.524742) (xy 234.370372 -11.524742)
			)
		)
	)
	(zone
		(layer "In12.Cu")
		(hatch none 0.5)
		(connect_pads
			(clearance 0)
		)
		(min_thickness 0.25)
		(keepout
			(tracks not_allowed)
			(vias allowed)
			(pads allowed)
			(copperpour not_allowed)
			(footprints allowed)
		)
		(placement
			(enabled no)
			(sheetname "")
		)
		(fill
			(thermal_gap 0.5)
			(thermal_bridge_width 0.5)
			(island_removal_mode 0)
		)
		(polygon
			(pts
				(xy 67.669918 -127.374142) (xy 68.228718 -127.374142) (xy 68.228718 -129.177542) (xy 67.669918 -129.177542)
			)
		)
	)
	(zone
		(layer "In12.Cu")
		(hatch none 0.5)
		(connect_pads
			(clearance 0)
		)
		(min_thickness 0.25)
		(keepout
			(tracks not_allowed)
			(vias allowed)
			(pads allowed)
			(copperpour not_allowed)
			(footprints allowed)
		)
		(placement
			(enabled no)
			(sheetname "")
		)
		(fill
			(thermal_gap 0.5)
			(thermal_bridge_width 0.5)
			(island_removal_mode 0)
		)
		(polygon
			(pts
				(xy 290.470336 -151.176482) (xy 291.029136 -151.176482) (xy 291.029136 -152.979882) (xy 290.470336 -152.979882)
			)
		)
	)
	(zone
		(layer "In12.Cu")
		(hatch none 0.5)
		(connect_pads
			(clearance 0)
		)
		(min_thickness 0.25)
		(keepout
			(tracks not_allowed)
			(vias allowed)
			(pads allowed)
			(copperpour not_allowed)
			(footprints allowed)
		)
		(placement
			(enabled no)
			(sheetname "")
		)
		(fill
			(thermal_gap 0.5)
			(thermal_bridge_width 0.5)
			(island_removal_mode 0)
		)
		(polygon
			(pts
				(xy 114.419888 -23.922482) (xy 114.978688 -23.922482) (xy 114.978688 -25.725882) (xy 114.419888 -25.725882)
			)
		)
	)
	(zone
		(layer "In12.Cu")
		(hatch none 0.5)
		(connect_pads
			(clearance 0)
		)
		(min_thickness 0.25)
		(keepout
			(tracks not_allowed)
			(vias allowed)
			(pads allowed)
			(copperpour not_allowed)
			(footprints allowed)
		)
		(placement
			(enabled no)
			(sheetname "")
		)
		(fill
			(thermal_gap 0.5)
			(thermal_bridge_width 0.5)
			(island_removal_mode 0)
		)
		(polygon
			(pts
				(xy 250.520454 -127.374142) (xy 251.079254 -127.374142) (xy 251.079254 -129.177542) (xy 250.520454 -129.177542)
			)
		)
	)
	(zone
		(layer "In12.Cu")
		(hatch none 0.5)
		(connect_pads
			(clearance 0)
		)
		(min_thickness 0.25)
		(keepout
			(tracks not_allowed)
			(vias allowed)
			(pads allowed)
			(copperpour not_allowed)
			(footprints allowed)
		)
		(placement
			(enabled no)
			(sheetname "")
		)
		(fill
			(thermal_gap 0.5)
			(thermal_bridge_width 0.5)
			(island_removal_mode 0)
		)
		(polygon
			(pts
				(xy 91.469972 -9.721342) (xy 92.028772 -9.721342) (xy 92.028772 -11.524742) (xy 91.469972 -11.524742)
			)
		)
	)
	(zone
		(layer "In12.Cu")
		(hatch none 0.5)
		(connect_pads
			(clearance 0)
		)
		(min_thickness 0.25)
		(keepout
			(tracks not_allowed)
			(vias allowed)
			(pads allowed)
			(copperpour not_allowed)
			(footprints allowed)
		)
		(placement
			(enabled no)
			(sheetname "")
		)
		(fill
			(thermal_gap 0.5)
			(thermal_bridge_width 0.5)
			(island_removal_mode 0)
		)
		(polygon
			(pts
				(xy 122.919998 -136.975342) (xy 123.478798 -136.975342) (xy 123.478798 -138.778742) (xy 122.919998 -138.778742)
			)
		)
	)
	(zone
		(layer "In12.Cu")
		(hatch none 0.5)
		(connect_pads
			(clearance 0)
		)
		(min_thickness 0.25)
		(keepout
			(tracks not_allowed)
			(vias allowed)
			(pads allowed)
			(copperpour not_allowed)
			(footprints allowed)
		)
		(placement
			(enabled no)
			(sheetname "")
		)
		(fill
			(thermal_gap 0.5)
			(thermal_bridge_width 0.5)
			(island_removal_mode 0)
		)
		(polygon
			(pts
				(xy 200.37044 -127.374142) (xy 200.92924 -127.374142) (xy 200.92924 -129.177542) (xy 200.37044 -129.177542)
			)
		)
	)
	(zone
		(layer "In12.Cu")
		(hatch none 0.5)
		(connect_pads
			(clearance 0)
		)
		(min_thickness 0.25)
		(keepout
			(tracks not_allowed)
			(vias allowed)
			(pads allowed)
			(copperpour not_allowed)
			(footprints allowed)
		)
		(placement
			(enabled no)
			(sheetname "")
		)
		(fill
			(thermal_gap 0.5)
			(thermal_bridge_width 0.5)
			(island_removal_mode 0)
		)
		(polygon
			(pts
				(xy 198.670418 -19.322542) (xy 199.229218 -19.322542) (xy 199.229218 -21.125942) (xy 198.670418 -21.125942)
			)
		)
	)
	(zone
		(layer "In12.Cu")
		(hatch none 0.5)
		(connect_pads
			(clearance 0)
		)
		(min_thickness 0.25)
		(keepout
			(tracks not_allowed)
			(vias allowed)
			(pads allowed)
			(copperpour not_allowed)
			(footprints allowed)
		)
		(placement
			(enabled no)
			(sheetname "")
		)
		(fill
			(thermal_gap 0.5)
			(thermal_bridge_width 0.5)
			(island_removal_mode 0)
		)
		(polygon
			(pts
				(xy 89.76995 -0.120142) (xy 90.32875 -0.120142) (xy 90.32875 -1.923542) (xy 89.76995 -1.923542)
			)
		)
	)
	(zone
		(layer "In12.Cu")
		(hatch none 0.5)
		(connect_pads
			(clearance 0)
		)
		(min_thickness 0.25)
		(keepout
			(tracks not_allowed)
			(vias allowed)
			(pads allowed)
			(copperpour not_allowed)
			(footprints allowed)
		)
		(placement
			(enabled no)
			(sheetname "")
		)
		(fill
			(thermal_gap 0.5)
			(thermal_bridge_width 0.5)
			(island_removal_mode 0)
		)
		(polygon
			(pts
				(xy 91.469972 -19.322542) (xy 92.028772 -19.322542) (xy 92.028772 -21.125942) (xy 91.469972 -21.125942)
			)
		)
	)
	(zone
		(layer "In12.Cu")
		(hatch none 0.5)
		(connect_pads
			(clearance 0)
		)
		(min_thickness 0.25)
		(keepout
			(tracks not_allowed)
			(vias allowed)
			(pads allowed)
			(copperpour not_allowed)
			(footprints allowed)
		)
		(placement
			(enabled no)
			(sheetname "")
		)
		(fill
			(thermal_gap 0.5)
			(thermal_bridge_width 0.5)
			(island_removal_mode 0)
		)
		(polygon
			(pts
				(xy 225.870516 -141.575282) (xy 226.429316 -141.575282) (xy 226.429316 -143.378682) (xy 225.870516 -143.378682)
			)
		)
	)
	(zone
		(layer "In12.Cu")
		(hatch none 0.5)
		(connect_pads
			(clearance 0)
		)
		(min_thickness 0.25)
		(keepout
			(tracks not_allowed)
			(vias allowed)
			(pads allowed)
			(copperpour not_allowed)
			(footprints allowed)
		)
		(placement
			(enabled no)
			(sheetname "")
		)
		(fill
			(thermal_gap 0.5)
			(thermal_bridge_width 0.5)
			(island_removal_mode 0)
		)
		(polygon
			(pts
				(xy 87.220044 -131.974082) (xy 87.778844 -131.974082) (xy 87.778844 -133.777482) (xy 87.220044 -133.777482)
			)
		)
	)
	(zone
		(layer "In12.Cu")
		(hatch none 0.5)
		(connect_pads
			(clearance 0)
		)
		(min_thickness 0.25)
		(keepout
			(tracks not_allowed)
			(vias allowed)
			(pads allowed)
			(copperpour not_allowed)
			(footprints allowed)
		)
		(placement
			(enabled no)
			(sheetname "")
		)
		(fill
			(thermal_gap 0.5)
			(thermal_bridge_width 0.5)
			(island_removal_mode 0)
		)
		(polygon
			(pts
				(xy 249.67057 -14.321282) (xy 250.22937 -14.321282) (xy 250.22937 -16.124682) (xy 249.67057 -16.124682)
			)
		)
	)
	(zone
		(layer "In12.Cu")
		(hatch none 0.5)
		(connect_pads
			(clearance 0)
		)
		(min_thickness 0.25)
		(keepout
			(tracks not_allowed)
			(vias allowed)
			(pads allowed)
			(copperpour not_allowed)
			(footprints allowed)
		)
		(placement
			(enabled no)
			(sheetname "")
		)
		(fill
			(thermal_gap 0.5)
			(thermal_bridge_width 0.5)
			(island_removal_mode 0)
		)
		(polygon
			(pts
				(xy 461.772 -115.34902) (xy 462.28 -115.34902) (xy 462.28 -116.74602) (xy 461.772 -116.74602)
			)
		)
	)
	(zone
		(layer "In12.Cu")
		(hatch none 0.5)
		(connect_pads
			(clearance 0)
		)
		(min_thickness 0.25)
		(keepout
			(tracks not_allowed)
			(vias allowed)
			(pads allowed)
			(copperpour not_allowed)
			(footprints allowed)
		)
		(placement
			(enabled no)
			(sheetname "")
		)
		(fill
			(thermal_gap 0.5)
			(thermal_bridge_width 0.5)
			(island_removal_mode 0)
		)
		(polygon
			(pts
				(xy 257.320542 -136.975342) (xy 257.879342 -136.975342) (xy 257.879342 -138.778742) (xy 257.320542 -138.778742)
			)
		)
	)
	(zone
		(layer "In12.Cu")
		(hatch none 0.5)
		(connect_pads
			(clearance 0)
		)
		(min_thickness 0.25)
		(keepout
			(tracks not_allowed)
			(vias allowed)
			(pads allowed)
			(copperpour not_allowed)
			(footprints allowed)
		)
		(placement
			(enabled no)
			(sheetname "")
		)
		(fill
			(thermal_gap 0.5)
			(thermal_bridge_width 0.5)
			(island_removal_mode 0)
		)
		(polygon
			(pts
				(xy 103.370126 -151.176482) (xy 103.928926 -151.176482) (xy 103.928926 -152.979882) (xy 103.370126 -152.979882)
			)
		)
	)
	(zone
		(layer "In12.Cu")
		(hatch none 0.5)
		(connect_pads
			(clearance 0)
		)
		(min_thickness 0.25)
		(keepout
			(tracks not_allowed)
			(vias allowed)
			(pads allowed)
			(copperpour not_allowed)
			(footprints allowed)
		)
		(placement
			(enabled no)
			(sheetname "")
		)
		(fill
			(thermal_gap 0.5)
			(thermal_bridge_width 0.5)
			(island_removal_mode 0)
		)
		(polygon
			(pts
				(xy 195.270374 -19.322542) (xy 195.829174 -19.322542) (xy 195.829174 -21.125942) (xy 195.270374 -21.125942)
			)
		)
	)
	(zone
		(layer "In12.Cu")
		(hatch none 0.5)
		(connect_pads
			(clearance 0)
		)
		(min_thickness 0.25)
		(keepout
			(tracks not_allowed)
			(vias allowed)
			(pads allowed)
			(copperpour not_allowed)
			(footprints allowed)
		)
		(placement
			(enabled no)
			(sheetname "")
		)
		(fill
			(thermal_gap 0.5)
			(thermal_bridge_width 0.5)
			(island_removal_mode 0)
		)
		(polygon
			(pts
				(xy 270.07058 -127.374142) (xy 270.62938 -127.374142) (xy 270.62938 -129.177542) (xy 270.07058 -129.177542)
			)
		)
	)
	(zone
		(layer "In12.Cu")
		(hatch none 0.5)
		(connect_pads
			(clearance 0)
		)
		(min_thickness 0.25)
		(keepout
			(tracks not_allowed)
			(vias allowed)
			(pads allowed)
			(copperpour not_allowed)
			(footprints allowed)
		)
		(placement
			(enabled no)
			(sheetname "")
		)
		(fill
			(thermal_gap 0.5)
			(thermal_bridge_width 0.5)
			(island_removal_mode 0)
		)
		(polygon
			(pts
				(xy 70.220078 -23.922482) (xy 70.778878 -23.922482) (xy 70.778878 -25.725882) (xy 70.220078 -25.725882)
			)
		)
	)
	(zone
		(layer "In12.Cu")
		(hatch none 0.5)
		(connect_pads
			(clearance 0)
		)
		(min_thickness 0.25)
		(keepout
			(tracks not_allowed)
			(vias allowed)
			(pads allowed)
			(copperpour not_allowed)
			(footprints allowed)
		)
		(placement
			(enabled no)
			(sheetname "")
		)
		(fill
			(thermal_gap 0.5)
			(thermal_bridge_width 0.5)
			(island_removal_mode 0)
		)
		(polygon
			(pts
				(xy 313.420506 -131.974082) (xy 313.979306 -131.974082) (xy 313.979306 -133.777482) (xy 313.420506 -133.777482)
			)
		)
	)
	(zone
		(layer "In12.Cu")
		(hatch none 0.5)
		(connect_pads
			(clearance 0)
		)
		(min_thickness 0.25)
		(keepout
			(tracks not_allowed)
			(vias allowed)
			(pads allowed)
			(copperpour not_allowed)
			(footprints allowed)
		)
		(placement
			(enabled no)
			(sheetname "")
		)
		(fill
			(thermal_gap 0.5)
			(thermal_bridge_width 0.5)
			(island_removal_mode 0)
		)
		(polygon
			(pts
				(xy 355.432614 -126.878842) (xy 353.146614 -126.878842) (xy 353.146614 -126.370842) (xy 355.432614 -126.370842)
			)
		)
	)
	(zone
		(layer "In12.Cu")
		(hatch none 0.5)
		(connect_pads
			(clearance 0)
		)
		(min_thickness 0.25)
		(keepout
			(tracks not_allowed)
			(vias allowed)
			(pads allowed)
			(copperpour not_allowed)
			(footprints allowed)
		)
		(placement
			(enabled no)
			(sheetname "")
		)
		(fill
			(thermal_gap 0.5)
			(thermal_bridge_width 0.5)
			(island_removal_mode 0)
		)
		(polygon
			(pts
				(xy 211.420456 -14.321282) (xy 211.979256 -14.321282) (xy 211.979256 -16.124682) (xy 211.420456 -16.124682)
			)
		)
	)
	(zone
		(layer "In12.Cu")
		(hatch none 0.5)
		(connect_pads
			(clearance 0)
		)
		(min_thickness 0.25)
		(keepout
			(tracks not_allowed)
			(vias allowed)
			(pads allowed)
			(copperpour not_allowed)
			(footprints allowed)
		)
		(placement
			(enabled no)
			(sheetname "")
		)
		(fill
			(thermal_gap 0.5)
			(thermal_bridge_width 0.5)
			(island_removal_mode 0)
		)
		(polygon
			(pts
				(xy 209.720434 -4.720082) (xy 210.279234 -4.720082) (xy 210.279234 -6.523482) (xy 209.720434 -6.523482)
			)
		)
	)
	(zone
		(layer "In12.Cu")
		(hatch none 0.5)
		(connect_pads
			(clearance 0)
		)
		(min_thickness 0.25)
		(keepout
			(tracks not_allowed)
			(vias allowed)
			(pads allowed)
			(copperpour not_allowed)
			(footprints allowed)
		)
		(placement
			(enabled no)
			(sheetname "")
		)
		(fill
			(thermal_gap 0.5)
			(thermal_bridge_width 0.5)
			(island_removal_mode 0)
		)
		(polygon
			(pts
				(xy 299.82033 -23.922482) (xy 300.37913 -23.922482) (xy 300.37913 -25.725882) (xy 299.82033 -25.725882)
			)
		)
	)
	(zone
		(layer "In12.Cu")
		(hatch none 0.5)
		(connect_pads
			(clearance 0)
		)
		(min_thickness 0.25)
		(keepout
			(tracks not_allowed)
			(vias allowed)
			(pads allowed)
			(copperpour not_allowed)
			(footprints allowed)
		)
		(placement
			(enabled no)
			(sheetname "")
		)
		(fill
			(thermal_gap 0.5)
			(thermal_bridge_width 0.5)
			(island_removal_mode 0)
		)
		(polygon
			(pts
				(xy 112.72012 -151.176482) (xy 113.27892 -151.176482) (xy 113.27892 -152.979882) (xy 112.72012 -152.979882)
			)
		)
	)
	(zone
		(layer "In12.Cu")
		(hatch none 0.5)
		(connect_pads
			(clearance 0)
		)
		(min_thickness 0.25)
		(keepout
			(tracks not_allowed)
			(vias allowed)
			(pads allowed)
			(copperpour not_allowed)
			(footprints allowed)
		)
		(placement
			(enabled no)
			(sheetname "")
		)
		(fill
			(thermal_gap 0.5)
			(thermal_bridge_width 0.5)
			(island_removal_mode 0)
		)
		(polygon
			(pts
				(xy 143.320008 -127.374142) (xy 143.878808 -127.374142) (xy 143.878808 -129.177542) (xy 143.320008 -129.177542)
			)
		)
	)
	(zone
		(layer "In12.Cu")
		(hatch none 0.5)
		(connect_pads
			(clearance 0)
		)
		(min_thickness 0.25)
		(keepout
			(tracks not_allowed)
			(vias allowed)
			(pads allowed)
			(copperpour not_allowed)
			(footprints allowed)
		)
		(placement
			(enabled no)
			(sheetname "")
		)
		(fill
			(thermal_gap 0.5)
			(thermal_bridge_width 0.5)
			(island_removal_mode 0)
		)
		(polygon
			(pts
				(xy 44.720002 -23.922482) (xy 45.278802 -23.922482) (xy 45.278802 -25.725882) (xy 44.720002 -25.725882)
			)
		)
	)
	(zone
		(layer "In12.Cu")
		(hatch none 0.5)
		(connect_pads
			(clearance 0)
		)
		(min_thickness 0.25)
		(keepout
			(tracks not_allowed)
			(vias allowed)
			(pads allowed)
			(copperpour not_allowed)
			(footprints allowed)
		)
		(placement
			(enabled no)
			(sheetname "")
		)
		(fill
			(thermal_gap 0.5)
			(thermal_bridge_width 0.5)
			(island_removal_mode 0)
		)
		(polygon
			(pts
				(xy 121.219976 -19.322542) (xy 121.778776 -19.322542) (xy 121.778776 -21.125942) (xy 121.219976 -21.125942)
			)
		)
	)
	(zone
		(layer "In12.Cu")
		(hatch none 0.5)
		(connect_pads
			(clearance 0)
		)
		(min_thickness 0.25)
		(keepout
			(tracks not_allowed)
			(vias allowed)
			(pads allowed)
			(copperpour not_allowed)
			(footprints allowed)
		)
		(placement
			(enabled no)
			(sheetname "")
		)
		(fill
			(thermal_gap 0.5)
			(thermal_bridge_width 0.5)
			(island_removal_mode 0)
		)
		(polygon
			(pts
				(xy 109.320076 -4.720082) (xy 109.878876 -4.720082) (xy 109.878876 -6.523482) (xy 109.320076 -6.523482)
			)
		)
	)
	(zone
		(layer "In12.Cu")
		(hatch none 0.5)
		(connect_pads
			(clearance 0)
		)
		(min_thickness 0.25)
		(keepout
			(tracks not_allowed)
			(vias allowed)
			(pads allowed)
			(copperpour not_allowed)
			(footprints allowed)
		)
		(placement
			(enabled no)
			(sheetname "")
		)
		(fill
			(thermal_gap 0.5)
			(thermal_bridge_width 0.5)
			(island_removal_mode 0)
		)
		(polygon
			(pts
				(xy 136.51992 -4.720082) (xy 137.07872 -4.720082) (xy 137.07872 -6.523482) (xy 136.51992 -6.523482)
			)
		)
	)
	(zone
		(layer "In12.Cu")
		(hatch none 0.5)
		(connect_pads
			(clearance 0)
		)
		(min_thickness 0.25)
		(keepout
			(tracks not_allowed)
			(vias allowed)
			(pads allowed)
			(copperpour not_allowed)
			(footprints allowed)
		)
		(placement
			(enabled no)
			(sheetname "")
		)
		(fill
			(thermal_gap 0.5)
			(thermal_bridge_width 0.5)
			(island_removal_mode 0)
		)
		(polygon
			(pts
				(xy 333.600806 -59.225434) (xy 333.600806 -61.511434) (xy 333.092806 -61.511434) (xy 333.092806 -59.225434)
			)
		)
	)
	(zone
		(layer "In12.Cu")
		(hatch none 0.5)
		(connect_pads
			(clearance 0)
		)
		(min_thickness 0.25)
		(keepout
			(tracks not_allowed)
			(vias allowed)
			(pads allowed)
			(copperpour not_allowed)
			(footprints allowed)
		)
		(placement
			(enabled no)
			(sheetname "")
		)
		(fill
			(thermal_gap 0.5)
			(thermal_bridge_width 0.5)
			(island_removal_mode 0)
		)
		(polygon
			(pts
				(xy 88.920066 -151.176482) (xy 89.478866 -151.176482) (xy 89.478866 -152.979882) (xy 88.920066 -152.979882)
			)
		)
	)
	(zone
		(layer "In12.Cu")
		(hatch none 0.5)
		(connect_pads
			(clearance 0)
		)
		(min_thickness 0.25)
		(keepout
			(tracks not_allowed)
			(vias allowed)
			(pads allowed)
			(copperpour not_allowed)
			(footprints allowed)
		)
		(placement
			(enabled no)
			(sheetname "")
		)
		(fill
			(thermal_gap 0.5)
			(thermal_bridge_width 0.5)
			(island_removal_mode 0)
		)
		(polygon
			(pts
				(xy 214.8205 -4.720082) (xy 215.3793 -4.720082) (xy 215.3793 -6.523482) (xy 214.8205 -6.523482)
			)
		)
	)
	(zone
		(layer "In12.Cu")
		(hatch none 0.5)
		(connect_pads
			(clearance 0)
		)
		(min_thickness 0.25)
		(keepout
			(tracks not_allowed)
			(vias allowed)
			(pads allowed)
			(copperpour not_allowed)
			(footprints allowed)
		)
		(placement
			(enabled no)
			(sheetname "")
		)
		(fill
			(thermal_gap 0.5)
			(thermal_bridge_width 0.5)
			(island_removal_mode 0)
		)
		(polygon
			(pts
				(xy 214.8205 -141.575282) (xy 215.3793 -141.575282) (xy 215.3793 -143.378682) (xy 214.8205 -143.378682)
			)
		)
	)
	(zone
		(layer "In12.Cu")
		(hatch none 0.5)
		(connect_pads
			(clearance 0)
		)
		(min_thickness 0.25)
		(keepout
			(tracks not_allowed)
			(vias allowed)
			(pads allowed)
			(copperpour not_allowed)
			(footprints allowed)
		)
		(placement
			(enabled no)
			(sheetname "")
		)
		(fill
			(thermal_gap 0.5)
			(thermal_bridge_width 0.5)
			(island_removal_mode 0)
		)
		(polygon
			(pts
				(xy 39.619936 -146.576542) (xy 40.178736 -146.576542) (xy 40.178736 -148.379942) (xy 39.619936 -148.379942)
			)
		)
	)
	(zone
		(layer "In12.Cu")
		(hatch none 0.5)
		(connect_pads
			(clearance 0)
		)
		(min_thickness 0.25)
		(keepout
			(tracks not_allowed)
			(vias allowed)
			(pads allowed)
			(copperpour not_allowed)
			(footprints allowed)
		)
		(placement
			(enabled no)
			(sheetname "")
		)
		(fill
			(thermal_gap 0.5)
			(thermal_bridge_width 0.5)
			(island_removal_mode 0)
		)
		(polygon
			(pts
				(xy 452.9582 -51.187858) (xy 453.4662 -51.187858) (xy 453.4662 -52.584858) (xy 452.9582 -52.584858)
			)
		)
	)
	(zone
		(layer "In12.Cu")
		(hatch none 0.5)
		(connect_pads
			(clearance 0)
		)
		(min_thickness 0.25)
		(keepout
			(tracks not_allowed)
			(vias allowed)
			(pads allowed)
			(copperpour not_allowed)
			(footprints allowed)
		)
		(placement
			(enabled no)
			(sheetname "")
		)
		(fill
			(thermal_gap 0.5)
			(thermal_bridge_width 0.5)
			(island_removal_mode 0)
		)
		(polygon
			(pts
				(xy 30.269942 -0.120142) (xy 30.828742 -0.120142) (xy 30.828742 -1.923542) (xy 30.269942 -1.923542)
			)
		)
	)
	(zone
		(layer "In12.Cu")
		(hatch none 0.5)
		(connect_pads
			(clearance 0)
		)
		(min_thickness 0.25)
		(keepout
			(tracks not_allowed)
			(vias allowed)
			(pads allowed)
			(copperpour not_allowed)
			(footprints allowed)
		)
		(placement
			(enabled no)
			(sheetname "")
		)
		(fill
			(thermal_gap 0.5)
			(thermal_bridge_width 0.5)
			(island_removal_mode 0)
		)
		(polygon
			(pts
				(xy 140.770102 -4.720082) (xy 141.328902 -4.720082) (xy 141.328902 -6.523482) (xy 140.770102 -6.523482)
			)
		)
	)
	(zone
		(net "PVDDQ_DEF")
		(layer "In12.Cu")
		(hatch none 0.5)
		(connect_pads
			(clearance 0.5)
		)
		(min_thickness 0.25)
		(fill yes
			(thermal_gap 0.5)
			(thermal_bridge_width 0.5)
			(island_removal_mode 0)
		)
		(polygon
			(pts
				(xy 265.254994 -138.8237) (xy 265.0109 -139.067794) (xy 265.0109 -139.798806) (xy 265.204194 -139.9921)
				(xy 267.967206 -139.9921) (xy 268.373606 -139.5857) (xy 268.805406 -139.5857) (xy 268.9225 -139.468606)
				(xy 268.9225 -139.067794) (xy 268.678406 -138.8237)
			)
		)
	)
	(zone
		(net "P12V_MB0_SW")
		(layer "In12.Cu")
		(hatch none 0.5)
		(connect_pads
			(clearance 0.5)
		)
		(min_thickness 0.25)
		(fill yes
			(thermal_gap 0.5)
			(thermal_bridge_width 0.5)
			(island_removal_mode 0)
		)
		(polygon
			(pts
				(xy 13.454126 -56.690514) (xy 13.119862 -57.024778) (xy 13.119862 -65.76568) (xy 15.207742 -67.85356)
				(xy 18.538698 -67.85356) (xy 19.070066 -67.322192) (xy 19.070066 -57.063894) (xy 18.696686 -56.690514)
			)
		)
	)
	(zone
		(layer "In12.Cu")
		(hatch none 0.5)
		(connect_pads
			(clearance 0)
		)
		(min_thickness 0.25)
		(keepout
			(tracks not_allowed)
			(vias allowed)
			(pads allowed)
			(copperpour not_allowed)
			(footprints allowed)
		)
		(placement
			(enabled no)
			(sheetname "")
		)
		(fill
			(thermal_gap 0.5)
			(thermal_bridge_width 0.5)
			(island_removal_mode 0)
		)
		(polygon
			(pts
				(xy 219.920566 -127.374142) (xy 220.479366 -127.374142) (xy 220.479366 -129.177542) (xy 219.920566 -129.177542)
			)
		)
	)
	(zone
		(layer "In12.Cu")
		(hatch none 0.5)
		(connect_pads
			(clearance 0)
		)
		(min_thickness 0.25)
		(keepout
			(tracks not_allowed)
			(vias allowed)
			(pads allowed)
			(copperpour not_allowed)
			(footprints allowed)
		)
		(placement
			(enabled no)
			(sheetname "")
		)
		(fill
			(thermal_gap 0.5)
			(thermal_bridge_width 0.5)
			(island_removal_mode 0)
		)
		(polygon
			(pts
				(xy 228.420422 -14.321282) (xy 228.979222 -14.321282) (xy 228.979222 -16.124682) (xy 228.420422 -16.124682)
			)
		)
	)
	(zone
		(layer "In12.Cu")
		(hatch none 0.5)
		(connect_pads
			(clearance 0)
		)
		(min_thickness 0.25)
		(keepout
			(tracks not_allowed)
			(vias allowed)
			(pads allowed)
			(copperpour not_allowed)
			(footprints allowed)
		)
		(placement
			(enabled no)
			(sheetname "")
		)
		(fill
			(thermal_gap 0.5)
			(thermal_bridge_width 0.5)
			(island_removal_mode 0)
		)
		(polygon
			(pts
				(xy 77.87005 -4.720082) (xy 78.42885 -4.720082) (xy 78.42885 -6.523482) (xy 77.87005 -6.523482)
			)
		)
	)
	(zone
		(layer "In12.Cu")
		(hatch none 0.5)
		(connect_pads
			(clearance 0)
		)
		(min_thickness 0.25)
		(keepout
			(tracks not_allowed)
			(vias allowed)
			(pads allowed)
			(copperpour not_allowed)
			(footprints allowed)
		)
		(placement
			(enabled no)
			(sheetname "")
		)
		(fill
			(thermal_gap 0.5)
			(thermal_bridge_width 0.5)
			(island_removal_mode 0)
		)
		(polygon
			(pts
				(xy 71.069962 -19.322542) (xy 71.628762 -19.322542) (xy 71.628762 -21.125942) (xy 71.069962 -21.125942)
			)
		)
	)
	(zone
		(layer "In12.Cu")
		(hatch none 0.5)
		(connect_pads
			(clearance 0)
		)
		(min_thickness 0.25)
		(keepout
			(tracks not_allowed)
			(vias allowed)
			(pads allowed)
			(copperpour not_allowed)
			(footprints allowed)
		)
		(placement
			(enabled no)
			(sheetname "")
		)
		(fill
			(thermal_gap 0.5)
			(thermal_bridge_width 0.5)
			(island_removal_mode 0)
		)
		(polygon
			(pts
				(xy 384.963924 -24.631904) (xy 386.360924 -24.631904) (xy 386.360924 -25.139904) (xy 384.963924 -25.139904)
			)
		)
	)
	(zone
		(layer "In12.Cu")
		(hatch none 0.5)
		(connect_pads
			(clearance 0)
		)
		(min_thickness 0.25)
		(keepout
			(tracks not_allowed)
			(vias allowed)
			(pads allowed)
			(copperpour not_allowed)
			(footprints allowed)
		)
		(placement
			(enabled no)
			(sheetname "")
		)
		(fill
			(thermal_gap 0.5)
			(thermal_bridge_width 0.5)
			(island_removal_mode 0)
		)
		(polygon
			(pts
				(xy 296.42054 -131.974082) (xy 296.97934 -131.974082) (xy 296.97934 -133.777482) (xy 296.42054 -133.777482)
			)
		)
	)
	(zone
		(layer "In12.Cu")
		(hatch none 0.5)
		(connect_pads
			(clearance 0)
		)
		(min_thickness 0.25)
		(keepout
			(tracks not_allowed)
			(vias allowed)
			(pads allowed)
			(copperpour not_allowed)
			(footprints allowed)
		)
		(placement
			(enabled no)
			(sheetname "")
		)
		(fill
			(thermal_gap 0.5)
			(thermal_bridge_width 0.5)
			(island_removal_mode 0)
		)
		(polygon
			(pts
				(xy 117.819932 -151.176482) (xy 118.378732 -151.176482) (xy 118.378732 -152.979882) (xy 117.819932 -152.979882)
			)
		)
	)
	(zone
		(layer "In12.Cu")
		(hatch none 0.5)
		(connect_pads
			(clearance 0)
		)
		(min_thickness 0.25)
		(keepout
			(tracks not_allowed)
			(vias allowed)
			(pads allowed)
			(copperpour not_allowed)
			(footprints allowed)
		)
		(placement
			(enabled no)
			(sheetname "")
		)
		(fill
			(thermal_gap 0.5)
			(thermal_bridge_width 0.5)
			(island_removal_mode 0)
		)
		(polygon
			(pts
				(xy 247.970548 -146.576542) (xy 248.529348 -146.576542) (xy 248.529348 -148.379942) (xy 247.970548 -148.379942)
			)
		)
	)
	(zone
		(layer "In12.Cu")
		(hatch none 0.5)
		(connect_pads
			(clearance 0)
		)
		(min_thickness 0.25)
		(keepout
			(tracks not_allowed)
			(vias allowed)
			(pads allowed)
			(copperpour not_allowed)
			(footprints allowed)
		)
		(placement
			(enabled no)
			(sheetname "")
		)
		(fill
			(thermal_gap 0.5)
			(thermal_bridge_width 0.5)
			(island_removal_mode 0)
		)
		(polygon
			(pts
				(xy 230.970582 -0.120142) (xy 231.529382 -0.120142) (xy 231.529382 -1.923542) (xy 230.970582 -1.923542)
			)
		)
	)
	(zone
		(layer "In12.Cu")
		(hatch none 0.5)
		(connect_pads
			(clearance 0)
		)
		(min_thickness 0.25)
		(keepout
			(tracks not_allowed)
			(vias allowed)
			(pads allowed)
			(copperpour not_allowed)
			(footprints allowed)
		)
		(placement
			(enabled no)
			(sheetname "")
		)
		(fill
			(thermal_gap 0.5)
			(thermal_bridge_width 0.5)
			(island_removal_mode 0)
		)
		(polygon
			(pts
				(xy 200.37044 -4.720082) (xy 200.92924 -4.720082) (xy 200.92924 -6.523482) (xy 200.37044 -6.523482)
			)
		)
	)
	(zone
		(layer "In12.Cu")
		(hatch none 0.5)
		(connect_pads
			(clearance 0)
		)
		(min_thickness 0.25)
		(keepout
			(tracks not_allowed)
			(vias allowed)
			(pads allowed)
			(copperpour not_allowed)
			(footprints allowed)
		)
		(placement
			(enabled no)
			(sheetname "")
		)
		(fill
			(thermal_gap 0.5)
			(thermal_bridge_width 0.5)
			(island_removal_mode 0)
		)
		(polygon
			(pts
				(xy 267.52042 -131.974082) (xy 268.07922 -131.974082) (xy 268.07922 -133.777482) (xy 267.52042 -133.777482)
			)
		)
	)
	(zone
		(layer "In12.Cu")
		(hatch none 0.5)
		(connect_pads
			(clearance 0)
		)
		(min_thickness 0.25)
		(keepout
			(tracks not_allowed)
			(vias allowed)
			(pads allowed)
			(copperpour not_allowed)
			(footprints allowed)
		)
		(placement
			(enabled no)
			(sheetname "")
		)
		(fill
			(thermal_gap 0.5)
			(thermal_bridge_width 0.5)
			(island_removal_mode 0)
		)
		(polygon
			(pts
				(xy 282.820364 -14.321282) (xy 283.379164 -14.321282) (xy 283.379164 -16.124682) (xy 282.820364 -16.124682)
			)
		)
	)
	(zone
		(layer "In12.Cu")
		(hatch none 0.5)
		(connect_pads
			(clearance 0)
		)
		(min_thickness 0.25)
		(keepout
			(tracks not_allowed)
			(vias allowed)
			(pads allowed)
			(copperpour not_allowed)
			(footprints allowed)
		)
		(placement
			(enabled no)
			(sheetname "")
		)
		(fill
			(thermal_gap 0.5)
			(thermal_bridge_width 0.5)
			(island_removal_mode 0)
		)
		(polygon
			(pts
				(xy 315.970412 -0.120142) (xy 316.529212 -0.120142) (xy 316.529212 -1.923542) (xy 315.970412 -1.923542)
			)
		)
	)
	(zone
		(layer "In12.Cu")
		(hatch none 0.5)
		(connect_pads
			(clearance 0)
		)
		(min_thickness 0.25)
		(keepout
			(tracks not_allowed)
			(vias allowed)
			(pads allowed)
			(copperpour not_allowed)
			(footprints allowed)
		)
		(placement
			(enabled no)
			(sheetname "")
		)
		(fill
			(thermal_gap 0.5)
			(thermal_bridge_width 0.5)
			(island_removal_mode 0)
		)
		(polygon
			(pts
				(xy 89.76995 -127.374142) (xy 90.32875 -127.374142) (xy 90.32875 -129.177542) (xy 89.76995 -129.177542)
			)
		)
	)
	(zone
		(layer "In12.Cu")
		(hatch none 0.5)
		(connect_pads
			(clearance 0)
		)
		(min_thickness 0.25)
		(keepout
			(tracks not_allowed)
			(vias allowed)
			(pads allowed)
			(copperpour not_allowed)
			(footprints allowed)
		)
		(placement
			(enabled no)
			(sheetname "")
		)
		(fill
			(thermal_gap 0.5)
			(thermal_bridge_width 0.5)
			(island_removal_mode 0)
		)
		(polygon
			(pts
				(xy 208.020412 -146.576542) (xy 208.579212 -146.576542) (xy 208.579212 -148.379942) (xy 208.020412 -148.379942)
			)
		)
	)
	(zone
		(layer "In12.Cu")
		(hatch none 0.5)
		(connect_pads
			(clearance 0)
		)
		(min_thickness 0.25)
		(keepout
			(tracks not_allowed)
			(vias allowed)
			(pads allowed)
			(copperpour not_allowed)
			(footprints allowed)
		)
		(placement
			(enabled no)
			(sheetname "")
		)
		(fill
			(thermal_gap 0.5)
			(thermal_bridge_width 0.5)
			(island_removal_mode 0)
		)
		(polygon
			(pts
				(xy 300.670468 -136.975342) (xy 301.229268 -136.975342) (xy 301.229268 -138.778742) (xy 300.670468 -138.778742)
			)
		)
	)
	(zone
		(layer "In12.Cu")
		(hatch none 0.5)
		(connect_pads
			(clearance 0)
		)
		(min_thickness 0.25)
		(keepout
			(tracks not_allowed)
			(vias allowed)
			(pads allowed)
			(copperpour not_allowed)
			(footprints allowed)
		)
		(placement
			(enabled no)
			(sheetname "")
		)
		(fill
			(thermal_gap 0.5)
			(thermal_bridge_width 0.5)
			(island_removal_mode 0)
		)
		(polygon
			(pts
				(xy 135.670036 -146.576542) (xy 136.228836 -146.576542) (xy 136.228836 -148.379942) (xy 135.670036 -148.379942)
			)
		)
	)
	(zone
		(layer "In12.Cu")
		(hatch none 0.5)
		(connect_pads
			(clearance 0)
		)
		(min_thickness 0.25)
		(keepout
			(tracks not_allowed)
			(vias allowed)
			(pads allowed)
			(copperpour not_allowed)
			(footprints allowed)
		)
		(placement
			(enabled no)
			(sheetname "")
		)
		(fill
			(thermal_gap 0.5)
			(thermal_bridge_width 0.5)
			(island_removal_mode 0)
		)
		(polygon
			(pts
				(xy 276.02053 -146.576542) (xy 276.57933 -146.576542) (xy 276.57933 -148.379942) (xy 276.02053 -148.379942)
			)
		)
	)
	(zone
		(layer "In12.Cu")
		(hatch none 0.5)
		(connect_pads
			(clearance 0)
		)
		(min_thickness 0.25)
		(keepout
			(tracks not_allowed)
			(vias allowed)
			(pads allowed)
			(copperpour not_allowed)
			(footprints allowed)
		)
		(placement
			(enabled no)
			(sheetname "")
		)
		(fill
			(thermal_gap 0.5)
			(thermal_bridge_width 0.5)
			(island_removal_mode 0)
		)
		(polygon
			(pts
				(xy 209.720434 -131.974082) (xy 210.279234 -131.974082) (xy 210.279234 -133.777482) (xy 209.720434 -133.777482)
			)
		)
	)
	(zone
		(layer "In12.Cu")
		(hatch none 0.5)
		(connect_pads
			(clearance 0)
		)
		(min_thickness 0.25)
		(keepout
			(tracks not_allowed)
			(vias allowed)
			(pads allowed)
			(copperpour not_allowed)
			(footprints allowed)
		)
		(placement
			(enabled no)
			(sheetname "")
		)
		(fill
			(thermal_gap 0.5)
			(thermal_bridge_width 0.5)
			(island_removal_mode 0)
		)
		(polygon
			(pts
				(xy 133.119876 -141.575282) (xy 133.678676 -141.575282) (xy 133.678676 -143.378682) (xy 133.119876 -143.378682)
			)
		)
	)
	(zone
		(layer "In12.Cu")
		(hatch none 0.5)
		(connect_pads
			(clearance 0)
		)
		(min_thickness 0.25)
		(keepout
			(tracks not_allowed)
			(vias allowed)
			(pads allowed)
			(copperpour not_allowed)
			(footprints allowed)
		)
		(placement
			(enabled no)
			(sheetname "")
		)
		(fill
			(thermal_gap 0.5)
			(thermal_bridge_width 0.5)
			(island_removal_mode 0)
		)
		(polygon
			(pts
				(xy 346.086176 -76.551536) (xy 346.086176 -78.837536) (xy 345.578176 -78.837536) (xy 345.578176 -76.551536)
			)
		)
	)
	(zone
		(layer "In12.Cu")
		(hatch none 0.5)
		(connect_pads
			(clearance 0)
		)
		(min_thickness 0.25)
		(keepout
			(tracks not_allowed)
			(vias allowed)
			(pads allowed)
			(copperpour not_allowed)
			(footprints allowed)
		)
		(placement
			(enabled no)
			(sheetname "")
		)
		(fill
			(thermal_gap 0.5)
			(thermal_bridge_width 0.5)
			(island_removal_mode 0)
		)
		(polygon
			(pts
				(xy 105.070148 -9.721342) (xy 105.628948 -9.721342) (xy 105.628948 -11.524742) (xy 105.070148 -11.524742)
			)
		)
	)
	(zone
		(layer "In12.Cu")
		(hatch none 0.5)
		(connect_pads
			(clearance 0)
		)
		(min_thickness 0.25)
		(keepout
			(tracks not_allowed)
			(vias allowed)
			(pads allowed)
			(copperpour not_allowed)
			(footprints allowed)
		)
		(placement
			(enabled no)
			(sheetname "")
		)
		(fill
			(thermal_gap 0.5)
			(thermal_bridge_width 0.5)
			(island_removal_mode 0)
		)
		(polygon
			(pts
				(xy 253.070614 -146.576542) (xy 253.629414 -146.576542) (xy 253.629414 -148.379942) (xy 253.070614 -148.379942)
			)
		)
	)
	(zone
		(layer "In12.Cu")
		(hatch none 0.5)
		(connect_pads
			(clearance 0)
		)
		(min_thickness 0.25)
		(keepout
			(tracks not_allowed)
			(vias allowed)
			(pads allowed)
			(copperpour not_allowed)
			(footprints allowed)
		)
		(placement
			(enabled no)
			(sheetname "")
		)
		(fill
			(thermal_gap 0.5)
			(thermal_bridge_width 0.5)
			(island_removal_mode 0)
		)
		(polygon
			(pts
				(xy 302.37049 -127.374142) (xy 302.92929 -127.374142) (xy 302.92929 -129.177542) (xy 302.37049 -129.177542)
			)
		)
	)
	(zone
		(layer "In12.Cu")
		(hatch none 0.5)
		(connect_pads
			(clearance 0)
		)
		(min_thickness 0.25)
		(keepout
			(tracks not_allowed)
			(vias allowed)
			(pads allowed)
			(copperpour not_allowed)
			(footprints allowed)
		)
		(placement
			(enabled no)
			(sheetname "")
		)
		(fill
			(thermal_gap 0.5)
			(thermal_bridge_width 0.5)
			(island_removal_mode 0)
		)
		(polygon
			(pts
				(xy 368.963956 -122.814842) (xy 366.677956 -122.814842) (xy 366.677956 -122.306842) (xy 368.963956 -122.306842)
			)
		)
	)
	(zone
		(layer "In12.Cu")
		(hatch none 0.5)
		(connect_pads
			(clearance 0)
		)
		(min_thickness 0.25)
		(keepout
			(tracks not_allowed)
			(vias allowed)
			(pads allowed)
			(copperpour not_allowed)
			(footprints allowed)
		)
		(placement
			(enabled no)
			(sheetname "")
		)
		(fill
			(thermal_gap 0.5)
			(thermal_bridge_width 0.5)
			(island_removal_mode 0)
		)
		(polygon
			(pts
				(xy 143.320008 -0.120142) (xy 143.878808 -0.120142) (xy 143.878808 -1.923542) (xy 143.320008 -1.923542)
			)
		)
	)
	(zone
		(layer "In12.Cu")
		(hatch none 0.5)
		(connect_pads
			(clearance 0)
		)
		(min_thickness 0.25)
		(keepout
			(tracks not_allowed)
			(vias allowed)
			(pads allowed)
			(copperpour not_allowed)
			(footprints allowed)
		)
		(placement
			(enabled no)
			(sheetname "")
		)
		(fill
			(thermal_gap 0.5)
			(thermal_bridge_width 0.5)
			(island_removal_mode 0)
		)
		(polygon
			(pts
				(xy 410.9212 -146.05) (xy 410.9212 -146.812) (xy 411.9118 -146.812) (xy 411.9118 -146.05)
			)
		)
	)
	(zone
		(layer "In12.Cu")
		(hatch none 0.5)
		(connect_pads
			(clearance 0)
		)
		(min_thickness 0.25)
		(keepout
			(tracks not_allowed)
			(vias allowed)
			(pads allowed)
			(copperpour not_allowed)
			(footprints allowed)
		)
		(placement
			(enabled no)
			(sheetname "")
		)
		(fill
			(thermal_gap 0.5)
			(thermal_bridge_width 0.5)
			(island_removal_mode 0)
		)
		(polygon
			(pts
				(xy 223.320356 -9.721342) (xy 223.879156 -9.721342) (xy 223.879156 -11.524742) (xy 223.320356 -11.524742)
			)
		)
	)
	(zone
		(layer "In12.Cu")
		(hatch none 0.5)
		(connect_pads
			(clearance 0)
		)
		(min_thickness 0.25)
		(keepout
			(tracks not_allowed)
			(vias allowed)
			(pads allowed)
			(copperpour not_allowed)
			(footprints allowed)
		)
		(placement
			(enabled no)
			(sheetname "")
		)
		(fill
			(thermal_gap 0.5)
			(thermal_bridge_width 0.5)
			(island_removal_mode 0)
		)
		(polygon
			(pts
				(xy 82.119978 -151.176482) (xy 82.678778 -151.176482) (xy 82.678778 -152.979882) (xy 82.119978 -152.979882)
			)
		)
	)
	(zone
		(layer "In12.Cu")
		(hatch none 0.5)
		(connect_pads
			(clearance 0)
		)
		(min_thickness 0.25)
		(keepout
			(tracks not_allowed)
			(vias allowed)
			(pads allowed)
			(copperpour not_allowed)
			(footprints allowed)
		)
		(placement
			(enabled no)
			(sheetname "")
		)
		(fill
			(thermal_gap 0.5)
			(thermal_bridge_width 0.5)
			(island_removal_mode 0)
		)
		(polygon
			(pts
				(xy 247.12041 -4.720082) (xy 247.67921 -4.720082) (xy 247.67921 -6.523482) (xy 247.12041 -6.523482)
			)
		)
	)
	(zone
		(layer "In12.Cu")
		(hatch none 0.5)
		(connect_pads
			(clearance 0)
		)
		(min_thickness 0.25)
		(keepout
			(tracks not_allowed)
			(vias allowed)
			(pads allowed)
			(copperpour not_allowed)
			(footprints allowed)
		)
		(placement
			(enabled no)
			(sheetname "")
		)
		(fill
			(thermal_gap 0.5)
			(thermal_bridge_width 0.5)
			(island_removal_mode 0)
		)
		(polygon
			(pts
				(xy 238.620554 -136.975342) (xy 239.179354 -136.975342) (xy 239.179354 -138.778742) (xy 238.620554 -138.778742)
			)
		)
	)
	(zone
		(layer "In12.Cu")
		(hatch none 0.5)
		(connect_pads
			(clearance 0)
		)
		(min_thickness 0.25)
		(keepout
			(tracks not_allowed)
			(vias allowed)
			(pads allowed)
			(copperpour not_allowed)
			(footprints allowed)
		)
		(placement
			(enabled no)
			(sheetname "")
		)
		(fill
			(thermal_gap 0.5)
			(thermal_bridge_width 0.5)
			(island_removal_mode 0)
		)
		(polygon
			(pts
				(xy 311.720484 -141.575282) (xy 312.279284 -141.575282) (xy 312.279284 -143.378682) (xy 311.720484 -143.378682)
			)
		)
	)
	(zone
		(layer "In12.Cu")
		(hatch none 0.5)
		(connect_pads
			(clearance 0)
		)
		(min_thickness 0.25)
		(keepout
			(tracks not_allowed)
			(vias allowed)
			(pads allowed)
			(copperpour not_allowed)
			(footprints allowed)
		)
		(placement
			(enabled no)
			(sheetname "")
		)
		(fill
			(thermal_gap 0.5)
			(thermal_bridge_width 0.5)
			(island_removal_mode 0)
		)
		(polygon
			(pts
				(xy 292.170358 -131.974082) (xy 292.729158 -131.974082) (xy 292.729158 -133.777482) (xy 292.170358 -133.777482)
			)
		)
	)
	(zone
		(layer "In12.Cu")
		(hatch none 0.5)
		(connect_pads
			(clearance 0)
		)
		(min_thickness 0.25)
		(keepout
			(tracks not_allowed)
			(vias allowed)
			(pads allowed)
			(copperpour not_allowed)
			(footprints allowed)
		)
		(placement
			(enabled no)
			(sheetname "")
		)
		(fill
			(thermal_gap 0.5)
			(thermal_bridge_width 0.5)
			(island_removal_mode 0)
		)
		(polygon
			(pts
				(xy 150.96998 -19.322542) (xy 151.52878 -19.322542) (xy 151.52878 -21.125942) (xy 150.96998 -21.125942)
			)
		)
	)
	(zone
		(layer "In12.Cu")
		(hatch none 0.5)
		(connect_pads
			(clearance 0)
		)
		(min_thickness 0.25)
		(keepout
			(tracks not_allowed)
			(vias allowed)
			(pads allowed)
			(copperpour not_allowed)
			(footprints allowed)
		)
		(placement
			(enabled no)
			(sheetname "")
		)
		(fill
			(thermal_gap 0.5)
			(thermal_bridge_width 0.5)
			(island_removal_mode 0)
		)
		(polygon
			(pts
				(xy 35.370008 -136.975342) (xy 35.928808 -136.975342) (xy 35.928808 -138.778742) (xy 35.370008 -138.778742)
			)
		)
	)
	(zone
		(layer "In12.Cu")
		(hatch none 0.5)
		(connect_pads
			(clearance 0)
		)
		(min_thickness 0.25)
		(keepout
			(tracks not_allowed)
			(vias allowed)
			(pads allowed)
			(copperpour not_allowed)
			(footprints allowed)
		)
		(placement
			(enabled no)
			(sheetname "")
		)
		(fill
			(thermal_gap 0.5)
			(thermal_bridge_width 0.5)
			(island_removal_mode 0)
		)
		(polygon
			(pts
				(xy 285.370524 -23.922482) (xy 285.929324 -23.922482) (xy 285.929324 -25.725882) (xy 285.370524 -25.725882)
			)
		)
	)
	(zone
		(layer "In12.Cu")
		(hatch none 0.5)
		(connect_pads
			(clearance 0)
		)
		(min_thickness 0.25)
		(keepout
			(tracks not_allowed)
			(vias allowed)
			(pads allowed)
			(copperpour not_allowed)
			(footprints allowed)
		)
		(placement
			(enabled no)
			(sheetname "")
		)
		(fill
			(thermal_gap 0.5)
			(thermal_bridge_width 0.5)
			(island_removal_mode 0)
		)
		(polygon
			(pts
				(xy 52.369974 -0.120142) (xy 52.928774 -0.120142) (xy 52.928774 -1.923542) (xy 52.369974 -1.923542)
			)
		)
	)
	(zone
		(layer "In12.Cu")
		(hatch none 0.5)
		(connect_pads
			(clearance 0)
		)
		(min_thickness 0.25)
		(keepout
			(tracks not_allowed)
			(vias allowed)
			(pads allowed)
			(copperpour not_allowed)
			(footprints allowed)
		)
		(placement
			(enabled no)
			(sheetname "")
		)
		(fill
			(thermal_gap 0.5)
			(thermal_bridge_width 0.5)
			(island_removal_mode 0)
		)
		(polygon
			(pts
				(xy 75.320144 -9.721342) (xy 75.878944 -9.721342) (xy 75.878944 -11.524742) (xy 75.320144 -11.524742)
			)
		)
	)
	(zone
		(layer "In12.Cu")
		(hatch none 0.5)
		(connect_pads
			(clearance 0)
		)
		(min_thickness 0.25)
		(keepout
			(tracks not_allowed)
			(vias allowed)
			(pads allowed)
			(copperpour not_allowed)
			(footprints allowed)
		)
		(placement
			(enabled no)
			(sheetname "")
		)
		(fill
			(thermal_gap 0.5)
			(thermal_bridge_width 0.5)
			(island_removal_mode 0)
		)
		(polygon
			(pts
				(xy 264.970514 -9.721342) (xy 265.529314 -9.721342) (xy 265.529314 -11.524742) (xy 264.970514 -11.524742)
			)
		)
	)
	(zone
		(layer "In12.Cu")
		(hatch none 0.5)
		(connect_pads
			(clearance 0)
		)
		(min_thickness 0.25)
		(keepout
			(tracks not_allowed)
			(vias allowed)
			(pads allowed)
			(copperpour not_allowed)
			(footprints allowed)
		)
		(placement
			(enabled no)
			(sheetname "")
		)
		(fill
			(thermal_gap 0.5)
			(thermal_bridge_width 0.5)
			(island_removal_mode 0)
		)
		(polygon
			(pts
				(xy 270.07058 -9.721342) (xy 270.62938 -9.721342) (xy 270.62938 -11.524742) (xy 270.07058 -11.524742)
			)
		)
	)
	(zone
		(layer "In12.Cu")
		(hatch none 0.5)
		(connect_pads
			(clearance 0)
		)
		(min_thickness 0.25)
		(keepout
			(tracks not_allowed)
			(vias allowed)
			(pads allowed)
			(copperpour not_allowed)
			(footprints allowed)
		)
		(placement
			(enabled no)
			(sheetname "")
		)
		(fill
			(thermal_gap 0.5)
			(thermal_bridge_width 0.5)
			(island_removal_mode 0)
		)
		(polygon
			(pts
				(xy 235.22051 -141.575282) (xy 235.77931 -141.575282) (xy 235.77931 -143.378682) (xy 235.22051 -143.378682)
			)
		)
	)
	(zone
		(layer "In12.Cu")
		(hatch none 0.5)
		(connect_pads
			(clearance 0)
		)
		(min_thickness 0.25)
		(keepout
			(tracks not_allowed)
			(vias allowed)
			(pads allowed)
			(copperpour not_allowed)
			(footprints allowed)
		)
		(placement
			(enabled no)
			(sheetname "")
		)
		(fill
			(thermal_gap 0.5)
			(thermal_bridge_width 0.5)
			(island_removal_mode 0)
		)
		(polygon
			(pts
				(xy 225.020378 -136.975342) (xy 225.579178 -136.975342) (xy 225.579178 -138.778742) (xy 225.020378 -138.778742)
			)
		)
	)
	(zone
		(layer "In12.Cu")
		(hatch none 0.5)
		(connect_pads
			(clearance 0)
		)
		(min_thickness 0.25)
		(keepout
			(tracks not_allowed)
			(vias allowed)
			(pads allowed)
			(copperpour not_allowed)
			(footprints allowed)
		)
		(placement
			(enabled no)
			(sheetname "")
		)
		(fill
			(thermal_gap 0.5)
			(thermal_bridge_width 0.5)
			(island_removal_mode 0)
		)
		(polygon
			(pts
				(xy 89.76995 -23.922482) (xy 90.32875 -23.922482) (xy 90.32875 -25.725882) (xy 89.76995 -25.725882)
			)
		)
	)
	(zone
		(layer "In12.Cu")
		(hatch none 0.5)
		(connect_pads
			(clearance 0)
		)
		(min_thickness 0.25)
		(keepout
			(tracks not_allowed)
			(vias allowed)
			(pads allowed)
			(copperpour not_allowed)
			(footprints allowed)
		)
		(placement
			(enabled no)
			(sheetname "")
		)
		(fill
			(thermal_gap 0.5)
			(thermal_bridge_width 0.5)
			(island_removal_mode 0)
		)
		(polygon
			(pts
				(xy 12.14882 -102.21468) (xy 13.54582 -102.21468) (xy 13.54582 -102.72268) (xy 12.14882 -102.72268)
			)
		)
	)
	(zone
		(layer "In12.Cu")
		(hatch none 0.5)
		(connect_pads
			(clearance 0)
		)
		(min_thickness 0.25)
		(keepout
			(tracks not_allowed)
			(vias allowed)
			(pads allowed)
			(copperpour not_allowed)
			(footprints allowed)
		)
		(placement
			(enabled no)
			(sheetname "")
		)
		(fill
			(thermal_gap 0.5)
			(thermal_bridge_width 0.5)
			(island_removal_mode 0)
		)
		(polygon
			(pts
				(xy 150.120096 -4.720082) (xy 150.678896 -4.720082) (xy 150.678896 -6.523482) (xy 150.120096 -6.523482)
			)
		)
	)
	(zone
		(layer "In12.Cu")
		(hatch none 0.5)
		(connect_pads
			(clearance 0)
		)
		(min_thickness 0.25)
		(keepout
			(tracks not_allowed)
			(vias allowed)
			(pads allowed)
			(copperpour not_allowed)
			(footprints allowed)
		)
		(placement
			(enabled no)
			(sheetname "")
		)
		(fill
			(thermal_gap 0.5)
			(thermal_bridge_width 0.5)
			(island_removal_mode 0)
		)
		(polygon
			(pts
				(xy 92.32011 -146.576542) (xy 92.87891 -146.576542) (xy 92.87891 -148.379942) (xy 92.32011 -148.379942)
			)
		)
	)
	(zone
		(layer "In12.Cu")
		(hatch none 0.5)
		(connect_pads
			(clearance 0)
		)
		(min_thickness 0.25)
		(keepout
			(tracks not_allowed)
			(vias allowed)
			(pads allowed)
			(copperpour not_allowed)
			(footprints allowed)
		)
		(placement
			(enabled no)
			(sheetname "")
		)
		(fill
			(thermal_gap 0.5)
			(thermal_bridge_width 0.5)
			(island_removal_mode 0)
		)
		(polygon
			(pts
				(xy 220.77045 -4.720082) (xy 221.32925 -4.720082) (xy 221.32925 -6.523482) (xy 220.77045 -6.523482)
			)
		)
	)
	(zone
		(layer "In12.Cu")
		(hatch none 0.5)
		(connect_pads
			(clearance 0)
		)
		(min_thickness 0.25)
		(keepout
			(tracks not_allowed)
			(vias allowed)
			(pads allowed)
			(copperpour not_allowed)
			(footprints allowed)
		)
		(placement
			(enabled no)
			(sheetname "")
		)
		(fill
			(thermal_gap 0.5)
			(thermal_bridge_width 0.5)
			(island_removal_mode 0)
		)
		(polygon
			(pts
				(xy 114.419888 -141.575282) (xy 114.978688 -141.575282) (xy 114.978688 -143.378682) (xy 114.419888 -143.378682)
			)
		)
	)
	(zone
		(layer "In12.Cu")
		(hatch none 0.5)
		(connect_pads
			(clearance 0)
		)
		(min_thickness 0.25)
		(keepout
			(tracks not_allowed)
			(vias allowed)
			(pads allowed)
			(copperpour not_allowed)
			(footprints allowed)
		)
		(placement
			(enabled no)
			(sheetname "")
		)
		(fill
			(thermal_gap 0.5)
			(thermal_bridge_width 0.5)
			(island_removal_mode 0)
		)
		(polygon
			(pts
				(xy 424.815 -142.0368) (xy 425.577 -142.0368) (xy 425.577 -141.0462) (xy 424.815 -141.0462)
			)
		)
	)
	(zone
		(layer "In12.Cu")
		(hatch none 0.5)
		(connect_pads
			(clearance 0)
		)
		(min_thickness 0.25)
		(keepout
			(tracks not_allowed)
			(vias allowed)
			(pads allowed)
			(copperpour not_allowed)
			(footprints allowed)
		)
		(placement
			(enabled no)
			(sheetname "")
		)
		(fill
			(thermal_gap 0.5)
			(thermal_bridge_width 0.5)
			(island_removal_mode 0)
		)
		(polygon
			(pts
				(xy 300.670468 -0.120142) (xy 301.229268 -0.120142) (xy 301.229268 -1.923542) (xy 300.670468 -1.923542)
			)
		)
	)
	(zone
		(layer "In12.Cu")
		(hatch none 0.5)
		(connect_pads
			(clearance 0)
		)
		(min_thickness 0.25)
		(keepout
			(tracks not_allowed)
			(vias allowed)
			(pads allowed)
			(copperpour not_allowed)
			(footprints allowed)
		)
		(placement
			(enabled no)
			(sheetname "")
		)
		(fill
			(thermal_gap 0.5)
			(thermal_bridge_width 0.5)
			(island_removal_mode 0)
		)
		(polygon
			(pts
				(xy 137.370058 -131.974082) (xy 137.928858 -131.974082) (xy 137.928858 -133.777482) (xy 137.370058 -133.777482)
			)
		)
	)
	(zone
		(layer "In12.Cu")
		(hatch none 0.5)
		(connect_pads
			(clearance 0)
		)
		(min_thickness 0.25)
		(keepout
			(tracks not_allowed)
			(vias allowed)
			(pads allowed)
			(copperpour not_allowed)
			(footprints allowed)
		)
		(placement
			(enabled no)
			(sheetname "")
		)
		(fill
			(thermal_gap 0.5)
			(thermal_bridge_width 0.5)
			(island_removal_mode 0)
		)
		(polygon
			(pts
				(xy 74.470006 -151.176482) (xy 75.028806 -151.176482) (xy 75.028806 -152.979882) (xy 74.470006 -152.979882)
			)
		)
	)
	(zone
		(layer "In12.Cu")
		(hatch none 0.5)
		(connect_pads
			(clearance 0)
		)
		(min_thickness 0.25)
		(keepout
			(tracks not_allowed)
			(vias allowed)
			(pads allowed)
			(copperpour not_allowed)
			(footprints allowed)
		)
		(placement
			(enabled no)
			(sheetname "")
		)
		(fill
			(thermal_gap 0.5)
			(thermal_bridge_width 0.5)
			(island_removal_mode 0)
		)
		(polygon
			(pts
				(xy 35.370008 -127.374142) (xy 35.928808 -127.374142) (xy 35.928808 -129.177542) (xy 35.370008 -129.177542)
			)
		)
	)
	(zone
		(layer "In12.Cu")
		(hatch none 0.5)
		(connect_pads
			(clearance 0)
		)
		(min_thickness 0.25)
		(keepout
			(tracks not_allowed)
			(vias allowed)
			(pads allowed)
			(copperpour not_allowed)
			(footprints allowed)
		)
		(placement
			(enabled no)
			(sheetname "")
		)
		(fill
			(thermal_gap 0.5)
			(thermal_bridge_width 0.5)
			(island_removal_mode 0)
		)
		(polygon
			(pts
				(xy 66.820034 -4.720082) (xy 67.378834 -4.720082) (xy 67.378834 -6.523482) (xy 66.820034 -6.523482)
			)
		)
	)
	(zone
		(layer "In12.Cu")
		(hatch none 0.5)
		(connect_pads
			(clearance 0)
		)
		(min_thickness 0.25)
		(keepout
			(tracks not_allowed)
			(vias allowed)
			(pads allowed)
			(copperpour not_allowed)
			(footprints allowed)
		)
		(placement
			(enabled no)
			(sheetname "")
		)
		(fill
			(thermal_gap 0.5)
			(thermal_bridge_width 0.5)
			(island_removal_mode 0)
		)
		(polygon
			(pts
				(xy 31.969964 -0.120142) (xy 32.528764 -0.120142) (xy 32.528764 -1.923542) (xy 31.969964 -1.923542)
			)
		)
	)
	(zone
		(layer "In12.Cu")
		(hatch none 0.5)
		(connect_pads
			(clearance 0)
		)
		(min_thickness 0.25)
		(keepout
			(tracks not_allowed)
			(vias allowed)
			(pads allowed)
			(copperpour not_allowed)
			(footprints allowed)
		)
		(placement
			(enabled no)
			(sheetname "")
		)
		(fill
			(thermal_gap 0.5)
			(thermal_bridge_width 0.5)
			(island_removal_mode 0)
		)
		(polygon
			(pts
				(xy 310.870346 -151.176482) (xy 311.429146 -151.176482) (xy 311.429146 -152.979882) (xy 310.870346 -152.979882)
			)
		)
	)
	(zone
		(layer "In12.Cu")
		(hatch none 0.5)
		(connect_pads
			(clearance 0)
		)
		(min_thickness 0.25)
		(keepout
			(tracks not_allowed)
			(vias allowed)
			(pads allowed)
			(copperpour not_allowed)
			(footprints allowed)
		)
		(placement
			(enabled no)
			(sheetname "")
		)
		(fill
			(thermal_gap 0.5)
			(thermal_bridge_width 0.5)
			(island_removal_mode 0)
		)
		(polygon
			(pts
				(xy 138.219942 -127.374142) (xy 138.778742 -127.374142) (xy 138.778742 -129.177542) (xy 138.219942 -129.177542)
			)
		)
	)
	(zone
		(layer "In12.Cu")
		(hatch none 0.5)
		(connect_pads
			(clearance 0)
		)
		(min_thickness 0.25)
		(keepout
			(tracks not_allowed)
			(vias allowed)
			(pads allowed)
			(copperpour not_allowed)
			(footprints allowed)
		)
		(placement
			(enabled no)
			(sheetname "")
		)
		(fill
			(thermal_gap 0.5)
			(thermal_bridge_width 0.5)
			(island_removal_mode 0)
		)
		(polygon
			(pts
				(xy 283.670502 -9.721342) (xy 284.229302 -9.721342) (xy 284.229302 -11.524742) (xy 283.670502 -11.524742)
			)
		)
	)
	(zone
		(layer "In12.Cu")
		(hatch none 0.5)
		(connect_pads
			(clearance 0)
		)
		(min_thickness 0.25)
		(keepout
			(tracks not_allowed)
			(vias allowed)
			(pads allowed)
			(copperpour not_allowed)
			(footprints allowed)
		)
		(placement
			(enabled no)
			(sheetname "")
		)
		(fill
			(thermal_gap 0.5)
			(thermal_bridge_width 0.5)
			(island_removal_mode 0)
		)
		(polygon
			(pts
				(xy 462.5594 -51.289458) (xy 463.0674 -51.289458) (xy 463.0674 -52.686458) (xy 462.5594 -52.686458)
			)
		)
	)
	(zone
		(layer "In12.Cu")
		(hatch none 0.5)
		(connect_pads
			(clearance 0)
		)
		(min_thickness 0.25)
		(keepout
			(tracks not_allowed)
			(vias allowed)
			(pads allowed)
			(copperpour not_allowed)
			(footprints allowed)
		)
		(placement
			(enabled no)
			(sheetname "")
		)
		(fill
			(thermal_gap 0.5)
			(thermal_bridge_width 0.5)
			(island_removal_mode 0)
		)
		(polygon
			(pts
				(xy 72.769984 -23.922482) (xy 73.328784 -23.922482) (xy 73.328784 -25.725882) (xy 72.769984 -25.725882)
			)
		)
	)
	(zone
		(layer "In12.Cu")
		(hatch none 0.5)
		(connect_pads
			(clearance 0)
		)
		(min_thickness 0.25)
		(keepout
			(tracks not_allowed)
			(vias allowed)
			(pads allowed)
			(copperpour not_allowed)
			(footprints allowed)
		)
		(placement
			(enabled no)
			(sheetname "")
		)
		(fill
			(thermal_gap 0.5)
			(thermal_bridge_width 0.5)
			(island_removal_mode 0)
		)
		(polygon
			(pts
				(xy 304.070512 -151.176482) (xy 304.629312 -151.176482) (xy 304.629312 -152.979882) (xy 304.070512 -152.979882)
			)
		)
	)
	(zone
		(layer "In12.Cu")
		(hatch none 0.5)
		(connect_pads
			(clearance 0)
		)
		(min_thickness 0.25)
		(keepout
			(tracks not_allowed)
			(vias allowed)
			(pads allowed)
			(copperpour not_allowed)
			(footprints allowed)
		)
		(placement
			(enabled no)
			(sheetname "")
		)
		(fill
			(thermal_gap 0.5)
			(thermal_bridge_width 0.5)
			(island_removal_mode 0)
		)
		(polygon
			(pts
				(xy 362.969556 -122.764042) (xy 360.683556 -122.764042) (xy 360.683556 -122.256042) (xy 362.969556 -122.256042)
			)
		)
	)
	(zone
		(layer "In12.Cu")
		(hatch none 0.5)
		(connect_pads
			(clearance 0)
		)
		(min_thickness 0.25)
		(keepout
			(tracks not_allowed)
			(vias allowed)
			(pads allowed)
			(copperpour not_allowed)
			(footprints allowed)
		)
		(placement
			(enabled no)
			(sheetname "")
		)
		(fill
			(thermal_gap 0.5)
			(thermal_bridge_width 0.5)
			(island_removal_mode 0)
		)
		(polygon
			(pts
				(xy 450.72935 -51.264058) (xy 451.23735 -51.264058) (xy 451.23735 -52.661058) (xy 450.72935 -52.661058)
			)
		)
	)
	(zone
		(layer "In12.Cu")
		(hatch none 0.5)
		(connect_pads
			(clearance 0)
		)
		(min_thickness 0.25)
		(keepout
			(tracks not_allowed)
			(vias allowed)
			(pads allowed)
			(copperpour not_allowed)
			(footprints allowed)
		)
		(placement
			(enabled no)
			(sheetname "")
		)
		(fill
			(thermal_gap 0.5)
			(thermal_bridge_width 0.5)
			(island_removal_mode 0)
		)
		(polygon
			(pts
				(xy 287.070546 -141.575282) (xy 287.629346 -141.575282) (xy 287.629346 -143.378682) (xy 287.070546 -143.378682)
			)
		)
	)
	(zone
		(layer "In12.Cu")
		(hatch none 0.5)
		(connect_pads
			(clearance 0)
		)
		(min_thickness 0.25)
		(keepout
			(tracks not_allowed)
			(vias allowed)
			(pads allowed)
			(copperpour not_allowed)
			(footprints allowed)
		)
		(placement
			(enabled no)
			(sheetname "")
		)
		(fill
			(thermal_gap 0.5)
			(thermal_bridge_width 0.5)
			(island_removal_mode 0)
		)
		(polygon
			(pts
				(xy 88.070182 -127.374142) (xy 88.628982 -127.374142) (xy 88.628982 -129.177542) (xy 88.070182 -129.177542)
			)
		)
	)
	(zone
		(layer "In12.Cu")
		(hatch none 0.5)
		(connect_pads
			(clearance 0)
		)
		(min_thickness 0.25)
		(keepout
			(tracks not_allowed)
			(vias allowed)
			(pads allowed)
			(copperpour not_allowed)
			(footprints allowed)
		)
		(placement
			(enabled no)
			(sheetname "")
		)
		(fill
			(thermal_gap 0.5)
			(thermal_bridge_width 0.5)
			(island_removal_mode 0)
		)
		(polygon
			(pts
				(xy 341.982806 -59.225434) (xy 341.982806 -61.511434) (xy 341.474806 -61.511434) (xy 341.474806 -59.225434)
			)
		)
	)
	(zone
		(layer "In12.Cu")
		(hatch none 0.5)
		(connect_pads
			(clearance 0)
		)
		(min_thickness 0.25)
		(keepout
			(tracks not_allowed)
			(vias allowed)
			(pads allowed)
			(copperpour not_allowed)
			(footprints allowed)
		)
		(placement
			(enabled no)
			(sheetname "")
		)
		(fill
			(thermal_gap 0.5)
			(thermal_bridge_width 0.5)
			(island_removal_mode 0)
		)
		(polygon
			(pts
				(xy 148.420074 -131.974082) (xy 148.978874 -131.974082) (xy 148.978874 -133.777482) (xy 148.420074 -133.777482)
			)
		)
	)
	(zone
		(layer "In12.Cu")
		(hatch none 0.5)
		(connect_pads
			(clearance 0)
		)
		(min_thickness 0.25)
		(keepout
			(tracks not_allowed)
			(vias allowed)
			(pads allowed)
			(copperpour not_allowed)
			(footprints allowed)
		)
		(placement
			(enabled no)
			(sheetname "")
		)
		(fill
			(thermal_gap 0.5)
			(thermal_bridge_width 0.5)
			(island_removal_mode 0)
		)
		(polygon
			(pts
				(xy 32.820102 -151.176482) (xy 33.378902 -151.176482) (xy 33.378902 -152.979882) (xy 32.820102 -152.979882)
			)
		)
	)
	(zone
		(layer "In12.Cu")
		(hatch none 0.5)
		(connect_pads
			(clearance 0)
		)
		(min_thickness 0.25)
		(keepout
			(tracks not_allowed)
			(vias allowed)
			(pads allowed)
			(copperpour not_allowed)
			(footprints allowed)
		)
		(placement
			(enabled no)
			(sheetname "")
		)
		(fill
			(thermal_gap 0.5)
			(thermal_bridge_width 0.5)
			(island_removal_mode 0)
		)
		(polygon
			(pts
				(xy 252.220476 -136.975342) (xy 252.779276 -136.975342) (xy 252.779276 -138.778742) (xy 252.220476 -138.778742)
			)
		)
	)
	(zone
		(layer "In12.Cu")
		(hatch none 0.5)
		(connect_pads
			(clearance 0)
		)
		(min_thickness 0.25)
		(keepout
			(tracks not_allowed)
			(vias allowed)
			(pads allowed)
			(copperpour not_allowed)
			(footprints allowed)
		)
		(placement
			(enabled no)
			(sheetname "")
		)
		(fill
			(thermal_gap 0.5)
			(thermal_bridge_width 0.5)
			(island_removal_mode 0)
		)
		(polygon
			(pts
				(xy 212.270594 -127.374142) (xy 212.829394 -127.374142) (xy 212.829394 -129.177542) (xy 212.270594 -129.177542)
			)
		)
	)
	(zone
		(layer "In12.Cu")
		(hatch none 0.5)
		(connect_pads
			(clearance 0)
		)
		(min_thickness 0.25)
		(keepout
			(tracks not_allowed)
			(vias allowed)
			(pads allowed)
			(copperpour not_allowed)
			(footprints allowed)
		)
		(placement
			(enabled no)
			(sheetname "")
		)
		(fill
			(thermal_gap 0.5)
			(thermal_bridge_width 0.5)
			(island_removal_mode 0)
		)
		(polygon
			(pts
				(xy 223.320356 -146.576542) (xy 223.879156 -146.576542) (xy 223.879156 -148.379942) (xy 223.320356 -148.379942)
			)
		)
	)
	(zone
		(layer "In12.Cu")
		(hatch none 0.5)
		(connect_pads
			(clearance 0)
		)
		(min_thickness 0.25)
		(keepout
			(tracks not_allowed)
			(vias allowed)
			(pads allowed)
			(copperpour not_allowed)
			(footprints allowed)
		)
		(placement
			(enabled no)
			(sheetname "")
		)
		(fill
			(thermal_gap 0.5)
			(thermal_bridge_width 0.5)
			(island_removal_mode 0)
		)
		(polygon
			(pts
				(xy 62.570106 -23.922482) (xy 63.128906 -23.922482) (xy 63.128906 -25.725882) (xy 62.570106 -25.725882)
			)
		)
	)
	(zone
		(layer "In12.Cu")
		(hatch none 0.5)
		(connect_pads
			(clearance 0)
		)
		(min_thickness 0.25)
		(keepout
			(tracks not_allowed)
			(vias allowed)
			(pads allowed)
			(copperpour not_allowed)
			(footprints allowed)
		)
		(placement
			(enabled no)
			(sheetname "")
		)
		(fill
			(thermal_gap 0.5)
			(thermal_bridge_width 0.5)
			(island_removal_mode 0)
		)
		(polygon
			(pts
				(xy 37.07003 -131.974082) (xy 37.62883 -131.974082) (xy 37.62883 -133.777482) (xy 37.07003 -133.777482)
			)
		)
	)
	(zone
		(layer "In12.Cu")
		(hatch none 0.5)
		(connect_pads
			(clearance 0)
		)
		(min_thickness 0.25)
		(keepout
			(tracks not_allowed)
			(vias allowed)
			(pads allowed)
			(copperpour not_allowed)
			(footprints allowed)
		)
		(placement
			(enabled no)
			(sheetname "")
		)
		(fill
			(thermal_gap 0.5)
			(thermal_bridge_width 0.5)
			(island_removal_mode 0)
		)
		(polygon
			(pts
				(xy 310.870346 -4.720082) (xy 311.429146 -4.720082) (xy 311.429146 -6.523482) (xy 310.870346 -6.523482)
			)
		)
	)
	(zone
		(layer "In12.Cu")
		(hatch none 0.5)
		(connect_pads
			(clearance 0)
		)
		(min_thickness 0.25)
		(keepout
			(tracks not_allowed)
			(vias allowed)
			(pads allowed)
			(copperpour not_allowed)
			(footprints allowed)
		)
		(placement
			(enabled no)
			(sheetname "")
		)
		(fill
			(thermal_gap 0.5)
			(thermal_bridge_width 0.5)
			(island_removal_mode 0)
		)
		(polygon
			(pts
				(xy 234.370372 -19.322542) (xy 234.929172 -19.322542) (xy 234.929172 -21.125942) (xy 234.370372 -21.125942)
			)
		)
	)
	(zone
		(layer "In12.Cu")
		(hatch none 0.5)
		(connect_pads
			(clearance 0)
		)
		(min_thickness 0.25)
		(keepout
			(tracks not_allowed)
			(vias allowed)
			(pads allowed)
			(copperpour not_allowed)
			(footprints allowed)
		)
		(placement
			(enabled no)
			(sheetname "")
		)
		(fill
			(thermal_gap 0.5)
			(thermal_bridge_width 0.5)
			(island_removal_mode 0)
		)
		(polygon
			(pts
				(xy 221.620588 -146.576542) (xy 222.179388 -146.576542) (xy 222.179388 -148.379942) (xy 221.620588 -148.379942)
			)
		)
	)
	(zone
		(layer "In12.Cu")
		(hatch none 0.5)
		(connect_pads
			(clearance 0)
		)
		(min_thickness 0.25)
		(keepout
			(tracks not_allowed)
			(vias allowed)
			(pads allowed)
			(copperpour not_allowed)
			(footprints allowed)
		)
		(placement
			(enabled no)
			(sheetname "")
		)
		(fill
			(thermal_gap 0.5)
			(thermal_bridge_width 0.5)
			(island_removal_mode 0)
		)
		(polygon
			(pts
				(xy 79.570072 -141.575282) (xy 80.128872 -141.575282) (xy 80.128872 -143.378682) (xy 79.570072 -143.378682)
			)
		)
	)
	(zone
		(layer "In12.Cu")
		(hatch none 0.5)
		(connect_pads
			(clearance 0)
		)
		(min_thickness 0.25)
		(keepout
			(tracks not_allowed)
			(vias allowed)
			(pads allowed)
			(copperpour not_allowed)
			(footprints allowed)
		)
		(placement
			(enabled no)
			(sheetname "")
		)
		(fill
			(thermal_gap 0.5)
			(thermal_bridge_width 0.5)
			(island_removal_mode 0)
		)
		(polygon
			(pts
				(xy 229.27056 -9.721342) (xy 229.82936 -9.721342) (xy 229.82936 -11.524742) (xy 229.27056 -11.524742)
			)
		)
	)
	(zone
		(layer "In12.Cu")
		(hatch none 0.5)
		(connect_pads
			(clearance 0)
		)
		(min_thickness 0.25)
		(keepout
			(tracks not_allowed)
			(vias allowed)
			(pads allowed)
			(copperpour not_allowed)
			(footprints allowed)
		)
		(placement
			(enabled no)
			(sheetname "")
		)
		(fill
			(thermal_gap 0.5)
			(thermal_bridge_width 0.5)
			(island_removal_mode 0)
		)
		(polygon
			(pts
				(xy 45.57014 -19.322542) (xy 46.12894 -19.322542) (xy 46.12894 -21.125942) (xy 45.57014 -21.125942)
			)
		)
	)
	(zone
		(layer "In12.Cu")
		(hatch none 0.5)
		(connect_pads
			(clearance 0)
		)
		(min_thickness 0.25)
		(keepout
			(tracks not_allowed)
			(vias allowed)
			(pads allowed)
			(copperpour not_allowed)
			(footprints allowed)
		)
		(placement
			(enabled no)
			(sheetname "")
		)
		(fill
			(thermal_gap 0.5)
			(thermal_bridge_width 0.5)
			(island_removal_mode 0)
		)
		(polygon
			(pts
				(xy 293.020496 -136.975342) (xy 293.579296 -136.975342) (xy 293.579296 -138.778742) (xy 293.020496 -138.778742)
			)
		)
	)
	(zone
		(layer "In12.Cu")
		(hatch none 0.5)
		(connect_pads
			(clearance 0)
		)
		(min_thickness 0.25)
		(keepout
			(tracks not_allowed)
			(vias allowed)
			(pads allowed)
			(copperpour not_allowed)
			(footprints allowed)
		)
		(placement
			(enabled no)
			(sheetname "")
		)
		(fill
			(thermal_gap 0.5)
			(thermal_bridge_width 0.5)
			(island_removal_mode 0)
		)
		(polygon
			(pts
				(xy 287.92043 -9.721342) (xy 288.47923 -9.721342) (xy 288.47923 -11.524742) (xy 287.92043 -11.524742)
			)
		)
	)
	(zone
		(layer "In12.Cu")
		(hatch none 0.5)
		(connect_pads
			(clearance 0)
		)
		(min_thickness 0.25)
		(keepout
			(tracks not_allowed)
			(vias allowed)
			(pads allowed)
			(copperpour not_allowed)
			(footprints allowed)
		)
		(placement
			(enabled no)
			(sheetname "")
		)
		(fill
			(thermal_gap 0.5)
			(thermal_bridge_width 0.5)
			(island_removal_mode 0)
		)
		(polygon
			(pts
				(xy 243.720366 -0.120142) (xy 244.279166 -0.120142) (xy 244.279166 -1.923542) (xy 243.720366 -1.923542)
			)
		)
	)
	(zone
		(layer "In12.Cu")
		(hatch none 0.5)
		(connect_pads
			(clearance 0)
		)
		(min_thickness 0.25)
		(keepout
			(tracks not_allowed)
			(vias allowed)
			(pads allowed)
			(copperpour not_allowed)
			(footprints allowed)
		)
		(placement
			(enabled no)
			(sheetname "")
		)
		(fill
			(thermal_gap 0.5)
			(thermal_bridge_width 0.5)
			(island_removal_mode 0)
		)
		(polygon
			(pts
				(xy 272.620486 -23.922482) (xy 273.179286 -23.922482) (xy 273.179286 -25.725882) (xy 272.620486 -25.725882)
			)
		)
	)
	(zone
		(layer "In12.Cu")
		(hatch none 0.5)
		(connect_pads
			(clearance 0)
		)
		(min_thickness 0.25)
		(keepout
			(tracks not_allowed)
			(vias allowed)
			(pads allowed)
			(copperpour not_allowed)
			(footprints allowed)
		)
		(placement
			(enabled no)
			(sheetname "")
		)
		(fill
			(thermal_gap 0.5)
			(thermal_bridge_width 0.5)
			(island_removal_mode 0)
		)
		(polygon
			(pts
				(xy 88.920066 -23.922482) (xy 89.478866 -23.922482) (xy 89.478866 -25.725882) (xy 88.920066 -25.725882)
			)
		)
	)
	(zone
		(layer "In12.Cu")
		(hatch none 0.5)
		(connect_pads
			(clearance 0)
		)
		(min_thickness 0.25)
		(keepout
			(tracks not_allowed)
			(vias allowed)
			(pads allowed)
			(copperpour not_allowed)
			(footprints allowed)
		)
		(placement
			(enabled no)
			(sheetname "")
		)
		(fill
			(thermal_gap 0.5)
			(thermal_bridge_width 0.5)
			(island_removal_mode 0)
		)
		(polygon
			(pts
				(xy 35.370008 -0.120142) (xy 35.928808 -0.120142) (xy 35.928808 -1.923542) (xy 35.370008 -1.923542)
			)
		)
	)
	(zone
		(layer "In12.Cu")
		(hatch none 0.5)
		(connect_pads
			(clearance 0)
		)
		(min_thickness 0.25)
		(keepout
			(tracks not_allowed)
			(vias allowed)
			(pads allowed)
			(copperpour not_allowed)
			(footprints allowed)
		)
		(placement
			(enabled no)
			(sheetname "")
		)
		(fill
			(thermal_gap 0.5)
			(thermal_bridge_width 0.5)
			(island_removal_mode 0)
		)
		(polygon
			(pts
				(xy 293.020496 -131.974082) (xy 293.579296 -131.974082) (xy 293.579296 -133.777482) (xy 293.020496 -133.777482)
			)
		)
	)
	(zone
		(layer "In12.Cu")
		(hatch none 0.5)
		(connect_pads
			(clearance 0)
		)
		(min_thickness 0.25)
		(keepout
			(tracks not_allowed)
			(vias allowed)
			(pads allowed)
			(copperpour not_allowed)
			(footprints allowed)
		)
		(placement
			(enabled no)
			(sheetname "")
		)
		(fill
			(thermal_gap 0.5)
			(thermal_bridge_width 0.5)
			(island_removal_mode 0)
		)
		(polygon
			(pts
				(xy 253.070614 -127.374142) (xy 253.629414 -127.374142) (xy 253.629414 -129.177542) (xy 253.070614 -129.177542)
			)
		)
	)
	(zone
		(layer "In12.Cu")
		(hatch none 0.5)
		(connect_pads
			(clearance 0)
		)
		(min_thickness 0.25)
		(keepout
			(tracks not_allowed)
			(vias allowed)
			(pads allowed)
			(copperpour not_allowed)
			(footprints allowed)
		)
		(placement
			(enabled no)
			(sheetname "")
		)
		(fill
			(thermal_gap 0.5)
			(thermal_bridge_width 0.5)
			(island_removal_mode 0)
		)
		(polygon
			(pts
				(xy 293.020496 -151.176482) (xy 293.579296 -151.176482) (xy 293.579296 -152.979882) (xy 293.020496 -152.979882)
			)
		)
	)
	(zone
		(layer "In12.Cu")
		(hatch none 0.5)
		(connect_pads
			(clearance 0)
		)
		(min_thickness 0.25)
		(keepout
			(tracks not_allowed)
			(vias allowed)
			(pads allowed)
			(copperpour not_allowed)
			(footprints allowed)
		)
		(placement
			(enabled no)
			(sheetname "")
		)
		(fill
			(thermal_gap 0.5)
			(thermal_bridge_width 0.5)
			(island_removal_mode 0)
		)
		(polygon
			(pts
				(xy 304.920396 -146.576542) (xy 305.479196 -146.576542) (xy 305.479196 -148.379942) (xy 304.920396 -148.379942)
			)
		)
	)
	(zone
		(layer "In12.Cu")
		(hatch none 0.5)
		(connect_pads
			(clearance 0)
		)
		(min_thickness 0.25)
		(keepout
			(tracks not_allowed)
			(vias allowed)
			(pads allowed)
			(copperpour not_allowed)
			(footprints allowed)
		)
		(placement
			(enabled no)
			(sheetname "")
		)
		(fill
			(thermal_gap 0.5)
			(thermal_bridge_width 0.5)
			(island_removal_mode 0)
		)
		(polygon
			(pts
				(xy 199.520556 -151.176482) (xy 200.079356 -151.176482) (xy 200.079356 -152.979882) (xy 199.520556 -152.979882)
			)
		)
	)
	(zone
		(layer "In12.Cu")
		(hatch none 0.5)
		(connect_pads
			(clearance 0)
		)
		(min_thickness 0.25)
		(keepout
			(tracks not_allowed)
			(vias allowed)
			(pads allowed)
			(copperpour not_allowed)
			(footprints allowed)
		)
		(placement
			(enabled no)
			(sheetname "")
		)
		(fill
			(thermal_gap 0.5)
			(thermal_bridge_width 0.5)
			(island_removal_mode 0)
		)
		(polygon
			(pts
				(xy 108.469938 -9.721342) (xy 109.028738 -9.721342) (xy 109.028738 -11.524742) (xy 108.469938 -11.524742)
			)
		)
	)
	(zone
		(net "GND")
		(layer "In12.Cu")
		(hatch none 0.5)
		(connect_pads
			(clearance 0.5)
		)
		(min_thickness 0.25)
		(fill yes
			(thermal_gap 0.5)
			(thermal_bridge_width 0.5)
			(island_removal_mode 0)
		)
		(polygon
			(pts
				(arc
					(start -4.99999 5.541772)
					(mid -5.383088 5.383088)
					(end -5.541772 4.99999)
				)
				(arc
					(start -5.541772 -158.100014)
					(mid -5.383088 -158.483112)
					(end -4.99999 -158.641796)
				)
				(arc
					(start 501.000014 -158.641796)
					(mid 501.383112 -158.483112)
					(end 501.541796 -158.100014)
				)
				(arc
					(start 501.541796 -110.87989)
					(mid 501.383112 -110.496792)
					(end 501.000014 -110.338108)
				)
				(xy 431.3936 -110.338108) (xy 431.3936 -110.337346)
				(arc
					(start 428.209964 -110.337346)
					(mid 427.17939 -109.910468)
					(end 426.752512 -108.879894)
				)
				(xy 426.752512 -89.408) (xy 426.75175 -89.408)
				(arc
					(start 426.75175 -68.879974)
					(mid 427.178851 -67.848861)
					(end 428.209964 -67.42176)
				)
				(arc
					(start 478.48012 -67.42176)
					(mid 478.863218 -67.263076)
					(end 479.021902 -66.879978)
				)
				(arc
					(start 479.021902 -63.680086)
					(mid 479.449003 -62.648973)
					(end 480.480116 -62.221872)
				)
				(arc
					(start 501.000014 -62.221872)
					(mid 501.383112 -62.063188)
					(end 501.541796 -61.68009)
				)
				(arc
					(start 501.541796 -14.99997)
					(mid 501.383112 -14.616872)
					(end 501.000014 -14.458188)
				)
				(arc
					(start 484.349806 -14.458188)
					(mid 483.67241 -14.177496)
					(end 483.391718 -13.5001)
				)
				(arc
					(start 483.391718 2.500122)
					(mid 483.67241 3.177518)
					(end 484.349806 3.45821)
				)
				(arc
					(start 501.000014 3.45821)
					(mid 501.383112 3.616894)
					(end 501.541796 3.999992)
				)
				(arc
					(start 501.541796 4.99999)
					(mid 501.383112 5.383088)
					(end 501.000014 5.541772)
				)
			)
		)
		(polygon
			(pts
				(xy 103.888794 -148.0185) (xy 100.022406 -148.0185) (xy 99.6315 -148.409406) (xy 99.6315 -149.557994)
				(arc
					(start 99.931728 -149.858222)
					(mid 100.000468 -149.906694)
					(end 100.083366 -149.92096)
				)
				(xy 103.163878 -149.92096) (xy 103.542338 -149.5425) (xy 103.964994 -149.5425) (xy 104.2797 -149.227794)
				(xy 104.2797 -148.409406)
			)
		)
		(polygon
			(pts
				(xy 268.785594 -147.9931) (xy 264.995406 -147.9931) (xy 264.5791 -148.409406) (xy 264.5791 -149.583394)
				(arc
					(start 264.907268 -149.911562)
					(mid 264.976008 -149.960034)
					(end 265.058906 -149.9743)
				)
				(xy 268.150594 -149.9743) (xy 268.556994 -149.5679) (xy 268.988794 -149.5679) (xy 269.2781 -149.278594)
				(xy 269.2781 -148.485606)
			)
		)
		(polygon
			(pts
				(xy 268.836394 -138.4427) (xy 265.097006 -138.4427) (xy 264.6299 -138.909806) (xy 264.6299 -139.956794)
				(arc
					(start 264.983468 -140.310362)
					(mid 265.052208 -140.358834)
					(end 265.135106 -140.3731)
				)
				(xy 268.125194 -140.3731) (xy 268.531594 -139.9667) (xy 268.963394 -139.9667) (xy 269.3035 -139.626594)
				(xy 269.3035 -138.909806)
			)
		)
		(polygon
			(pts
				(xy 103.863394 -138.3919) (xy 99.997006 -138.3919) (xy 99.6569 -138.732006)
				(arc
					(start 99.6569 -139.9032)
					(mid 99.671484 -139.976047)
					(end 99.71278 -140.03782)
				)
				(arc
					(start 99.908868 -140.234162)
					(mid 99.977608 -140.282634)
					(end 100.060506 -140.2969)
				)
				(xy 103.177594 -140.2969) (xy 103.507794 -139.9667) (xy 103.964994 -139.9667) (xy 104.3305 -139.601194)
				(xy 104.3305 -138.859006)
			)
		)
		(polygon
			(pts
				(arc
					(start 435.66461 -136.344914)
					(mid 435.440681 -135.804303)
					(end 434.90007 -135.580374)
				)
				(arc
					(start 433.63007 -135.580374)
					(mid 432.86553 -136.344914)
					(end 433.63007 -137.109454)
				)
				(arc
					(start 434.90007 -137.109454)
					(mid 435.439783 -136.886423)
					(end 435.66461 -136.347454)
				)
				(xy 435.473856 -136.347454) (xy 435.473856 -136.344914)
			)
		)
		(polygon
			(pts
				(arc
					(start 431.85461 -136.344914)
					(mid 431.630681 -135.804303)
					(end 431.09007 -135.580374)
				)
				(arc
					(start 429.82007 -135.580374)
					(mid 429.05553 -136.344914)
					(end 429.82007 -137.109454)
				)
				(arc
					(start 431.09007 -137.109454)
					(mid 431.629783 -136.886423)
					(end 431.85461 -136.347454)
				)
				(xy 431.666142 -136.347454) (xy 431.666142 -136.344914)
			)
		)
		(polygon
			(pts
				(xy 172.444156 -129.0066) (xy 171.319444 -129.0066) (xy 171.0182 -129.307844) (xy 171.0182 -131.339844)
				(xy 171.014644 -131.3434) (xy 170.582844 -131.3434) (xy 170.18 -131.746244) (xy 170.18 -133.836156)
				(xy 171.116244 -134.7724) (xy 177.905156 -134.7724) (xy 178.816 -133.861556) (xy 178.816 -131.974844)
				(xy 178.6636 -131.822444) (xy 178.6636 -129.587244) (xy 178.311556 -129.2352) (xy 172.672756 -129.2352)
			)
		)
		(polygon
			(pts
				(xy 93.703394 -128.8669) (xy 78.762606 -128.8669) (xy 78.3971 -129.232406) (xy 78.3971 -130.324606)
				(xy 77.5081 -131.213606) (xy 77.5081 -131.879594) (xy 77.887068 -132.258562) (xy 77.901038 -132.272278)
				(xy 77.949806 -132.3213) (xy 78.019148 -132.3213) (xy 78.038706 -132.3213) (xy 93.703394 -132.3213)
				(xy 94.0181 -132.006594) (xy 94.0181 -129.181606)
			)
		)
		(polygon
			(pts
				(xy 278.234394 -128.7907) (xy 265.071606 -128.7907) (xy 264.6553 -129.207006) (xy 264.6553 -130.812794)
				(arc
					(start 266.151868 -132.309362)
					(mid 266.220608 -132.357834)
					(end 266.303506 -132.3721)
				)
				(xy 278.285194 -132.3721) (xy 278.7523 -131.904994) (xy 278.7523 -130.604006) (xy 278.5237 -130.375406)
				(xy 278.5237 -130.101594) (xy 278.7015 -129.923794) (xy 278.7015 -129.257806)
			)
		)
		(polygon
			(pts
				(xy 113.286794 -128.7907) (xy 100.098606 -128.7907) (xy 99.7077 -129.181606)
				(arc
					(start 99.7077 -130.800094)
					(mid 99.721943 -130.883001)
					(end 99.770438 -130.951732)
				)
				(xy 100.2919 -131.473194) (xy 100.2919 -131.955794) (xy 100.682806 -132.3467) (xy 113.286794 -132.3467)
				(xy 113.7539 -131.879594) (xy 113.7539 -130.604006) (xy 113.4999 -130.350006) (xy 113.4999 -130.101594)
				(xy 113.7031 -129.898394) (xy 113.7031 -129.207006)
			)
		)
		(polygon
			(pts
				(xy 258.473194 -128.7653)
				(arc
					(start 243.951506 -128.7653)
					(mid 243.868599 -128.779543)
					(end 243.799868 -128.828038)
				)
				(xy 243.3955 -129.232406) (xy 243.3955 -130.324606) (xy 242.5065 -131.213606) (xy 242.5065 -132.006594)
				(xy 242.872006 -132.3721) (xy 258.600194 -132.3721) (xy 259.0927 -131.879594) (xy 259.0927 -129.384806)
			)
		)
		(polygon
			(pts
				(xy 402.40077 -127.405384) (xy 401.00377 -127.405384) (xy 401.00377 -127.913384) (xy 402.40077 -127.913384)
			)
		)
		(polygon
			(pts
				(xy 402.40077 -126.135384) (xy 401.00377 -126.135384) (xy 401.00377 -126.643384) (xy 402.40077 -126.643384)
			)
		)
		(polygon
			(pts
				(arc
					(start 350.30664 -60.21451)
					(mid 350.255332 -60.164218)
					(end 350.20504 -60.215526)
				)
				(arc
					(start 350.20504 -60.222638)
					(mid 350.255332 -60.273946)
					(end 350.30664 -60.223654)
				)
			)
		)
		(polygon
			(pts
				(arc
					(start 339.235542 -59.773312)
					(mid 339.184234 -59.72302)
					(end 339.133942 -59.774328)
				)
				(arc
					(start 339.133942 -59.78144)
					(mid 339.184234 -59.832748)
					(end 339.235542 -59.782456)
				)
			)
		)
		(polygon
			(pts
				(arc
					(start 344.88755 -59.360562)
					(mid 344.836242 -59.31027)
					(end 344.78595 -59.361578)
				)
				(arc
					(start 344.78595 -59.36869)
					(mid 344.836242 -59.419998)
					(end 344.88755 -59.369706)
				)
			)
		)
		(polygon
			(pts
				(arc
					(start 346.481146 -59.068208)
					(mid 346.429838 -59.017916)
					(end 346.379546 -59.069224)
				)
				(arc
					(start 346.379546 -59.076336)
					(mid 346.429838 -59.127644)
					(end 346.481146 -59.077352)
				)
			)
		)
		(polygon
			(pts
				(xy 19.11731 -55.674514) (xy 13.033502 -55.674514) (xy 12.103862 -56.604154) (xy 12.103862 -66.186304)
				(xy 14.787118 -68.86956) (xy 18.959322 -68.86956) (xy 20.086066 -67.742816) (xy 20.086066 -56.64327)
			)
		)
		(polygon
			(pts
				(xy 9.984994 -48.768) (xy 2.835656 -48.768) (xy 1.8034 -49.800256) (xy 1.8034 -58.588656) (xy 0.5334 -59.858656)
				(xy 0.5334 -67.268344) (xy 2.2352 -68.970144) (xy 2.2352 -86.089744) (xy 3.597656 -87.4522) (xy 10.370566 -87.4522)
				(xy 11.362436 -86.46033) (xy 11.362436 -50.145442)
			)
		)
		(polygon
			(pts
				(arc
					(start 419.178994 -40.707818)
					(mid 419.090286 -40.655673)
					(end 419.001448 -40.707818)
				)
				(arc
					(start 419.001448 -40.707818)
					(mid 418.943757 -40.784752)
					(end 418.86759 -40.843454)
				)
				(arc
					(start 418.86759 -40.843454)
					(mid 418.816553 -40.929546)
					(end 418.864034 -41.017698)
				)
				(arc
					(start 418.864034 -41.017698)
					(mid 418.916874 -41.580177)
					(end 418.359844 -41.485312)
				)
				(arc
					(start 418.359844 -41.485312)
					(mid 418.270779 -41.430988)
					(end 418.180774 -41.483788)
				)
				(arc
					(start 418.180774 -41.483788)
					(mid 417.884888 -41.66859)
					(end 417.573206 -41.511982)
				)
				(arc
					(start 417.573206 -41.511982)
					(mid 417.485647 -41.467421)
					(end 417.401248 -41.517824)
				)
				(arc
					(start 417.401248 -41.517824)
					(mid 417.343328 -41.592264)
					(end 417.267898 -41.648888)
				)
				(arc
					(start 417.267898 -41.648888)
					(mid 417.215884 -41.737077)
					(end 417.267136 -41.825672)
				)
				(arc
					(start 417.267136 -41.825672)
					(mid 417.343596 -41.884442)
					(end 417.401502 -41.961562)
				)
				(arc
					(start 417.401502 -41.961562)
					(mid 417.49034 -42.013799)
					(end 417.579048 -41.961562)
				)
				(arc
					(start 417.579048 -41.961562)
					(mid 417.890198 -41.778538)
					(end 418.201348 -41.961562)
				)
				(arc
					(start 418.201348 -41.961562)
					(mid 418.290186 -42.013799)
					(end 418.378894 -41.961562)
				)
				(arc
					(start 418.378894 -41.961562)
					(mid 418.690044 -41.778669)
					(end 419.001194 -41.961562)
				)
				(arc
					(start 419.001194 -41.961562)
					(mid 419.090032 -42.013929)
					(end 419.17874 -41.961562)
				)
				(arc
					(start 419.17874 -41.961562)
					(mid 419.238162 -41.882808)
					(end 419.316916 -41.823386)
				)
				(arc
					(start 419.316916 -41.823386)
					(mid 419.369061 -41.734678)
					(end 419.316916 -41.64584)
				)
				(arc
					(start 419.316916 -41.64584)
					(mid 419.134023 -41.334579)
					(end 419.31717 -41.02354)
				)
				(arc
					(start 419.31717 -41.02354)
					(mid 419.369537 -40.93464)
					(end 419.31717 -40.84574)
				)
				(arc
					(start 419.31717 -40.84574)
					(mid 419.238415 -40.786457)
					(end 419.178994 -40.707818)
				)
			)
		)
		(polygon
			(pts
				(arc
					(start 419.97884 -39.907718)
					(mid 419.890132 -39.855573)
					(end 419.801294 -39.907718)
				)
				(arc
					(start 419.801294 -39.907718)
					(mid 419.741821 -39.986305)
					(end 419.663118 -40.04564)
				)
				(arc
					(start 419.663118 -40.04564)
					(mid 419.610751 -40.13454)
					(end 419.663118 -40.22344)
				)
				(arc
					(start 419.663118 -40.22344)
					(mid 419.742797 -40.283649)
					(end 419.802564 -40.363648)
				)
				(arc
					(start 419.802564 -40.363648)
					(mid 419.888404 -40.416315)
					(end 419.977316 -40.369236)
				)
				(arc
					(start 419.977316 -40.369236)
					(mid 420.287789 -40.203992)
					(end 420.588694 -40.386)
				)
				(arc
					(start 420.588694 -40.386)
					(mid 420.68052 -40.437965)
					(end 420.769034 -40.380412)
				)
				(arc
					(start 420.769034 -40.380412)
					(mid 420.830772 -40.290455)
					(end 420.916862 -40.22344)
				)
				(arc
					(start 420.916862 -40.22344)
					(mid 420.969007 -40.134732)
					(end 420.916862 -40.045894)
				)
				(arc
					(start 420.916862 -40.045894)
					(mid 420.838274 -39.98656)
					(end 420.77894 -39.907972)
				)
				(arc
					(start 420.77894 -39.907972)
					(mid 420.690232 -39.855827)
					(end 420.601394 -39.907972)
				)
				(arc
					(start 420.601394 -39.907972)
					(mid 420.290071 -40.090865)
					(end 419.97884 -39.907718)
				)
			)
		)
		(polygon
			(pts
				(xy 341.100156 -21.082) (xy 340.127844 -21.082) (xy 339.725 -21.484844) (xy 339.725 -22.330156)
				(xy 340.127844 -22.733) (xy 340.381844 -22.733) (xy 340.487 -22.838156) (xy 340.487 -23.114) (xy 338.544154 -23.114)
				(xy 337.909154 -22.606) (xy 336.042 -22.606) (xy 336.042 -25.251156) (xy 337.587844 -26.797) (xy 340.465156 -26.797)
				(xy 340.846156 -26.416) (xy 345.418156 -26.416) (xy 346.583 -25.251156) (xy 346.583 -23.516844)
				(xy 346.456 -23.389844) (xy 346.456 -21.738844) (xy 345.926156 -21.209) (xy 345.207844 -21.209)
				(xy 344.932 -21.484844) (xy 344.932 -22.098) (xy 343.386156 -22.098) (xy 342.751156 -21.463) (xy 341.481156 -21.463)
			)
		)
		(polygon
			(pts
				(xy 258.574794 -20.7645) (xy 243.761006 -20.7645) (xy 243.4209 -21.104606) (xy 243.4209 -22.222206)
				(xy 242.5065 -23.136606) (xy 242.5065 -23.827994) (xy 242.910868 -24.232362) (xy 242.924838 -24.246078)
				(xy 242.999006 -24.3205) (xy 243.156994 -24.3205) (xy 243.182394 -24.2951) (xy 258.650994 -24.2951)
				(xy 259.0927 -23.853394) (xy 259.0927 -21.282406)
			)
		)
		(polygon
			(pts
				(xy 93.804994 -20.7645) (xy 78.737206 -20.7645) (xy 78.3971 -21.104606) (xy 78.3971 -22.273006)
				(xy 77.5081 -23.162006) (xy 77.5081 -23.853394) (xy 77.836268 -24.181562) (xy 77.850238 -24.195278)
				(xy 77.899006 -24.2443) (xy 77.968348 -24.2443) (xy 77.987906 -24.2443) (xy 93.703394 -24.2443)
				(xy 94.0689 -23.878794) (xy 94.0689 -21.028406)
			)
		)
		(polygon
			(pts
				(xy 278.259794 -20.7391) (xy 265.198606 -20.7391) (xy 264.6807 -21.257006)
				(arc
					(start 264.6807 -22.723094)
					(mid 264.694943 -22.806001)
					(end 264.743438 -22.874732)
				)
				(xy 265.2903 -23.421594) (xy 265.2903 -23.853394) (xy 265.732006 -24.2951) (xy 278.285194 -24.2951)
				(xy 278.7523 -23.827994) (xy 278.7523 -21.231606)
			)
		)
		(polygon
			(pts
				(xy 111.635794 -20.7391) (xy 100.124006 -20.7391) (xy 99.6569 -21.206206) (xy 99.6569 -22.761194)
				(arc
					(start 101.077268 -24.181562)
					(mid 101.146008 -24.230034)
					(end 101.228906 -24.2443)
				)
				(xy 112.524794 -24.2443) (xy 112.8903 -23.878794) (xy 112.8903 -23.314406) (xy 112.6363 -23.060406)
				(xy 112.6363 -22.659594) (xy 112.7887 -22.507194) (xy 112.7887 -21.892006)
			)
		)
		(polygon
			(pts
				(arc
					(start 483.39121 -11.36142)
					(mid 483.336833 -11.281355)
					(end 483.24008 -11.283188)
				)
				(arc
					(start 483.24008 -11.283188)
					(mid 482.878425 -11.387468)
					(end 482.50856 -11.317732)
				)
				(arc
					(start 482.50856 -11.317732)
					(mid 482.403723 -11.331162)
					(end 482.36759 -11.430508)
				)
				(arc
					(start 482.36759 -11.430508)
					(mid 482.383385 -11.59002)
					(end 482.36759 -11.749532)
				)
				(arc
					(start 482.36759 -11.749532)
					(mid 482.403701 -11.848905)
					(end 482.50856 -11.862308)
				)
				(arc
					(start 482.50856 -11.862308)
					(mid 482.878424 -11.792603)
					(end 483.24008 -11.896852)
				)
				(arc
					(start 483.24008 -11.896852)
					(mid 483.33682 -11.898659)
					(end 483.39121 -11.81862)
				)
			)
		)
		(polygon
			(pts
				(xy 268.912594 -11.1633) (xy 264.995406 -11.1633) (xy 264.5791 -11.579606) (xy 264.5791 -13.007594)
				(arc
					(start 264.958068 -13.386562)
					(mid 265.026808 -13.435034)
					(end 265.109706 -13.4493)
				)
				(xy 267.794994 -13.4493) (xy 268.531594 -12.7127) (xy 268.963394 -12.7127) (xy 269.3543 -12.321794)
				(xy 269.3543 -11.605006)
			)
		)
		(polygon
			(pts
				(xy 103.914194 -11.1379) (xy 99.971606 -11.1379) (xy 99.6061 -11.503406) (xy 99.6061 -13.007594)
				(arc
					(start 99.883468 -13.284962)
					(mid 99.952208 -13.333434)
					(end 100.035106 -13.3477)
				)
				(xy 102.872794 -13.3477) (xy 103.507794 -12.7127) (xy 103.990394 -12.7127) (xy 104.3305 -12.372594)
				(xy 104.3305 -11.554206)
			)
		)
		(polygon
			(pts
				(arc
					(start 483.39121 -9.331452)
					(mid 483.336833 -9.251387)
					(end 483.24008 -9.25322)
				)
				(arc
					(start 483.24008 -9.25322)
					(mid 482.878425 -9.3575)
					(end 482.50856 -9.287764)
				)
				(arc
					(start 482.50856 -9.287764)
					(mid 482.403723 -9.301194)
					(end 482.36759 -9.40054)
				)
				(arc
					(start 482.36759 -9.40054)
					(mid 482.383385 -9.560052)
					(end 482.36759 -9.719564)
				)
				(arc
					(start 482.36759 -9.719564)
					(mid 482.403701 -9.818937)
					(end 482.50856 -9.83234)
				)
				(arc
					(start 482.50856 -9.83234)
					(mid 482.878424 -9.762635)
					(end 483.24008 -9.866884)
				)
				(arc
					(start 483.24008 -9.866884)
					(mid 483.33682 -9.868691)
					(end 483.39121 -9.788652)
				)
			)
		)
		(polygon
			(pts
				(arc
					(start 483.39121 -7.301484)
					(mid 483.336833 -7.221419)
					(end 483.24008 -7.223252)
				)
				(arc
					(start 483.24008 -7.223252)
					(mid 482.878425 -7.327532)
					(end 482.50856 -7.257796)
				)
				(arc
					(start 482.50856 -7.257796)
					(mid 482.403723 -7.271226)
					(end 482.36759 -7.370572)
				)
				(arc
					(start 482.36759 -7.370572)
					(mid 482.383385 -7.530084)
					(end 482.36759 -7.689596)
				)
				(arc
					(start 482.36759 -7.689596)
					(mid 482.403701 -7.788969)
					(end 482.50856 -7.802372)
				)
				(arc
					(start 482.50856 -7.802372)
					(mid 482.878424 -7.732667)
					(end 483.24008 -7.836916)
				)
				(arc
					(start 483.24008 -7.836916)
					(mid 483.33682 -7.838723)
					(end 483.39121 -7.758684)
				)
			)
		)
		(polygon
			(pts
				(xy 178.159156 -5.969) (xy 175.027844 -5.969) (xy 174.646844 -6.35) (xy 172.868844 -6.35) (xy 171.704 -7.514844)
				(xy 171.704 -8.784844) (xy 170.561 -9.927844) (xy 170.561 -12.170156) (xy 171.217844 -12.827) (xy 173.122844 -12.827)
				(xy 173.884844 -13.589) (xy 174.857156 -13.589) (xy 175.514 -12.932156) (xy 175.514 -11.281156)
				(xy 175.619156 -11.176) (xy 178.286156 -11.176) (xy 178.689 -10.773156) (xy 178.689 -10.011156)
				(xy 178.943 -9.757156) (xy 178.943 -8.149844) (xy 178.689 -7.895844) (xy 178.689 -6.498844)
			)
		)
		(polygon
			(pts
				(arc
					(start 483.39121 -5.271516)
					(mid 483.336833 -5.191451)
					(end 483.24008 -5.193284)
				)
				(arc
					(start 483.24008 -5.193284)
					(mid 482.864287 -5.298109)
					(end 482.482906 -5.21589)
				)
				(arc
					(start 482.482906 -5.21589)
					(mid 482.375359 -5.227301)
					(end 482.339142 -5.329174)
				)
				(arc
					(start 482.339142 -5.329174)
					(mid 482.35791 -5.500116)
					(end 482.339142 -5.671058)
				)
				(arc
					(start 482.339142 -5.671058)
					(mid 482.375396 -5.772884)
					(end 482.482906 -5.784342)
				)
				(arc
					(start 482.482906 -5.784342)
					(mid 482.864288 -5.702108)
					(end 483.24008 -5.806948)
				)
				(arc
					(start 483.24008 -5.806948)
					(mid 483.33682 -5.808755)
					(end 483.39121 -5.728716)
				)
			)
		)
		(polygon
			(pts
				(arc
					(start 483.39121 -3.241548)
					(mid 483.336833 -3.161483)
					(end 483.24008 -3.163316)
				)
				(arc
					(start 483.24008 -3.163316)
					(mid 482.878425 -3.267596)
					(end 482.50856 -3.19786)
				)
				(arc
					(start 482.50856 -3.19786)
					(mid 482.403723 -3.21129)
					(end 482.36759 -3.310636)
				)
				(arc
					(start 482.36759 -3.310636)
					(mid 482.383385 -3.470148)
					(end 482.36759 -3.62966)
				)
				(arc
					(start 482.36759 -3.62966)
					(mid 482.403701 -3.729033)
					(end 482.50856 -3.742436)
				)
				(arc
					(start 482.50856 -3.742436)
					(mid 482.878424 -3.672731)
					(end 483.24008 -3.77698)
				)
				(arc
					(start 483.24008 -3.77698)
					(mid 483.33682 -3.778787)
					(end 483.39121 -3.698748)
				)
			)
		)
		(polygon
			(pts
				(xy 268.988794 -1.6129) (xy 264.970006 -1.6129) (xy 264.5791 -2.003806) (xy 264.5791 -3.457194)
				(arc
					(start 264.856468 -3.734562)
					(mid 264.925208 -3.783034)
					(end 265.008106 -3.7973)
				)
				(xy 267.845794 -3.7973) (xy 268.531594 -3.1115) (xy 268.963394 -3.1115) (xy 269.3289 -2.745994)
				(xy 269.3289 -1.953006)
			)
		)
		(polygon
			(pts
				(xy 103.863394 -1.5367) (xy 100.047806 -1.5367) (xy 99.5807 -2.003806) (xy 99.5807 -3.380994)
				(arc
					(start 99.908868 -3.709162)
					(mid 99.977608 -3.757634)
					(end 100.060506 -3.7719)
				)
				(xy 102.847394 -3.7719) (xy 103.507794 -3.1115) (xy 103.964994 -3.1115) (xy 104.3051 -2.771394)
				(xy 104.3051 -1.978406)
			)
		)
		(polygon
			(pts
				(arc
					(start 483.39121 -1.21158)
					(mid 483.336833 -1.131515)
					(end 483.24008 -1.133348)
				)
				(arc
					(start 483.24008 -1.133348)
					(mid 482.878425 -1.237628)
					(end 482.50856 -1.167892)
				)
				(arc
					(start 482.50856 -1.167892)
					(mid 482.403723 -1.181322)
					(end 482.36759 -1.280668)
				)
				(arc
					(start 482.36759 -1.280668)
					(mid 482.383385 -1.44018)
					(end 482.36759 -1.599692)
				)
				(arc
					(start 482.36759 -1.599692)
					(mid 482.403701 -1.699065)
					(end 482.50856 -1.712468)
				)
				(arc
					(start 482.50856 -1.712468)
					(mid 482.878424 -1.642763)
					(end 483.24008 -1.747012)
				)
				(arc
					(start 483.24008 -1.747012)
					(mid 483.33682 -1.748819)
					(end 483.39121 -1.66878)
				)
			)
		)
		(polygon
			(pts
				(arc
					(start 483.39121 0.818388)
					(mid 483.336833 0.898453)
					(end 483.24008 0.89662)
				)
				(arc
					(start 483.24008 0.89662)
					(mid 482.878425 0.79234)
					(end 482.50856 0.862076)
				)
				(arc
					(start 482.50856 0.862076)
					(mid 482.403723 0.848646)
					(end 482.36759 0.7493)
				)
				(arc
					(start 482.36759 0.7493)
					(mid 482.383385 0.589788)
					(end 482.36759 0.430276)
				)
				(arc
					(start 482.36759 0.430276)
					(mid 482.403701 0.330903)
					(end 482.50856 0.3175)
				)
				(arc
					(start 482.50856 0.3175)
					(mid 482.878424 0.387205)
					(end 483.24008 0.282956)
				)
				(arc
					(start 483.24008 0.282956)
					(mid 483.33682 0.281149)
					(end 483.39121 0.361188)
				)
			)
		)
	)
	(zone
		(layer "In12.Cu")
		(hatch none 0.5)
		(connect_pads
			(clearance 0)
		)
		(min_thickness 0.25)
		(keepout
			(tracks not_allowed)
			(vias allowed)
			(pads allowed)
			(copperpour not_allowed)
			(footprints allowed)
		)
		(placement
			(enabled no)
			(sheetname "")
		)
		(fill
			(thermal_gap 0.5)
			(thermal_bridge_width 0.5)
			(island_removal_mode 0)
		)
		(polygon
			(pts
				(xy 58.319924 -127.374142) (xy 58.878724 -127.374142) (xy 58.878724 -129.177542) (xy 58.319924 -129.177542)
			)
		)
	)
	(zone
		(layer "In12.Cu")
		(hatch none 0.5)
		(connect_pads
			(clearance 0)
		)
		(min_thickness 0.25)
		(keepout
			(tracks not_allowed)
			(vias allowed)
			(pads allowed)
			(copperpour not_allowed)
			(footprints allowed)
		)
		(placement
			(enabled no)
			(sheetname "")
		)
		(fill
			(thermal_gap 0.5)
			(thermal_bridge_width 0.5)
			(island_removal_mode 0)
		)
		(polygon
			(pts
				(xy 92.32011 -127.374142) (xy 92.87891 -127.374142) (xy 92.87891 -129.177542) (xy 92.32011 -129.177542)
			)
		)
	)
	(zone
		(layer "In12.Cu")
		(hatch none 0.5)
		(connect_pads
			(clearance 0)
		)
		(min_thickness 0.25)
		(keepout
			(tracks not_allowed)
			(vias allowed)
			(pads allowed)
			(copperpour not_allowed)
			(footprints allowed)
		)
		(placement
			(enabled no)
			(sheetname "")
		)
		(fill
			(thermal_gap 0.5)
			(thermal_bridge_width 0.5)
			(island_removal_mode 0)
		)
		(polygon
			(pts
				(xy 86.37016 -131.974082) (xy 86.92896 -131.974082) (xy 86.92896 -133.777482) (xy 86.37016 -133.777482)
			)
		)
	)
	(zone
		(layer "In12.Cu")
		(hatch none 0.5)
		(connect_pads
			(clearance 0)
		)
		(min_thickness 0.25)
		(keepout
			(tracks not_allowed)
			(vias allowed)
			(pads allowed)
			(copperpour not_allowed)
			(footprints allowed)
		)
		(placement
			(enabled no)
			(sheetname "")
		)
		(fill
			(thermal_gap 0.5)
			(thermal_bridge_width 0.5)
			(island_removal_mode 0)
		)
		(polygon
			(pts
				(xy 68.520056 -131.974082) (xy 69.078856 -131.974082) (xy 69.078856 -133.777482) (xy 68.520056 -133.777482)
			)
		)
	)
	(zone
		(layer "In12.Cu")
		(hatch none 0.5)
		(connect_pads
			(clearance 0)
		)
		(min_thickness 0.25)
		(keepout
			(tracks not_allowed)
			(vias allowed)
			(pads allowed)
			(copperpour not_allowed)
			(footprints allowed)
		)
		(placement
			(enabled no)
			(sheetname "")
		)
		(fill
			(thermal_gap 0.5)
			(thermal_bridge_width 0.5)
			(island_removal_mode 0)
		)
		(polygon
			(pts
				(xy 256.470404 -151.176482) (xy 257.029204 -151.176482) (xy 257.029204 -152.979882) (xy 256.470404 -152.979882)
			)
		)
	)
	(zone
		(layer "In12.Cu")
		(hatch none 0.5)
		(connect_pads
			(clearance 0)
		)
		(min_thickness 0.25)
		(keepout
			(tracks not_allowed)
			(vias allowed)
			(pads allowed)
			(copperpour not_allowed)
			(footprints allowed)
		)
		(placement
			(enabled no)
			(sheetname "")
		)
		(fill
			(thermal_gap 0.5)
			(thermal_bridge_width 0.5)
			(island_removal_mode 0)
		)
		(polygon
			(pts
				(xy 86.37016 -4.720082) (xy 86.92896 -4.720082) (xy 86.92896 -6.523482) (xy 86.37016 -6.523482)
			)
		)
	)
	(zone
		(layer "In12.Cu")
		(hatch none 0.5)
		(connect_pads
			(clearance 0)
		)
		(min_thickness 0.25)
		(keepout
			(tracks not_allowed)
			(vias allowed)
			(pads allowed)
			(copperpour not_allowed)
			(footprints allowed)
		)
		(placement
			(enabled no)
			(sheetname "")
		)
		(fill
			(thermal_gap 0.5)
			(thermal_bridge_width 0.5)
			(island_removal_mode 0)
		)
		(polygon
			(pts
				(xy 91.469972 -141.575282) (xy 92.028772 -141.575282) (xy 92.028772 -143.378682) (xy 91.469972 -143.378682)
			)
		)
	)
	(zone
		(layer "In12.Cu")
		(hatch none 0.5)
		(connect_pads
			(clearance 0)
		)
		(min_thickness 0.25)
		(keepout
			(tracks not_allowed)
			(vias allowed)
			(pads allowed)
			(copperpour not_allowed)
			(footprints allowed)
		)
		(placement
			(enabled no)
			(sheetname "")
		)
		(fill
			(thermal_gap 0.5)
			(thermal_bridge_width 0.5)
			(island_removal_mode 0)
		)
		(polygon
			(pts
				(xy 225.870516 -131.974082) (xy 226.429316 -131.974082) (xy 226.429316 -133.777482) (xy 225.870516 -133.777482)
			)
		)
	)
	(zone
		(layer "In12.Cu")
		(hatch none 0.5)
		(connect_pads
			(clearance 0)
		)
		(min_thickness 0.25)
		(keepout
			(tracks not_allowed)
			(vias allowed)
			(pads allowed)
			(copperpour not_allowed)
			(footprints allowed)
		)
		(placement
			(enabled no)
			(sheetname "")
		)
		(fill
			(thermal_gap 0.5)
			(thermal_bridge_width 0.5)
			(island_removal_mode 0)
		)
		(polygon
			(pts
				(xy 32.820102 -141.575282) (xy 33.378902 -141.575282) (xy 33.378902 -143.378682) (xy 32.820102 -143.378682)
			)
		)
	)
	(zone
		(layer "In12.Cu")
		(hatch none 0.5)
		(connect_pads
			(clearance 0)
		)
		(min_thickness 0.25)
		(keepout
			(tracks not_allowed)
			(vias allowed)
			(pads allowed)
			(copperpour not_allowed)
			(footprints allowed)
		)
		(placement
			(enabled no)
			(sheetname "")
		)
		(fill
			(thermal_gap 0.5)
			(thermal_bridge_width 0.5)
			(island_removal_mode 0)
		)
		(polygon
			(pts
				(xy 276.02053 -127.374142) (xy 276.57933 -127.374142) (xy 276.57933 -129.177542) (xy 276.02053 -129.177542)
			)
		)
	)
	(zone
		(layer "In12.Cu")
		(hatch none 0.5)
		(connect_pads
			(clearance 0)
		)
		(min_thickness 0.25)
		(keepout
			(tracks not_allowed)
			(vias allowed)
			(pads allowed)
			(copperpour not_allowed)
			(footprints allowed)
		)
		(placement
			(enabled no)
			(sheetname "")
		)
		(fill
			(thermal_gap 0.5)
			(thermal_bridge_width 0.5)
			(island_removal_mode 0)
		)
		(polygon
			(pts
				(xy 453.9742 -51.187858) (xy 454.4822 -51.187858) (xy 454.4822 -52.584858) (xy 453.9742 -52.584858)
			)
		)
	)
	(zone
		(layer "In12.Cu")
		(hatch none 0.5)
		(connect_pads
			(clearance 0)
		)
		(min_thickness 0.25)
		(keepout
			(tracks not_allowed)
			(vias allowed)
			(pads allowed)
			(copperpour not_allowed)
			(footprints allowed)
		)
		(placement
			(enabled no)
			(sheetname "")
		)
		(fill
			(thermal_gap 0.5)
			(thermal_bridge_width 0.5)
			(island_removal_mode 0)
		)
		(polygon
			(pts
				(xy 120.370092 -131.974082) (xy 120.928892 -131.974082) (xy 120.928892 -133.777482) (xy 120.370092 -133.777482)
			)
		)
	)
	(zone
		(layer "In12.Cu")
		(hatch none 0.5)
		(connect_pads
			(clearance 0)
		)
		(min_thickness 0.25)
		(keepout
			(tracks not_allowed)
			(vias allowed)
			(pads allowed)
			(copperpour not_allowed)
			(footprints allowed)
		)
		(placement
			(enabled no)
			(sheetname "")
		)
		(fill
			(thermal_gap 0.5)
			(thermal_bridge_width 0.5)
			(island_removal_mode 0)
		)
		(polygon
			(pts
				(xy 267.52042 -0.120142) (xy 268.07922 -0.120142) (xy 268.07922 -1.923542) (xy 267.52042 -1.923542)
			)
		)
	)
	(zone
		(layer "In12.Cu")
		(hatch none 0.5)
		(connect_pads
			(clearance 0)
		)
		(min_thickness 0.25)
		(keepout
			(tracks not_allowed)
			(vias allowed)
			(pads allowed)
			(copperpour not_allowed)
			(footprints allowed)
		)
		(placement
			(enabled no)
			(sheetname "")
		)
		(fill
			(thermal_gap 0.5)
			(thermal_bridge_width 0.5)
			(island_removal_mode 0)
		)
		(polygon
			(pts
				(xy 122.070114 -23.922482) (xy 122.628914 -23.922482) (xy 122.628914 -25.725882) (xy 122.070114 -25.725882)
			)
		)
	)
	(zone
		(layer "In12.Cu")
		(hatch none 0.5)
		(connect_pads
			(clearance 0)
		)
		(min_thickness 0.25)
		(keepout
			(tracks not_allowed)
			(vias allowed)
			(pads allowed)
			(copperpour not_allowed)
			(footprints allowed)
		)
		(placement
			(enabled no)
			(sheetname "")
		)
		(fill
			(thermal_gap 0.5)
			(thermal_bridge_width 0.5)
			(island_removal_mode 0)
		)
		(polygon
			(pts
				(xy 267.52042 -19.322542) (xy 268.07922 -19.322542) (xy 268.07922 -21.125942) (xy 267.52042 -21.125942)
			)
		)
	)
	(zone
		(layer "In12.Cu")
		(hatch none 0.5)
		(connect_pads
			(clearance 0)
		)
		(min_thickness 0.25)
		(keepout
			(tracks not_allowed)
			(vias allowed)
			(pads allowed)
			(copperpour not_allowed)
			(footprints allowed)
		)
		(placement
			(enabled no)
			(sheetname "")
		)
		(fill
			(thermal_gap 0.5)
			(thermal_bridge_width 0.5)
			(island_removal_mode 0)
		)
		(polygon
			(pts
				(xy 48.96993 -127.374142) (xy 49.52873 -127.374142) (xy 49.52873 -129.177542) (xy 48.96993 -129.177542)
			)
		)
	)
	(zone
		(layer "In12.Cu")
		(hatch none 0.5)
		(connect_pads
			(clearance 0)
		)
		(min_thickness 0.25)
		(keepout
			(tracks not_allowed)
			(vias allowed)
			(pads allowed)
			(copperpour not_allowed)
			(footprints allowed)
		)
		(placement
			(enabled no)
			(sheetname "")
		)
		(fill
			(thermal_gap 0.5)
			(thermal_bridge_width 0.5)
			(island_removal_mode 0)
		)
		(polygon
			(pts
				(xy 301.520352 -151.176482) (xy 302.079152 -151.176482) (xy 302.079152 -152.979882) (xy 301.520352 -152.979882)
			)
		)
	)
	(zone
		(layer "In12.Cu")
		(hatch none 0.5)
		(connect_pads
			(clearance 0)
		)
		(min_thickness 0.25)
		(keepout
			(tracks not_allowed)
			(vias allowed)
			(pads allowed)
			(copperpour not_allowed)
			(footprints allowed)
		)
		(placement
			(enabled no)
			(sheetname "")
		)
		(fill
			(thermal_gap 0.5)
			(thermal_bridge_width 0.5)
			(island_removal_mode 0)
		)
		(polygon
			(pts
				(xy 49.820068 -151.176482) (xy 50.378868 -151.176482) (xy 50.378868 -152.979882) (xy 49.820068 -152.979882)
			)
		)
	)
	(zone
		(layer "In12.Cu")
		(hatch none 0.5)
		(connect_pads
			(clearance 0)
		)
		(min_thickness 0.25)
		(keepout
			(tracks not_allowed)
			(vias allowed)
			(pads allowed)
			(copperpour not_allowed)
			(footprints allowed)
		)
		(placement
			(enabled no)
			(sheetname "")
		)
		(fill
			(thermal_gap 0.5)
			(thermal_bridge_width 0.5)
			(island_removal_mode 0)
		)
		(polygon
			(pts
				(xy 292.170358 -14.321282) (xy 292.729158 -14.321282) (xy 292.729158 -16.124682) (xy 292.170358 -16.124682)
			)
		)
	)
	(zone
		(layer "In12.Cu")
		(hatch none 0.5)
		(connect_pads
			(clearance 0)
		)
		(min_thickness 0.25)
		(keepout
			(tracks not_allowed)
			(vias allowed)
			(pads allowed)
			(copperpour not_allowed)
			(footprints allowed)
		)
		(placement
			(enabled no)
			(sheetname "")
		)
		(fill
			(thermal_gap 0.5)
			(thermal_bridge_width 0.5)
			(island_removal_mode 0)
		)
		(polygon
			(pts
				(xy 283.670502 -0.120142) (xy 284.229302 -0.120142) (xy 284.229302 -1.923542) (xy 283.670502 -1.923542)
			)
		)
	)
	(zone
		(layer "In12.Cu")
		(hatch none 0.5)
		(connect_pads
			(clearance 0)
		)
		(min_thickness 0.25)
		(keepout
			(tracks not_allowed)
			(vias allowed)
			(pads allowed)
			(copperpour not_allowed)
			(footprints allowed)
		)
		(placement
			(enabled no)
			(sheetname "")
		)
		(fill
			(thermal_gap 0.5)
			(thermal_bridge_width 0.5)
			(island_removal_mode 0)
		)
		(polygon
			(pts
				(xy 144.169892 -14.321282) (xy 144.728692 -14.321282) (xy 144.728692 -16.124682) (xy 144.169892 -16.124682)
			)
		)
	)
	(zone
		(layer "In12.Cu")
		(hatch none 0.5)
		(connect_pads
			(clearance 0)
		)
		(min_thickness 0.25)
		(keepout
			(tracks not_allowed)
			(vias allowed)
			(pads allowed)
			(copperpour not_allowed)
			(footprints allowed)
		)
		(placement
			(enabled no)
			(sheetname "")
		)
		(fill
			(thermal_gap 0.5)
			(thermal_bridge_width 0.5)
			(island_removal_mode 0)
		)
		(polygon
			(pts
				(xy 312.570368 -9.721342) (xy 313.129168 -9.721342) (xy 313.129168 -11.524742) (xy 312.570368 -11.524742)
			)
		)
	)
	(zone
		(layer "In12.Cu")
		(hatch none 0.5)
		(connect_pads
			(clearance 0)
		)
		(min_thickness 0.25)
		(keepout
			(tracks not_allowed)
			(vias allowed)
			(pads allowed)
			(copperpour not_allowed)
			(footprints allowed)
		)
		(placement
			(enabled no)
			(sheetname "")
		)
		(fill
			(thermal_gap 0.5)
			(thermal_bridge_width 0.5)
			(island_removal_mode 0)
		)
		(polygon
			(pts
				(xy 54.069996 -136.975342) (xy 54.628796 -136.975342) (xy 54.628796 -138.778742) (xy 54.069996 -138.778742)
			)
		)
	)
	(zone
		(net "PVDDQ_GHJ")
		(layer "In12.Cu")
		(hatch none 0.5)
		(connect_pads
			(clearance 0.5)
		)
		(min_thickness 0.25)
		(fill yes
			(thermal_gap 0.5)
			(thermal_bridge_width 0.5)
			(island_removal_mode 0)
		)
		(polygon
			(pts
				(xy 100.281994 -21.1201) (xy 100.0379 -21.364194) (xy 100.0379 -22.603206) (xy 101.297994 -23.8633)
				(xy 112.366806 -23.8633) (xy 112.5093 -23.720806) (xy 112.5093 -23.472394) (xy 112.2553 -23.218394)
				(xy 112.2553 -22.501606) (xy 112.4077 -22.349206) (xy 112.4077 -22.049994) (xy 111.477806 -21.1201)
			)
		)
	)
	(zone
		(layer "In12.Cu")
		(hatch none 0.5)
		(connect_pads
			(clearance 0)
		)
		(min_thickness 0.25)
		(keepout
			(tracks not_allowed)
			(vias allowed)
			(pads allowed)
			(copperpour not_allowed)
			(footprints allowed)
		)
		(placement
			(enabled no)
			(sheetname "")
		)
		(fill
			(thermal_gap 0.5)
			(thermal_bridge_width 0.5)
			(island_removal_mode 0)
		)
		(polygon
			(pts
				(xy 92.32011 -151.176482) (xy 92.87891 -151.176482) (xy 92.87891 -152.979882) (xy 92.32011 -152.979882)
			)
		)
	)
	(zone
		(layer "In12.Cu")
		(hatch none 0.5)
		(connect_pads
			(clearance 0)
		)
		(min_thickness 0.25)
		(keepout
			(tracks not_allowed)
			(vias allowed)
			(pads allowed)
			(copperpour not_allowed)
			(footprints allowed)
		)
		(placement
			(enabled no)
			(sheetname "")
		)
		(fill
			(thermal_gap 0.5)
			(thermal_bridge_width 0.5)
			(island_removal_mode 0)
		)
		(polygon
			(pts
				(xy 360.10088 -76.780136) (xy 360.10088 -79.066136) (xy 359.59288 -79.066136) (xy 359.59288 -76.780136)
			)
		)
	)
	(zone
		(layer "In12.Cu")
		(hatch none 0.5)
		(connect_pads
			(clearance 0)
		)
		(min_thickness 0.25)
		(keepout
			(tracks not_allowed)
			(vias allowed)
			(pads allowed)
			(copperpour not_allowed)
			(footprints allowed)
		)
		(placement
			(enabled no)
			(sheetname "")
		)
		(fill
			(thermal_gap 0.5)
			(thermal_bridge_width 0.5)
			(island_removal_mode 0)
		)
		(polygon
			(pts
				(xy 205.470506 -141.575282) (xy 206.029306 -141.575282) (xy 206.029306 -143.378682) (xy 205.470506 -143.378682)
			)
		)
	)
	(zone
		(layer "In12.Cu")
		(hatch none 0.5)
		(connect_pads
			(clearance 0)
		)
		(min_thickness 0.25)
		(keepout
			(tracks not_allowed)
			(vias allowed)
			(pads allowed)
			(copperpour not_allowed)
			(footprints allowed)
		)
		(placement
			(enabled no)
			(sheetname "")
		)
		(fill
			(thermal_gap 0.5)
			(thermal_bridge_width 0.5)
			(island_removal_mode 0)
		)
		(polygon
			(pts
				(xy 141.619986 -9.721342) (xy 142.178786 -9.721342) (xy 142.178786 -11.524742) (xy 141.619986 -11.524742)
			)
		)
	)
	(zone
		(net "PVDDQ_KLM")
		(layer "In12.Cu")
		(hatch none 0.5)
		(connect_pads
			(clearance 0.5)
		)
		(min_thickness 0.25)
		(fill yes
			(thermal_gap 0.5)
			(thermal_bridge_width 0.5)
			(island_removal_mode 0)
		)
		(polygon
			(pts
				(xy 100.154994 -138.7729) (xy 100.0379 -138.889994) (xy 100.0379 -139.824206) (xy 100.129594 -139.9159)
				(xy 103.019606 -139.9159) (xy 103.349806 -139.5857) (xy 103.807006 -139.5857) (xy 103.9495 -139.443206)
				(xy 103.9495 -139.016994) (xy 103.705406 -138.7729)
			)
		)
	)
	(zone
		(layer "In12.Cu")
		(hatch none 0.5)
		(connect_pads
			(clearance 0)
		)
		(min_thickness 0.25)
		(keepout
			(tracks not_allowed)
			(vias allowed)
			(pads allowed)
			(copperpour not_allowed)
			(footprints allowed)
		)
		(placement
			(enabled no)
			(sheetname "")
		)
		(fill
			(thermal_gap 0.5)
			(thermal_bridge_width 0.5)
			(island_removal_mode 0)
		)
		(polygon
			(pts
				(xy 45.57014 -127.374142) (xy 46.12894 -127.374142) (xy 46.12894 -129.177542) (xy 45.57014 -129.177542)
			)
		)
	)
	(zone
		(layer "In12.Cu")
		(hatch none 0.5)
		(connect_pads
			(clearance 0)
		)
		(min_thickness 0.25)
		(keepout
			(tracks not_allowed)
			(vias allowed)
			(pads allowed)
			(copperpour not_allowed)
			(footprints allowed)
		)
		(placement
			(enabled no)
			(sheetname "")
		)
		(fill
			(thermal_gap 0.5)
			(thermal_bridge_width 0.5)
			(island_removal_mode 0)
		)
		(polygon
			(pts
				(xy 112.72012 -141.575282) (xy 113.27892 -141.575282) (xy 113.27892 -143.378682) (xy 112.72012 -143.378682)
			)
		)
	)
	(zone
		(layer "In12.Cu")
		(hatch none 0.5)
		(connect_pads
			(clearance 0)
		)
		(min_thickness 0.25)
		(keepout
			(tracks not_allowed)
			(vias allowed)
			(pads allowed)
			(copperpour not_allowed)
			(footprints allowed)
		)
		(placement
			(enabled no)
			(sheetname "")
		)
		(fill
			(thermal_gap 0.5)
			(thermal_bridge_width 0.5)
			(island_removal_mode 0)
		)
		(polygon
			(pts
				(xy 216.520522 -4.720082) (xy 217.079322 -4.720082) (xy 217.079322 -6.523482) (xy 216.520522 -6.523482)
			)
		)
	)
	(zone
		(layer "In12.Cu")
		(hatch none 0.5)
		(connect_pads
			(clearance 0)
		)
		(min_thickness 0.25)
		(keepout
			(tracks not_allowed)
			(vias allowed)
			(pads allowed)
			(copperpour not_allowed)
			(footprints allowed)
		)
		(placement
			(enabled no)
			(sheetname "")
		)
		(fill
			(thermal_gap 0.5)
			(thermal_bridge_width 0.5)
			(island_removal_mode 0)
		)
		(polygon
			(pts
				(xy 270.07058 -141.575282) (xy 270.62938 -141.575282) (xy 270.62938 -143.378682) (xy 270.07058 -143.378682)
			)
		)
	)
	(zone
		(layer "In12.Cu")
		(hatch none 0.5)
		(connect_pads
			(clearance 0)
		)
		(min_thickness 0.25)
		(keepout
			(tracks not_allowed)
			(vias allowed)
			(pads allowed)
			(copperpour not_allowed)
			(footprints allowed)
		)
		(placement
			(enabled no)
			(sheetname "")
		)
		(fill
			(thermal_gap 0.5)
			(thermal_bridge_width 0.5)
			(island_removal_mode 0)
		)
		(polygon
			(pts
				(xy 58.319924 -9.721342) (xy 58.878724 -9.721342) (xy 58.878724 -11.524742) (xy 58.319924 -11.524742)
			)
		)
	)
	(zone
		(layer "In12.Cu")
		(hatch none 0.5)
		(connect_pads
			(clearance 0)
		)
		(min_thickness 0.25)
		(keepout
			(tracks not_allowed)
			(vias allowed)
			(pads allowed)
			(copperpour not_allowed)
			(footprints allowed)
		)
		(placement
			(enabled no)
			(sheetname "")
		)
		(fill
			(thermal_gap 0.5)
			(thermal_bridge_width 0.5)
			(island_removal_mode 0)
		)
		(polygon
			(pts
				(xy 221.620588 -127.374142) (xy 222.179388 -127.374142) (xy 222.179388 -129.177542) (xy 221.620588 -129.177542)
			)
		)
	)
	(zone
		(layer "In12.Cu")
		(hatch none 0.5)
		(connect_pads
			(clearance 0)
		)
		(min_thickness 0.25)
		(keepout
			(tracks not_allowed)
			(vias allowed)
			(pads allowed)
			(copperpour not_allowed)
			(footprints allowed)
		)
		(placement
			(enabled no)
			(sheetname "")
		)
		(fill
			(thermal_gap 0.5)
			(thermal_bridge_width 0.5)
			(island_removal_mode 0)
		)
		(polygon
			(pts
				(xy 48.120046 -4.720082) (xy 48.678846 -4.720082) (xy 48.678846 -6.523482) (xy 48.120046 -6.523482)
			)
		)
	)
	(zone
		(layer "In12.Cu")
		(hatch none 0.5)
		(connect_pads
			(clearance 0)
		)
		(min_thickness 0.25)
		(keepout
			(tracks not_allowed)
			(vias allowed)
			(pads allowed)
			(copperpour not_allowed)
			(footprints allowed)
		)
		(placement
			(enabled no)
			(sheetname "")
		)
		(fill
			(thermal_gap 0.5)
			(thermal_bridge_width 0.5)
			(island_removal_mode 0)
		)
		(polygon
			(pts
				(xy 147.569936 -19.322542) (xy 148.128736 -19.322542) (xy 148.128736 -21.125942) (xy 147.569936 -21.125942)
			)
		)
	)
	(zone
		(layer "In12.Cu")
		(hatch none 0.5)
		(connect_pads
			(clearance 0)
		)
		(min_thickness 0.25)
		(keepout
			(tracks not_allowed)
			(vias allowed)
			(pads allowed)
			(copperpour not_allowed)
			(footprints allowed)
		)
		(placement
			(enabled no)
			(sheetname "")
		)
		(fill
			(thermal_gap 0.5)
			(thermal_bridge_width 0.5)
			(island_removal_mode 0)
		)
		(polygon
			(pts
				(xy 146.720052 -19.322542) (xy 147.278852 -19.322542) (xy 147.278852 -21.125942) (xy 146.720052 -21.125942)
			)
		)
	)
	(zone
		(layer "In12.Cu")
		(hatch none 0.5)
		(connect_pads
			(clearance 0)
		)
		(min_thickness 0.25)
		(keepout
			(tracks not_allowed)
			(vias allowed)
			(pads allowed)
			(copperpour not_allowed)
			(footprints allowed)
		)
		(placement
			(enabled no)
			(sheetname "")
		)
		(fill
			(thermal_gap 0.5)
			(thermal_bridge_width 0.5)
			(island_removal_mode 0)
		)
		(polygon
			(pts
				(xy 256.470404 -141.575282) (xy 257.029204 -141.575282) (xy 257.029204 -143.378682) (xy 256.470404 -143.378682)
			)
		)
	)
	(zone
		(layer "In12.Cu")
		(hatch none 0.5)
		(connect_pads
			(clearance 0)
		)
		(min_thickness 0.25)
		(keepout
			(tracks not_allowed)
			(vias allowed)
			(pads allowed)
			(copperpour not_allowed)
			(footprints allowed)
		)
		(placement
			(enabled no)
			(sheetname "")
		)
		(fill
			(thermal_gap 0.5)
			(thermal_bridge_width 0.5)
			(island_removal_mode 0)
		)
		(polygon
			(pts
				(xy 267.52042 -151.176482) (xy 268.07922 -151.176482) (xy 268.07922 -152.979882) (xy 267.52042 -152.979882)
			)
		)
	)
	(zone
		(layer "In12.Cu")
		(hatch none 0.5)
		(connect_pads
			(clearance 0)
		)
		(min_thickness 0.25)
		(keepout
			(tracks not_allowed)
			(vias allowed)
			(pads allowed)
			(copperpour not_allowed)
			(footprints allowed)
		)
		(placement
			(enabled no)
			(sheetname "")
		)
		(fill
			(thermal_gap 0.5)
			(thermal_bridge_width 0.5)
			(island_removal_mode 0)
		)
		(polygon
			(pts
				(xy 285.370524 -141.575282) (xy 285.929324 -141.575282) (xy 285.929324 -143.378682) (xy 285.370524 -143.378682)
			)
		)
	)
	(zone
		(layer "In12.Cu")
		(hatch none 0.5)
		(connect_pads
			(clearance 0)
		)
		(min_thickness 0.25)
		(keepout
			(tracks not_allowed)
			(vias allowed)
			(pads allowed)
			(copperpour not_allowed)
			(footprints allowed)
		)
		(placement
			(enabled no)
			(sheetname "")
		)
		(fill
			(thermal_gap 0.5)
			(thermal_bridge_width 0.5)
			(island_removal_mode 0)
		)
		(polygon
			(pts
				(xy 288.770314 -4.720082) (xy 289.329114 -4.720082) (xy 289.329114 -6.523482) (xy 288.770314 -6.523482)
			)
		)
	)
	(zone
		(layer "In12.Cu")
		(hatch none 0.5)
		(connect_pads
			(clearance 0)
		)
		(min_thickness 0.25)
		(keepout
			(tracks not_allowed)
			(vias allowed)
			(pads allowed)
			(copperpour not_allowed)
			(footprints allowed)
		)
		(placement
			(enabled no)
			(sheetname "")
		)
		(fill
			(thermal_gap 0.5)
			(thermal_bridge_width 0.5)
			(island_removal_mode 0)
		)
		(polygon
			(pts
				(xy 121.219976 -0.120142) (xy 121.778776 -0.120142) (xy 121.778776 -1.923542) (xy 121.219976 -1.923542)
			)
		)
	)
	(zone
		(layer "In12.Cu")
		(hatch none 0.5)
		(connect_pads
			(clearance 0)
		)
		(min_thickness 0.25)
		(keepout
			(tracks not_allowed)
			(vias allowed)
			(pads allowed)
			(copperpour not_allowed)
			(footprints allowed)
		)
		(placement
			(enabled no)
			(sheetname "")
		)
		(fill
			(thermal_gap 0.5)
			(thermal_bridge_width 0.5)
			(island_removal_mode 0)
		)
		(polygon
			(pts
				(xy 69.36994 -0.120142) (xy 69.92874 -0.120142) (xy 69.92874 -1.923542) (xy 69.36994 -1.923542)
			)
		)
	)
	(zone
		(layer "In12.Cu")
		(hatch none 0.5)
		(connect_pads
			(clearance 0)
		)
		(min_thickness 0.25)
		(keepout
			(tracks not_allowed)
			(vias allowed)
			(pads allowed)
			(copperpour not_allowed)
			(footprints allowed)
		)
		(placement
			(enabled no)
			(sheetname "")
		)
		(fill
			(thermal_gap 0.5)
			(thermal_bridge_width 0.5)
			(island_removal_mode 0)
		)
		(polygon
			(pts
				(xy 133.119876 -14.321282) (xy 133.678676 -14.321282) (xy 133.678676 -16.124682) (xy 133.119876 -16.124682)
			)
		)
	)
	(zone
		(layer "In12.Cu")
		(hatch none 0.5)
		(connect_pads
			(clearance 0)
		)
		(min_thickness 0.25)
		(keepout
			(tracks not_allowed)
			(vias allowed)
			(pads allowed)
			(copperpour not_allowed)
			(footprints allowed)
		)
		(placement
			(enabled no)
			(sheetname "")
		)
		(fill
			(thermal_gap 0.5)
			(thermal_bridge_width 0.5)
			(island_removal_mode 0)
		)
		(polygon
			(pts
				(xy 277.720552 -146.576542) (xy 278.279352 -146.576542) (xy 278.279352 -148.379942) (xy 277.720552 -148.379942)
			)
		)
	)
	(zone
		(layer "In12.Cu")
		(hatch none 0.5)
		(connect_pads
			(clearance 0)
		)
		(min_thickness 0.25)
		(keepout
			(tracks not_allowed)
			(vias allowed)
			(pads allowed)
			(copperpour not_allowed)
			(footprints allowed)
		)
		(placement
			(enabled no)
			(sheetname "")
		)
		(fill
			(thermal_gap 0.5)
			(thermal_bridge_width 0.5)
			(island_removal_mode 0)
		)
		(polygon
			(pts
				(xy 292.170358 -4.720082) (xy 292.729158 -4.720082) (xy 292.729158 -6.523482) (xy 292.170358 -6.523482)
			)
		)
	)
	(zone
		(layer "In12.Cu")
		(hatch none 0.5)
		(connect_pads
			(clearance 0)
		)
		(min_thickness 0.25)
		(keepout
			(tracks not_allowed)
			(vias allowed)
			(pads allowed)
			(copperpour not_allowed)
			(footprints allowed)
		)
		(placement
			(enabled no)
			(sheetname "")
		)
		(fill
			(thermal_gap 0.5)
			(thermal_bridge_width 0.5)
			(island_removal_mode 0)
		)
		(polygon
			(pts
				(xy 422.021 -142.0114) (xy 422.783 -142.0114) (xy 422.783 -141.0208) (xy 422.021 -141.0208)
			)
		)
	)
	(zone
		(layer "In12.Cu")
		(hatch none 0.5)
		(connect_pads
			(clearance 0)
		)
		(min_thickness 0.25)
		(keepout
			(tracks not_allowed)
			(vias allowed)
			(pads allowed)
			(copperpour not_allowed)
			(footprints allowed)
		)
		(placement
			(enabled no)
			(sheetname "")
		)
		(fill
			(thermal_gap 0.5)
			(thermal_bridge_width 0.5)
			(island_removal_mode 0)
		)
		(polygon
			(pts
				(xy 218.220544 -131.974082) (xy 218.779344 -131.974082) (xy 218.779344 -133.777482) (xy 218.220544 -133.777482)
			)
		)
	)
	(zone
		(layer "In12.Cu")
		(hatch none 0.5)
		(connect_pads
			(clearance 0)
		)
		(min_thickness 0.25)
		(keepout
			(tracks not_allowed)
			(vias allowed)
			(pads allowed)
			(copperpour not_allowed)
			(footprints allowed)
		)
		(placement
			(enabled no)
			(sheetname "")
		)
		(fill
			(thermal_gap 0.5)
			(thermal_bridge_width 0.5)
			(island_removal_mode 0)
		)
		(polygon
			(pts
				(xy 244.570504 -131.974082) (xy 245.129304 -131.974082) (xy 245.129304 -133.777482) (xy 244.570504 -133.777482)
			)
		)
	)
	(zone
		(layer "In12.Cu")
		(hatch none 0.5)
		(connect_pads
			(clearance 0)
		)
		(min_thickness 0.25)
		(keepout
			(tracks not_allowed)
			(vias allowed)
			(pads allowed)
			(copperpour not_allowed)
			(footprints allowed)
		)
		(placement
			(enabled no)
			(sheetname "")
		)
		(fill
			(thermal_gap 0.5)
			(thermal_bridge_width 0.5)
			(island_removal_mode 0)
		)
		(polygon
			(pts
				(xy 286.220408 -146.576542) (xy 286.779208 -146.576542) (xy 286.779208 -148.379942) (xy 286.220408 -148.379942)
			)
		)
	)
	(zone
		(layer "In12.Cu")
		(hatch none 0.5)
		(connect_pads
			(clearance 0)
		)
		(min_thickness 0.25)
		(keepout
			(tracks not_allowed)
			(vias allowed)
			(pads allowed)
			(copperpour not_allowed)
			(footprints allowed)
		)
		(placement
			(enabled no)
			(sheetname "")
		)
		(fill
			(thermal_gap 0.5)
			(thermal_bridge_width 0.5)
			(island_removal_mode 0)
		)
		(polygon
			(pts
				(xy 39.619936 -0.120142) (xy 40.178736 -0.120142) (xy 40.178736 -1.923542) (xy 39.619936 -1.923542)
			)
		)
	)
	(zone
		(layer "In12.Cu")
		(hatch none 0.5)
		(connect_pads
			(clearance 0)
		)
		(min_thickness 0.25)
		(keepout
			(tracks not_allowed)
			(vias allowed)
			(pads allowed)
			(copperpour not_allowed)
			(footprints allowed)
		)
		(placement
			(enabled no)
			(sheetname "")
		)
		(fill
			(thermal_gap 0.5)
			(thermal_bridge_width 0.5)
			(island_removal_mode 0)
		)
		(polygon
			(pts
				(xy 34.520124 -131.974082) (xy 35.078924 -131.974082) (xy 35.078924 -133.777482) (xy 34.520124 -133.777482)
			)
		)
	)
	(zone
		(layer "In12.Cu")
		(hatch none 0.5)
		(connect_pads
			(clearance 0)
		)
		(min_thickness 0.25)
		(keepout
			(tracks not_allowed)
			(vias allowed)
			(pads allowed)
			(copperpour not_allowed)
			(footprints allowed)
		)
		(placement
			(enabled no)
			(sheetname "")
		)
		(fill
			(thermal_gap 0.5)
			(thermal_bridge_width 0.5)
			(island_removal_mode 0)
		)
		(polygon
			(pts
				(xy 272.620486 -4.720082) (xy 273.179286 -4.720082) (xy 273.179286 -6.523482) (xy 272.620486 -6.523482)
			)
		)
	)
	(zone
		(layer "In12.Cu")
		(hatch none 0.5)
		(connect_pads
			(clearance 0)
		)
		(min_thickness 0.25)
		(keepout
			(tracks not_allowed)
			(vias allowed)
			(pads allowed)
			(copperpour not_allowed)
			(footprints allowed)
		)
		(placement
			(enabled no)
			(sheetname "")
		)
		(fill
			(thermal_gap 0.5)
			(thermal_bridge_width 0.5)
			(island_removal_mode 0)
		)
		(polygon
			(pts
				(xy 251.370592 -131.974082) (xy 251.929392 -131.974082) (xy 251.929392 -133.777482) (xy 251.370592 -133.777482)
			)
		)
	)
	(zone
		(layer "In12.Cu")
		(hatch none 0.5)
		(connect_pads
			(clearance 0)
		)
		(min_thickness 0.25)
		(keepout
			(tracks not_allowed)
			(vias allowed)
			(pads allowed)
			(copperpour not_allowed)
			(footprints allowed)
		)
		(placement
			(enabled no)
			(sheetname "")
		)
		(fill
			(thermal_gap 0.5)
			(thermal_bridge_width 0.5)
			(island_removal_mode 0)
		)
		(polygon
			(pts
				(xy 208.020412 -0.120142) (xy 208.579212 -0.120142) (xy 208.579212 -1.923542) (xy 208.020412 -1.923542)
			)
		)
	)
	(zone
		(layer "In12.Cu")
		(hatch none 0.5)
		(connect_pads
			(clearance 0)
		)
		(min_thickness 0.25)
		(keepout
			(tracks not_allowed)
			(vias allowed)
			(pads allowed)
			(copperpour not_allowed)
			(footprints allowed)
		)
		(placement
			(enabled no)
			(sheetname "")
		)
		(fill
			(thermal_gap 0.5)
			(thermal_bridge_width 0.5)
			(island_removal_mode 0)
		)
		(polygon
			(pts
				(xy 307.470302 -4.720082) (xy 308.029102 -4.720082) (xy 308.029102 -6.523482) (xy 307.470302 -6.523482)
			)
		)
	)
	(zone
		(layer "In12.Cu")
		(hatch none 0.5)
		(connect_pads
			(clearance 0)
		)
		(min_thickness 0.25)
		(keepout
			(tracks not_allowed)
			(vias allowed)
			(pads allowed)
			(copperpour not_allowed)
			(footprints allowed)
		)
		(placement
			(enabled no)
			(sheetname "")
		)
		(fill
			(thermal_gap 0.5)
			(thermal_bridge_width 0.5)
			(island_removal_mode 0)
		)
		(polygon
			(pts
				(xy 105.070148 -4.720082) (xy 105.628948 -4.720082) (xy 105.628948 -6.523482) (xy 105.070148 -6.523482)
			)
		)
	)
	(zone
		(layer "In12.Cu")
		(hatch none 0.5)
		(connect_pads
			(clearance 0)
		)
		(min_thickness 0.25)
		(keepout
			(tracks not_allowed)
			(vias allowed)
			(pads allowed)
			(copperpour not_allowed)
			(footprints allowed)
		)
		(placement
			(enabled no)
			(sheetname "")
		)
		(fill
			(thermal_gap 0.5)
			(thermal_bridge_width 0.5)
			(island_removal_mode 0)
		)
		(polygon
			(pts
				(xy 64.270128 -19.322542) (xy 64.828928 -19.322542) (xy 64.828928 -21.125942) (xy 64.270128 -21.125942)
			)
		)
	)
	(zone
		(layer "In12.Cu")
		(hatch none 0.5)
		(connect_pads
			(clearance 0)
		)
		(min_thickness 0.25)
		(keepout
			(tracks not_allowed)
			(vias allowed)
			(pads allowed)
			(copperpour not_allowed)
			(footprints allowed)
		)
		(placement
			(enabled no)
			(sheetname "")
		)
		(fill
			(thermal_gap 0.5)
			(thermal_bridge_width 0.5)
			(island_removal_mode 0)
		)
		(polygon
			(pts
				(xy 116.970048 -19.322542) (xy 117.528848 -19.322542) (xy 117.528848 -21.125942) (xy 116.970048 -21.125942)
			)
		)
	)
	(zone
		(layer "In12.Cu")
		(hatch none 0.5)
		(connect_pads
			(clearance 0)
		)
		(min_thickness 0.25)
		(keepout
			(tracks not_allowed)
			(vias allowed)
			(pads allowed)
			(copperpour not_allowed)
			(footprints allowed)
		)
		(placement
			(enabled no)
			(sheetname "")
		)
		(fill
			(thermal_gap 0.5)
			(thermal_bridge_width 0.5)
			(island_removal_mode 0)
		)
		(polygon
			(pts
				(xy 116.11991 -141.575282) (xy 116.67871 -141.575282) (xy 116.67871 -143.378682) (xy 116.11991 -143.378682)
			)
		)
	)
	(zone
		(layer "In12.Cu")
		(hatch none 0.5)
		(connect_pads
			(clearance 0)
		)
		(min_thickness 0.25)
		(keepout
			(tracks not_allowed)
			(vias allowed)
			(pads allowed)
			(copperpour not_allowed)
			(footprints allowed)
		)
		(placement
			(enabled no)
			(sheetname "")
		)
		(fill
			(thermal_gap 0.5)
			(thermal_bridge_width 0.5)
			(island_removal_mode 0)
		)
		(polygon
			(pts
				(xy 145.02003 -0.120142) (xy 145.57883 -0.120142) (xy 145.57883 -1.923542) (xy 145.02003 -1.923542)
			)
		)
	)
	(zone
		(layer "In12.Cu")
		(hatch none 0.5)
		(connect_pads
			(clearance 0)
		)
		(min_thickness 0.25)
		(keepout
			(tracks not_allowed)
			(vias allowed)
			(pads allowed)
			(copperpour not_allowed)
			(footprints allowed)
		)
		(placement
			(enabled no)
			(sheetname "")
		)
		(fill
			(thermal_gap 0.5)
			(thermal_bridge_width 0.5)
			(island_removal_mode 0)
		)
		(polygon
			(pts
				(xy 290.470336 -14.321282) (xy 291.029136 -14.321282) (xy 291.029136 -16.124682) (xy 290.470336 -16.124682)
			)
		)
	)
	(zone
		(layer "In12.Cu")
		(hatch none 0.5)
		(connect_pads
			(clearance 0)
		)
		(min_thickness 0.25)
		(keepout
			(tracks not_allowed)
			(vias allowed)
			(pads allowed)
			(copperpour not_allowed)
			(footprints allowed)
		)
		(placement
			(enabled no)
			(sheetname "")
		)
		(fill
			(thermal_gap 0.5)
			(thermal_bridge_width 0.5)
			(island_removal_mode 0)
		)
		(polygon
			(pts
				(xy 139.07008 -4.720082) (xy 139.62888 -4.720082) (xy 139.62888 -6.523482) (xy 139.07008 -6.523482)
			)
		)
	)
	(zone
		(layer "In12.Cu")
		(hatch none 0.5)
		(connect_pads
			(clearance 0)
		)
		(min_thickness 0.25)
		(keepout
			(tracks not_allowed)
			(vias allowed)
			(pads allowed)
			(copperpour not_allowed)
			(footprints allowed)
		)
		(placement
			(enabled no)
			(sheetname "")
		)
		(fill
			(thermal_gap 0.5)
			(thermal_bridge_width 0.5)
			(island_removal_mode 0)
		)
		(polygon
			(pts
				(xy 275.170392 -19.322542) (xy 275.729192 -19.322542) (xy 275.729192 -21.125942) (xy 275.170392 -21.125942)
			)
		)
	)
	(zone
		(layer "In12.Cu")
		(hatch none 0.5)
		(connect_pads
			(clearance 0)
		)
		(min_thickness 0.25)
		(keepout
			(tracks not_allowed)
			(vias allowed)
			(pads allowed)
			(copperpour not_allowed)
			(footprints allowed)
		)
		(placement
			(enabled no)
			(sheetname "")
		)
		(fill
			(thermal_gap 0.5)
			(thermal_bridge_width 0.5)
			(island_removal_mode 0)
		)
		(polygon
			(pts
				(xy 277.720552 -14.321282) (xy 278.279352 -14.321282) (xy 278.279352 -16.124682) (xy 277.720552 -16.124682)
			)
		)
	)
	(zone
		(layer "In12.Cu")
		(hatch none 0.5)
		(connect_pads
			(clearance 0)
		)
		(min_thickness 0.25)
		(keepout
			(tracks not_allowed)
			(vias allowed)
			(pads allowed)
			(copperpour not_allowed)
			(footprints allowed)
		)
		(placement
			(enabled no)
			(sheetname "")
		)
		(fill
			(thermal_gap 0.5)
			(thermal_bridge_width 0.5)
			(island_removal_mode 0)
		)
		(polygon
			(pts
				(xy 240.320576 -9.721342) (xy 240.879376 -9.721342) (xy 240.879376 -11.524742) (xy 240.320576 -11.524742)
			)
		)
	)
	(zone
		(layer "In12.Cu")
		(hatch none 0.5)
		(connect_pads
			(clearance 0)
		)
		(min_thickness 0.25)
		(keepout
			(tracks not_allowed)
			(vias allowed)
			(pads allowed)
			(copperpour not_allowed)
			(footprints allowed)
		)
		(placement
			(enabled no)
			(sheetname "")
		)
		(fill
			(thermal_gap 0.5)
			(thermal_bridge_width 0.5)
			(island_removal_mode 0)
		)
		(polygon
			(pts
				(xy 107.620054 -151.176482) (xy 108.178854 -151.176482) (xy 108.178854 -152.979882) (xy 107.620054 -152.979882)
			)
		)
	)
	(zone
		(layer "In12.Cu")
		(hatch none 0.5)
		(connect_pads
			(clearance 0)
		)
		(min_thickness 0.25)
		(keepout
			(tracks not_allowed)
			(vias allowed)
			(pads allowed)
			(copperpour not_allowed)
			(footprints allowed)
		)
		(placement
			(enabled no)
			(sheetname "")
		)
		(fill
			(thermal_gap 0.5)
			(thermal_bridge_width 0.5)
			(island_removal_mode 0)
		)
		(polygon
			(pts
				(xy 17.58442 -102.20452) (xy 18.98142 -102.20452) (xy 18.98142 -102.71252) (xy 17.58442 -102.71252)
			)
		)
	)
	(zone
		(layer "In12.Cu")
		(hatch none 0.5)
		(connect_pads
			(clearance 0)
		)
		(min_thickness 0.25)
		(keepout
			(tracks not_allowed)
			(vias allowed)
			(pads allowed)
			(copperpour not_allowed)
			(footprints allowed)
		)
		(placement
			(enabled no)
			(sheetname "")
		)
		(fill
			(thermal_gap 0.5)
			(thermal_bridge_width 0.5)
			(island_removal_mode 0)
		)
		(polygon
			(pts
				(xy 66.820034 -151.176482) (xy 67.378834 -151.176482) (xy 67.378834 -152.979882) (xy 66.820034 -152.979882)
			)
		)
	)
	(zone
		(layer "In12.Cu")
		(hatch none 0.5)
		(connect_pads
			(clearance 0)
		)
		(min_thickness 0.25)
		(keepout
			(tracks not_allowed)
			(vias allowed)
			(pads allowed)
			(copperpour not_allowed)
			(footprints allowed)
		)
		(placement
			(enabled no)
			(sheetname "")
		)
		(fill
			(thermal_gap 0.5)
			(thermal_bridge_width 0.5)
			(island_removal_mode 0)
		)
		(polygon
			(pts
				(xy 248.820432 -14.321282) (xy 249.379232 -14.321282) (xy 249.379232 -16.124682) (xy 248.820432 -16.124682)
			)
		)
	)
	(zone
		(layer "In12.Cu")
		(hatch none 0.5)
		(connect_pads
			(clearance 0)
		)
		(min_thickness 0.25)
		(keepout
			(tracks not_allowed)
			(vias allowed)
			(pads allowed)
			(copperpour not_allowed)
			(footprints allowed)
		)
		(placement
			(enabled no)
			(sheetname "")
		)
		(fill
			(thermal_gap 0.5)
			(thermal_bridge_width 0.5)
			(island_removal_mode 0)
		)
		(polygon
			(pts
				(xy 283.670502 -14.321282) (xy 284.229302 -14.321282) (xy 284.229302 -16.124682) (xy 283.670502 -16.124682)
			)
		)
	)
	(zone
		(layer "In12.Cu")
		(hatch none 0.5)
		(connect_pads
			(clearance 0)
		)
		(min_thickness 0.25)
		(keepout
			(tracks not_allowed)
			(vias allowed)
			(pads allowed)
			(copperpour not_allowed)
			(footprints allowed)
		)
		(placement
			(enabled no)
			(sheetname "")
		)
		(fill
			(thermal_gap 0.5)
			(thermal_bridge_width 0.5)
			(island_removal_mode 0)
		)
		(polygon
			(pts
				(xy 210.570572 -146.576542) (xy 211.129372 -146.576542) (xy 211.129372 -148.379942) (xy 210.570572 -148.379942)
			)
		)
	)
	(zone
		(layer "In12.Cu")
		(hatch none 0.5)
		(connect_pads
			(clearance 0)
		)
		(min_thickness 0.25)
		(keepout
			(tracks not_allowed)
			(vias allowed)
			(pads allowed)
			(copperpour not_allowed)
			(footprints allowed)
		)
		(placement
			(enabled no)
			(sheetname "")
		)
		(fill
			(thermal_gap 0.5)
			(thermal_bridge_width 0.5)
			(island_removal_mode 0)
		)
		(polygon
			(pts
				(xy 314.27039 -127.374142) (xy 314.82919 -127.374142) (xy 314.82919 -129.177542) (xy 314.27039 -129.177542)
			)
		)
	)
	(zone
		(layer "In12.Cu")
		(hatch none 0.5)
		(connect_pads
			(clearance 0)
		)
		(min_thickness 0.25)
		(keepout
			(tracks not_allowed)
			(vias allowed)
			(pads allowed)
			(copperpour not_allowed)
			(footprints allowed)
		)
		(placement
			(enabled no)
			(sheetname "")
		)
		(fill
			(thermal_gap 0.5)
			(thermal_bridge_width 0.5)
			(island_removal_mode 0)
		)
		(polygon
			(pts
				(xy 343.379806 -59.225434) (xy 343.379806 -61.511434) (xy 342.871806 -61.511434) (xy 342.871806 -59.225434)
			)
		)
	)
	(zone
		(layer "In12.Cu")
		(hatch none 0.5)
		(connect_pads
			(clearance 0)
		)
		(min_thickness 0.25)
		(keepout
			(tracks not_allowed)
			(vias allowed)
			(pads allowed)
			(copperpour not_allowed)
			(footprints allowed)
		)
		(placement
			(enabled no)
			(sheetname "")
		)
		(fill
			(thermal_gap 0.5)
			(thermal_bridge_width 0.5)
			(island_removal_mode 0)
		)
		(polygon
			(pts
				(xy 133.970014 -19.322542) (xy 134.528814 -19.322542) (xy 134.528814 -21.125942) (xy 133.970014 -21.125942)
			)
		)
	)
	(zone
		(layer "In12.Cu")
		(hatch none 0.5)
		(connect_pads
			(clearance 0)
		)
		(min_thickness 0.25)
		(keepout
			(tracks not_allowed)
			(vias allowed)
			(pads allowed)
			(copperpour not_allowed)
			(footprints allowed)
		)
		(placement
			(enabled no)
			(sheetname "")
		)
		(fill
			(thermal_gap 0.5)
			(thermal_bridge_width 0.5)
			(island_removal_mode 0)
		)
		(polygon
			(pts
				(xy 227.570538 -23.922482) (xy 228.129338 -23.922482) (xy 228.129338 -25.725882) (xy 227.570538 -25.725882)
			)
		)
	)
	(zone
		(layer "In12.Cu")
		(hatch none 0.5)
		(connect_pads
			(clearance 0)
		)
		(min_thickness 0.25)
		(keepout
			(tracks not_allowed)
			(vias allowed)
			(pads allowed)
			(copperpour not_allowed)
			(footprints allowed)
		)
		(placement
			(enabled no)
			(sheetname "")
		)
		(fill
			(thermal_gap 0.5)
			(thermal_bridge_width 0.5)
			(island_removal_mode 0)
		)
		(polygon
			(pts
				(xy 362.969556 -121.646442) (xy 360.683556 -121.646442) (xy 360.683556 -121.138442) (xy 362.969556 -121.138442)
			)
		)
	)
	(zone
		(layer "In12.Cu")
		(hatch none 0.5)
		(connect_pads
			(clearance 0)
		)
		(min_thickness 0.25)
		(keepout
			(tracks not_allowed)
			(vias allowed)
			(pads allowed)
			(copperpour not_allowed)
			(footprints allowed)
		)
		(placement
			(enabled no)
			(sheetname "")
		)
		(fill
			(thermal_gap 0.5)
			(thermal_bridge_width 0.5)
			(island_removal_mode 0)
		)
		(polygon
			(pts
				(xy 73.620122 -127.374142) (xy 74.178922 -127.374142) (xy 74.178922 -129.177542) (xy 73.620122 -129.177542)
			)
		)
	)
	(zone
		(layer "In12.Cu")
		(hatch none 0.5)
		(connect_pads
			(clearance 0)
		)
		(min_thickness 0.25)
		(keepout
			(tracks not_allowed)
			(vias allowed)
			(pads allowed)
			(copperpour not_allowed)
			(footprints allowed)
		)
		(placement
			(enabled no)
			(sheetname "")
		)
		(fill
			(thermal_gap 0.5)
			(thermal_bridge_width 0.5)
			(island_removal_mode 0)
		)
		(polygon
			(pts
				(xy 121.219976 -127.374142) (xy 121.778776 -127.374142) (xy 121.778776 -129.177542) (xy 121.219976 -129.177542)
			)
		)
	)
	(zone
		(layer "In12.Cu")
		(hatch none 0.5)
		(connect_pads
			(clearance 0)
		)
		(min_thickness 0.25)
		(keepout
			(tracks not_allowed)
			(vias allowed)
			(pads allowed)
			(copperpour not_allowed)
			(footprints allowed)
		)
		(placement
			(enabled no)
			(sheetname "")
		)
		(fill
			(thermal_gap 0.5)
			(thermal_bridge_width 0.5)
			(island_removal_mode 0)
		)
		(polygon
			(pts
				(xy 54.069996 -127.374142) (xy 54.628796 -127.374142) (xy 54.628796 -129.177542) (xy 54.069996 -129.177542)
			)
		)
	)
	(zone
		(layer "In12.Cu")
		(hatch none 0.5)
		(connect_pads
			(clearance 0)
		)
		(min_thickness 0.25)
		(keepout
			(tracks not_allowed)
			(vias allowed)
			(pads allowed)
			(copperpour not_allowed)
			(footprints allowed)
		)
		(placement
			(enabled no)
			(sheetname "")
		)
		(fill
			(thermal_gap 0.5)
			(thermal_bridge_width 0.5)
			(island_removal_mode 0)
		)
		(polygon
			(pts
				(xy 290.470336 -141.575282) (xy 291.029136 -141.575282) (xy 291.029136 -143.378682) (xy 290.470336 -143.378682)
			)
		)
	)
	(zone
		(layer "In12.Cu")
		(hatch none 0.5)
		(connect_pads
			(clearance 0)
		)
		(min_thickness 0.25)
		(keepout
			(tracks not_allowed)
			(vias allowed)
			(pads allowed)
			(copperpour not_allowed)
			(footprints allowed)
		)
		(placement
			(enabled no)
			(sheetname "")
		)
		(fill
			(thermal_gap 0.5)
			(thermal_bridge_width 0.5)
			(island_removal_mode 0)
		)
		(polygon
			(pts
				(xy 118.67007 -151.176482) (xy 119.22887 -151.176482) (xy 119.22887 -152.979882) (xy 118.67007 -152.979882)
			)
		)
	)
	(zone
		(layer "In12.Cu")
		(hatch none 0.5)
		(connect_pads
			(clearance 0)
		)
		(min_thickness 0.25)
		(keepout
			(tracks not_allowed)
			(vias allowed)
			(pads allowed)
			(copperpour not_allowed)
			(footprints allowed)
		)
		(placement
			(enabled no)
			(sheetname "")
		)
		(fill
			(thermal_gap 0.5)
			(thermal_bridge_width 0.5)
			(island_removal_mode 0)
		)
		(polygon
			(pts
				(xy 42.170096 -23.922482) (xy 42.728896 -23.922482) (xy 42.728896 -25.725882) (xy 42.170096 -25.725882)
			)
		)
	)
	(zone
		(net "PVDDQ_GHJ")
		(layer "In12.Cu")
		(hatch none 0.5)
		(connect_pads
			(clearance 0.5)
		)
		(min_thickness 0.25)
		(fill yes
			(thermal_gap 0.5)
			(thermal_bridge_width 0.5)
			(island_removal_mode 0)
		)
		(polygon
			(pts
				(xy 78.895194 -21.1455) (xy 78.7781 -21.262594) (xy 78.7781 -22.430994) (xy 77.8891 -23.319994)
				(xy 77.8891 -23.695406) (xy 78.056994 -23.8633) (xy 93.545406 -23.8633) (xy 93.6879 -23.720806)
				(xy 93.6879 -21.186394) (xy 93.647006 -21.1455)
			)
		)
	)
	(zone
		(layer "In12.Cu")
		(hatch none 0.5)
		(connect_pads
			(clearance 0)
		)
		(min_thickness 0.25)
		(keepout
			(tracks not_allowed)
			(vias allowed)
			(pads allowed)
			(copperpour not_allowed)
			(footprints allowed)
		)
		(placement
			(enabled no)
			(sheetname "")
		)
		(fill
			(thermal_gap 0.5)
			(thermal_bridge_width 0.5)
			(island_removal_mode 0)
		)
		(polygon
			(pts
				(xy 150.96998 -127.374142) (xy 151.52878 -127.374142) (xy 151.52878 -129.177542) (xy 150.96998 -129.177542)
			)
		)
	)
	(zone
		(layer "In12.Cu")
		(hatch none 0.5)
		(connect_pads
			(clearance 0)
		)
		(min_thickness 0.25)
		(keepout
			(tracks not_allowed)
			(vias allowed)
			(pads allowed)
			(copperpour not_allowed)
			(footprints allowed)
		)
		(placement
			(enabled no)
			(sheetname "")
		)
		(fill
			(thermal_gap 0.5)
			(thermal_bridge_width 0.5)
			(island_removal_mode 0)
		)
		(polygon
			(pts
				(xy 236.920532 -151.176482) (xy 237.479332 -151.176482) (xy 237.479332 -152.979882) (xy 236.920532 -152.979882)
			)
		)
	)
	(zone
		(layer "In12.Cu")
		(hatch none 0.5)
		(connect_pads
			(clearance 0)
		)
		(min_thickness 0.25)
		(keepout
			(tracks not_allowed)
			(vias allowed)
			(pads allowed)
			(copperpour not_allowed)
			(footprints allowed)
		)
		(placement
			(enabled no)
			(sheetname "")
		)
		(fill
			(thermal_gap 0.5)
			(thermal_bridge_width 0.5)
			(island_removal_mode 0)
		)
		(polygon
			(pts
				(xy 210.570572 -136.975342) (xy 211.129372 -136.975342) (xy 211.129372 -138.778742) (xy 210.570572 -138.778742)
			)
		)
	)
	(zone
		(layer "In12.Cu")
		(hatch none 0.5)
		(connect_pads
			(clearance 0)
		)
		(min_thickness 0.25)
		(keepout
			(tracks not_allowed)
			(vias allowed)
			(pads allowed)
			(copperpour not_allowed)
			(footprints allowed)
		)
		(placement
			(enabled no)
			(sheetname "")
		)
		(fill
			(thermal_gap 0.5)
			(thermal_bridge_width 0.5)
			(island_removal_mode 0)
		)
		(polygon
			(pts
				(xy 111.020098 -19.322542) (xy 111.578898 -19.322542) (xy 111.578898 -21.125942) (xy 111.020098 -21.125942)
			)
		)
	)
	(zone
		(layer "In12.Cu")
		(hatch none 0.5)
		(connect_pads
			(clearance 0)
		)
		(min_thickness 0.25)
		(keepout
			(tracks not_allowed)
			(vias allowed)
			(pads allowed)
			(copperpour not_allowed)
			(footprints allowed)
		)
		(placement
			(enabled no)
			(sheetname "")
		)
		(fill
			(thermal_gap 0.5)
			(thermal_bridge_width 0.5)
			(island_removal_mode 0)
		)
		(polygon
			(pts
				(xy 102.519988 -131.974082) (xy 103.078788 -131.974082) (xy 103.078788 -133.777482) (xy 102.519988 -133.777482)
			)
		)
	)
	(zone
		(layer "In12.Cu")
		(hatch none 0.5)
		(connect_pads
			(clearance 0)
		)
		(min_thickness 0.25)
		(keepout
			(tracks not_allowed)
			(vias allowed)
			(pads allowed)
			(copperpour not_allowed)
			(footprints allowed)
		)
		(placement
			(enabled no)
			(sheetname "")
		)
		(fill
			(thermal_gap 0.5)
			(thermal_bridge_width 0.5)
			(island_removal_mode 0)
		)
		(polygon
			(pts
				(xy 240.320576 -0.120142) (xy 240.879376 -0.120142) (xy 240.879376 -1.923542) (xy 240.320576 -1.923542)
			)
		)
	)
	(zone
		(layer "In12.Cu")
		(hatch none 0.5)
		(connect_pads
			(clearance 0)
		)
		(min_thickness 0.25)
		(keepout
			(tracks not_allowed)
			(vias allowed)
			(pads allowed)
			(copperpour not_allowed)
			(footprints allowed)
		)
		(placement
			(enabled no)
			(sheetname "")
		)
		(fill
			(thermal_gap 0.5)
			(thermal_bridge_width 0.5)
			(island_removal_mode 0)
		)
		(polygon
			(pts
				(xy 117.819932 -23.922482) (xy 118.378732 -23.922482) (xy 118.378732 -25.725882) (xy 117.819932 -25.725882)
			)
		)
	)
	(zone
		(layer "In12.Cu")
		(hatch none 0.5)
		(connect_pads
			(clearance 0)
		)
		(min_thickness 0.25)
		(keepout
			(tracks not_allowed)
			(vias allowed)
			(pads allowed)
			(copperpour not_allowed)
			(footprints allowed)
		)
		(placement
			(enabled no)
			(sheetname "")
		)
		(fill
			(thermal_gap 0.5)
			(thermal_bridge_width 0.5)
			(island_removal_mode 0)
		)
		(polygon
			(pts
				(xy 230.120444 -131.974082) (xy 230.679244 -131.974082) (xy 230.679244 -133.777482) (xy 230.120444 -133.777482)
			)
		)
	)
	(zone
		(layer "In12.Cu")
		(hatch none 0.5)
		(connect_pads
			(clearance 0)
		)
		(min_thickness 0.25)
		(keepout
			(tracks not_allowed)
			(vias allowed)
			(pads allowed)
			(copperpour not_allowed)
			(footprints allowed)
		)
		(placement
			(enabled no)
			(sheetname "")
		)
		(fill
			(thermal_gap 0.5)
			(thermal_bridge_width 0.5)
			(island_removal_mode 0)
		)
		(polygon
			(pts
				(xy 60.870084 -14.321282) (xy 61.428884 -14.321282) (xy 61.428884 -16.124682) (xy 60.870084 -16.124682)
			)
		)
	)
	(zone
		(layer "In12.Cu")
		(hatch none 0.5)
		(connect_pads
			(clearance 0)
		)
		(min_thickness 0.25)
		(keepout
			(tracks not_allowed)
			(vias allowed)
			(pads allowed)
			(copperpour not_allowed)
			(footprints allowed)
		)
		(placement
			(enabled no)
			(sheetname "")
		)
		(fill
			(thermal_gap 0.5)
			(thermal_bridge_width 0.5)
			(island_removal_mode 0)
		)
		(polygon
			(pts
				(xy 273.47037 -9.721342) (xy 274.02917 -9.721342) (xy 274.02917 -11.524742) (xy 273.47037 -11.524742)
			)
		)
	)
	(zone
		(layer "In12.Cu")
		(hatch none 0.5)
		(connect_pads
			(clearance 0)
		)
		(min_thickness 0.25)
		(keepout
			(tracks not_allowed)
			(vias allowed)
			(pads allowed)
			(copperpour not_allowed)
			(footprints allowed)
		)
		(placement
			(enabled no)
			(sheetname "")
		)
		(fill
			(thermal_gap 0.5)
			(thermal_bridge_width 0.5)
			(island_removal_mode 0)
		)
		(polygon
			(pts
				(xy 61.719968 -0.120142) (xy 62.278768 -0.120142) (xy 62.278768 -1.923542) (xy 61.719968 -1.923542)
			)
		)
	)
	(zone
		(layer "In12.Cu")
		(hatch none 0.5)
		(connect_pads
			(clearance 0)
		)
		(min_thickness 0.25)
		(keepout
			(tracks not_allowed)
			(vias allowed)
			(pads allowed)
			(copperpour not_allowed)
			(footprints allowed)
		)
		(placement
			(enabled no)
			(sheetname "")
		)
		(fill
			(thermal_gap 0.5)
			(thermal_bridge_width 0.5)
			(island_removal_mode 0)
		)
		(polygon
			(pts
				(xy 275.170392 -0.120142) (xy 275.729192 -0.120142) (xy 275.729192 -1.923542) (xy 275.170392 -1.923542)
			)
		)
	)
	(zone
		(layer "In12.Cu")
		(hatch none 0.5)
		(connect_pads
			(clearance 0)
		)
		(min_thickness 0.25)
		(keepout
			(tracks not_allowed)
			(vias allowed)
			(pads allowed)
			(copperpour not_allowed)
			(footprints allowed)
		)
		(placement
			(enabled no)
			(sheetname "")
		)
		(fill
			(thermal_gap 0.5)
			(thermal_bridge_width 0.5)
			(island_removal_mode 0)
		)
		(polygon
			(pts
				(xy 100.819966 -4.720082) (xy 101.378766 -4.720082) (xy 101.378766 -6.523482) (xy 100.819966 -6.523482)
			)
		)
	)
	(zone
		(layer "In12.Cu")
		(hatch none 0.5)
		(connect_pads
			(clearance 0)
		)
		(min_thickness 0.25)
		(keepout
			(tracks not_allowed)
			(vias allowed)
			(pads allowed)
			(copperpour not_allowed)
			(footprints allowed)
		)
		(placement
			(enabled no)
			(sheetname "")
		)
		(fill
			(thermal_gap 0.5)
			(thermal_bridge_width 0.5)
			(island_removal_mode 0)
		)
		(polygon
			(pts
				(xy 298.970446 -146.576542) (xy 299.529246 -146.576542) (xy 299.529246 -148.379942) (xy 298.970446 -148.379942)
			)
		)
	)
	(zone
		(layer "In12.Cu")
		(hatch none 0.5)
		(connect_pads
			(clearance 0)
		)
		(min_thickness 0.25)
		(keepout
			(tracks not_allowed)
			(vias allowed)
			(pads allowed)
			(copperpour not_allowed)
			(footprints allowed)
		)
		(placement
			(enabled no)
			(sheetname "")
		)
		(fill
			(thermal_gap 0.5)
			(thermal_bridge_width 0.5)
			(island_removal_mode 0)
		)
		(polygon
			(pts
				(xy 209.720434 -127.374142) (xy 210.279234 -127.374142) (xy 210.279234 -129.177542) (xy 209.720434 -129.177542)
			)
		)
	)
	(zone
		(layer "In12.Cu")
		(hatch none 0.5)
		(connect_pads
			(clearance 0)
		)
		(min_thickness 0.25)
		(keepout
			(tracks not_allowed)
			(vias allowed)
			(pads allowed)
			(copperpour not_allowed)
			(footprints allowed)
		)
		(placement
			(enabled no)
			(sheetname "")
		)
		(fill
			(thermal_gap 0.5)
			(thermal_bridge_width 0.5)
			(island_removal_mode 0)
		)
		(polygon
			(pts
				(xy 299.82033 -131.974082) (xy 300.37913 -131.974082) (xy 300.37913 -133.777482) (xy 299.82033 -133.777482)
			)
		)
	)
	(zone
		(layer "In12.Cu")
		(hatch none 0.5)
		(connect_pads
			(clearance 0)
		)
		(min_thickness 0.25)
		(keepout
			(tracks not_allowed)
			(vias allowed)
			(pads allowed)
			(copperpour not_allowed)
			(footprints allowed)
		)
		(placement
			(enabled no)
			(sheetname "")
		)
		(fill
			(thermal_gap 0.5)
			(thermal_bridge_width 0.5)
			(island_removal_mode 0)
		)
		(polygon
			(pts
				(xy 145.869914 -4.720082) (xy 146.428714 -4.720082) (xy 146.428714 -6.523482) (xy 145.869914 -6.523482)
			)
		)
	)
	(zone
		(layer "In12.Cu")
		(hatch none 0.5)
		(connect_pads
			(clearance 0)
		)
		(min_thickness 0.25)
		(keepout
			(tracks not_allowed)
			(vias allowed)
			(pads allowed)
			(copperpour not_allowed)
			(footprints allowed)
		)
		(placement
			(enabled no)
			(sheetname "")
		)
		(fill
			(thermal_gap 0.5)
			(thermal_bridge_width 0.5)
			(island_removal_mode 0)
		)
		(polygon
			(pts
				(xy 100.819966 -131.974082) (xy 101.378766 -131.974082) (xy 101.378766 -133.777482) (xy 100.819966 -133.777482)
			)
		)
	)
	(zone
		(layer "In12.Cu")
		(hatch none 0.5)
		(connect_pads
			(clearance 0)
		)
		(min_thickness 0.25)
		(keepout
			(tracks not_allowed)
			(vias allowed)
			(pads allowed)
			(copperpour not_allowed)
			(footprints allowed)
		)
		(placement
			(enabled no)
			(sheetname "")
		)
		(fill
			(thermal_gap 0.5)
			(thermal_bridge_width 0.5)
			(island_removal_mode 0)
		)
		(polygon
			(pts
				(xy 46.420024 -23.922482) (xy 46.978824 -23.922482) (xy 46.978824 -25.725882) (xy 46.420024 -25.725882)
			)
		)
	)
	(zone
		(net "P12V_PSU")
		(layer "In12.Cu")
		(hatch none 0.5)
		(connect_pads
			(clearance 0.5)
		)
		(min_thickness 0.25)
		(fill yes
			(thermal_gap 0.5)
			(thermal_bridge_width 0.5)
			(island_removal_mode 0)
		)
		(polygon
			(pts
				(xy 3.361944 -50.038) (xy 3.0734 -50.326544) (xy 3.0734 -59.114944) (xy 1.8034 -60.384944) (xy 1.8034 -66.742056)
				(xy 3.5052 -68.443856) (xy 3.5052 -85.563456) (xy 4.123944 -86.1822) (xy 9.844278 -86.1822) (xy 10.092436 -85.934042)
				(xy 10.092436 -50.67173) (xy 9.458706 -50.038)
			)
		)
	)
	(zone
		(layer "In12.Cu")
		(hatch none 0.5)
		(connect_pads
			(clearance 0)
		)
		(min_thickness 0.25)
		(keepout
			(tracks not_allowed)
			(vias allowed)
			(pads allowed)
			(copperpour not_allowed)
			(footprints allowed)
		)
		(placement
			(enabled no)
			(sheetname "")
		)
		(fill
			(thermal_gap 0.5)
			(thermal_bridge_width 0.5)
			(island_removal_mode 0)
		)
		(polygon
			(pts
				(xy 293.020496 -23.922482) (xy 293.579296 -23.922482) (xy 293.579296 -25.725882) (xy 293.020496 -25.725882)
			)
		)
	)
	(zone
		(net "PVDDQ_ABC")
		(layer "In12.Cu")
		(hatch none 0.5)
		(connect_pads
			(clearance 0.5)
		)
		(min_thickness 0.25)
		(fill yes
			(thermal_gap 0.5)
			(thermal_bridge_width 0.5)
			(island_removal_mode 0)
		)
		(polygon
			(pts
				(xy 243.918994 -21.1455) (xy 243.8019 -21.262594) (xy 243.8019 -22.380194) (xy 242.8875 -23.294594)
				(xy 242.8875 -23.670006) (xy 243.131594 -23.9141) (xy 258.493006 -23.9141) (xy 258.7117 -23.695406)
				(xy 258.7117 -21.440394) (xy 258.416806 -21.1455)
			)
		)
	)
	(zone
		(layer "In12.Cu")
		(hatch none 0.5)
		(connect_pads
			(clearance 0)
		)
		(min_thickness 0.25)
		(keepout
			(tracks not_allowed)
			(vias allowed)
			(pads allowed)
			(copperpour not_allowed)
			(footprints allowed)
		)
		(placement
			(enabled no)
			(sheetname "")
		)
		(fill
			(thermal_gap 0.5)
			(thermal_bridge_width 0.5)
			(island_removal_mode 0)
		)
		(polygon
			(pts
				(xy 222.470472 -131.974082) (xy 223.029272 -131.974082) (xy 223.029272 -133.777482) (xy 222.470472 -133.777482)
			)
		)
	)
	(zone
		(layer "In12.Cu")
		(hatch none 0.5)
		(connect_pads
			(clearance 0)
		)
		(min_thickness 0.25)
		(keepout
			(tracks not_allowed)
			(vias allowed)
			(pads allowed)
			(copperpour not_allowed)
			(footprints allowed)
		)
		(placement
			(enabled no)
			(sheetname "")
		)
		(fill
			(thermal_gap 0.5)
			(thermal_bridge_width 0.5)
			(island_removal_mode 0)
		)
		(polygon
			(pts
				(xy 227.570538 -141.575282) (xy 228.129338 -141.575282) (xy 228.129338 -143.378682) (xy 227.570538 -143.378682)
			)
		)
	)
	(zone
		(layer "In12.Cu")
		(hatch none 0.5)
		(connect_pads
			(clearance 0)
		)
		(min_thickness 0.25)
		(keepout
			(tracks not_allowed)
			(vias allowed)
			(pads allowed)
			(copperpour not_allowed)
			(footprints allowed)
		)
		(placement
			(enabled no)
			(sheetname "")
		)
		(fill
			(thermal_gap 0.5)
			(thermal_bridge_width 0.5)
			(island_removal_mode 0)
		)
		(polygon
			(pts
				(xy 306.620418 -146.576542) (xy 307.179218 -146.576542) (xy 307.179218 -148.379942) (xy 306.620418 -148.379942)
			)
		)
	)
	(zone
		(layer "In12.Cu")
		(hatch none 0.5)
		(connect_pads
			(clearance 0)
		)
		(min_thickness 0.25)
		(keepout
			(tracks not_allowed)
			(vias allowed)
			(pads allowed)
			(copperpour not_allowed)
			(footprints allowed)
		)
		(placement
			(enabled no)
			(sheetname "")
		)
		(fill
			(thermal_gap 0.5)
			(thermal_bridge_width 0.5)
			(island_removal_mode 0)
		)
		(polygon
			(pts
				(xy 60.870084 -23.922482) (xy 61.428884 -23.922482) (xy 61.428884 -25.725882) (xy 60.870084 -25.725882)
			)
		)
	)
	(zone
		(layer "In12.Cu")
		(hatch none 0.5)
		(connect_pads
			(clearance 0)
		)
		(min_thickness 0.25)
		(keepout
			(tracks not_allowed)
			(vias allowed)
			(pads allowed)
			(copperpour not_allowed)
			(footprints allowed)
		)
		(placement
			(enabled no)
			(sheetname "")
		)
		(fill
			(thermal_gap 0.5)
			(thermal_bridge_width 0.5)
			(island_removal_mode 0)
		)
		(polygon
			(pts
				(xy 147.569936 -9.721342) (xy 148.128736 -9.721342) (xy 148.128736 -11.524742) (xy 147.569936 -11.524742)
			)
		)
	)
	(zone
		(layer "In12.Cu")
		(hatch none 0.5)
		(connect_pads
			(clearance 0)
		)
		(min_thickness 0.25)
		(keepout
			(tracks not_allowed)
			(vias allowed)
			(pads allowed)
			(copperpour not_allowed)
			(footprints allowed)
		)
		(placement
			(enabled no)
			(sheetname "")
		)
		(fill
			(thermal_gap 0.5)
			(thermal_bridge_width 0.5)
			(island_removal_mode 0)
		)
		(polygon
			(pts
				(xy 116.970048 -0.120142) (xy 117.528848 -0.120142) (xy 117.528848 -1.923542) (xy 116.970048 -1.923542)
			)
		)
	)
	(zone
		(layer "In12.Cu")
		(hatch none 0.5)
		(connect_pads
			(clearance 0)
		)
		(min_thickness 0.25)
		(keepout
			(tracks not_allowed)
			(vias allowed)
			(pads allowed)
			(copperpour not_allowed)
			(footprints allowed)
		)
		(placement
			(enabled no)
			(sheetname "")
		)
		(fill
			(thermal_gap 0.5)
			(thermal_bridge_width 0.5)
			(island_removal_mode 0)
		)
		(polygon
			(pts
				(xy 54.920134 -146.576542) (xy 55.478934 -146.576542) (xy 55.478934 -148.379942) (xy 54.920134 -148.379942)
			)
		)
	)
	(zone
		(layer "In12.Cu")
		(hatch none 0.5)
		(connect_pads
			(clearance 0)
		)
		(min_thickness 0.25)
		(keepout
			(tracks not_allowed)
			(vias allowed)
			(pads allowed)
			(copperpour not_allowed)
			(footprints allowed)
		)
		(placement
			(enabled no)
			(sheetname "")
		)
		(fill
			(thermal_gap 0.5)
			(thermal_bridge_width 0.5)
			(island_removal_mode 0)
		)
		(polygon
			(pts
				(xy 268.370558 -151.176482) (xy 268.929358 -151.176482) (xy 268.929358 -152.979882) (xy 268.370558 -152.979882)
			)
		)
	)
)
